(kicad_pcb (version 20221018) (generator pcbnew)

  (general
    (thickness 1.562)
  )

  (paper "A4")
  (title_block
    (title "Thunderbolt PCIe Adaper")
    (date "2024-07-09")
    (rev "1.0.3")
    (comment 1 "www.antmicro.com")
    (comment 2 "Antmicro Ltd.")
  )

  (layers
    (0 "F.Cu" signal)
    (1 "In1.Cu" signal)
    (2 "In2.Cu" signal)
    (3 "In3.Cu" signal)
    (4 "In4.Cu" signal)
    (31 "B.Cu" signal)
    (32 "B.Adhes" user "B.Adhesive")
    (33 "F.Adhes" user "F.Adhesive")
    (34 "B.Paste" user)
    (35 "F.Paste" user)
    (36 "B.SilkS" user "B.Silkscreen")
    (37 "F.SilkS" user "F.Silkscreen")
    (38 "B.Mask" user)
    (39 "F.Mask" user)
    (40 "Dwgs.User" user "User.Drawings")
    (41 "Cmts.User" user "User.Comments")
    (42 "Eco1.User" user "User.Eco1")
    (43 "Eco2.User" user "User.Eco2")
    (44 "Edge.Cuts" user)
    (45 "Margin" user)
    (46 "B.CrtYd" user "B.Courtyard")
    (47 "F.CrtYd" user "F.Courtyard")
    (48 "B.Fab" user)
    (49 "F.Fab" user)
  )

  (setup
    (stackup
      (layer "F.SilkS" (type "Top Silk Screen"))
      (layer "F.Paste" (type "Top Solder Paste"))
      (layer "F.Mask" (type "Top Solder Mask") (color "Black") (thickness 0.01))
      (layer "F.Cu" (type "copper") (thickness 0.035))
      (layer "dielectric 1" (type "prepreg") (thickness 0.12) (material "PR2116") (epsilon_r 4.12) (loss_tangent 0.023))
      (layer "In1.Cu" (type "copper") (thickness 0.018))
      (layer "dielectric 2" (type "core") (thickness 0.51) (material "FR4-Improved") (epsilon_r 4.125) (loss_tangent 0.022))
      (layer "In2.Cu" (type "copper") (thickness 0.018))
      (layer "dielectric 3" (type "prepreg") (thickness 0.14) (material "PR1080") (epsilon_r 4.125) (loss_tangent 0.025))
      (layer "In3.Cu" (type "copper") (thickness 0.018))
      (layer "dielectric 4" (type "core") (thickness 0.51) (material "FR4-Improved") (epsilon_r 4.125) (loss_tangent 0.022))
      (layer "In4.Cu" (type "copper") (thickness 0.018))
      (layer "dielectric 5" (type "prepreg") (thickness 0.12) (material "PR2116") (epsilon_r 4.12) (loss_tangent 0.023))
      (layer "B.Cu" (type "copper") (thickness 0.035))
      (layer "B.Mask" (type "Bottom Solder Mask") (color "Black") (thickness 0.01))
      (layer "B.Paste" (type "Bottom Solder Paste"))
      (layer "B.SilkS" (type "Bottom Silk Screen"))
      (copper_finish "None")
      (dielectric_constraints yes)
    )
    (pad_to_mask_clearance 0)
    (pcbplotparams
      (layerselection 0x00010fc_ffffffff)
      (plot_on_all_layers_selection 0x0000000_00000000)
      (disableapertmacros false)
      (usegerberextensions false)
      (usegerberattributes true)
      (usegerberadvancedattributes true)
      (creategerberjobfile true)
      (dashed_line_dash_ratio 12.000000)
      (dashed_line_gap_ratio 3.000000)
      (svgprecision 6)
      (plotframeref false)
      (viasonmask false)
      (mode 1)
      (useauxorigin false)
      (hpglpennumber 1)
      (hpglpenspeed 20)
      (hpglpendiameter 15.000000)
      (dxfpolygonmode true)
      (dxfimperialunits true)
      (dxfusepcbnewfont true)
      (psnegative false)
      (psa4output false)
      (plotreference true)
      (plotvalue true)
      (plotinvisibletext false)
      (sketchpadsonfab false)
      (subtractmaskfromsilk false)
      (outputformat 1)
      (mirror false)
      (drillshape 1)
      (scaleselection 1)
      (outputdirectory "")
    )
  )

  (net 0 "")
  (net 1 "GND")
  (net 2 "3V3_SYS")
  (net 3 "5V0_USB")
  (net 4 "Net-(C26-Pad2)")
  (net 5 "Net-(U1-VREF)")
  (net 6 "/Power/SMPS_LDO")
  (net 7 "Net-(C30-Pad2)")
  (net 8 "12V0_PCIE")
  (net 9 "/Power/TPS_3V3")
  (net 10 "CC2")
  (net 11 "CC1")
  (net 12 "TB_TX0_P")
  (net 13 "/TB Controller/PA_TX0_P")
  (net 14 "TB_TX1_P")
  (net 15 "/TB Controller/PA_TX1_P")
  (net 16 "AUX_P")
  (net 17 "TB_TX0_N")
  (net 18 "/TB Controller/PA_TX0_N")
  (net 19 "PP_HV")
  (net 20 "PP_5V0")
  (net 21 "TB_TX1_N")
  (net 22 "/TB Controller/PA_TX1_N")
  (net 23 "AUX_N")
  (net 24 "PCIE_TX0_N")
  (net 25 "PCIE_TX1_N")
  (net 26 "PCIE_TX2_N")
  (net 27 "PCIE_TX3_N")
  (net 28 "PCIE_TX0_P")
  (net 29 "PCIE_TX1_P")
  (net 30 "PCIE_TX2_P")
  (net 31 "PCIE_TX3_P")
  (net 32 "VBUS")
  (net 33 "USB_T_P")
  (net 34 "USB_T_N")
  (net 35 "SBU1")
  (net 36 "TB_RX1_N")
  (net 37 "TB_RX1_P")
  (net 38 "USB_B_P")
  (net 39 "USB_B_N")
  (net 40 "SBU2")
  (net 41 "TB_RX0_N")
  (net 42 "TB_RX0_P")
  (net 43 "PCIE_PWRGD")
  (net 44 "PCIE_CLK_CON_P")
  (net 45 "PCIE_CLK_CON_N")
  (net 46 "PCIE_RX0_P")
  (net 47 "PCIE_RX0_N")
  (net 48 "PCIE_RX1_P")
  (net 49 "PCIE_RX1_N")
  (net 50 "PCIE_RX2_P")
  (net 51 "PCIE_RX2_N")
  (net 52 "PCIE_RX3_P")
  (net 53 "PCIE_RX3_N")
  (net 54 "PCIE_WAKE")
  (net 55 "Net-(L3-Pad1)")
  (net 56 "I2C1_IRQ")
  (net 57 "I2C1_SCL")
  (net 58 "HPD")
  (net 59 "I2C1_SDA")
  (net 60 "12V0_DCDC")
  (net 61 "12V0_MOLEX")
  (net 62 "RESET_N")
  (net 63 "SPI_MISO")
  (net 64 "/TB Controller/FLASH_WP")
  (net 65 "SPI_CS")
  (net 66 "LSX_P2R")
  (net 67 "LSX_R2P")
  (net 68 "SPI_SCLK")
  (net 69 "SPI_MOSI")
  (net 70 "USB_RP_N")
  (net 71 "USB_RP_P")
  (net 72 "/TB Controller/PCIE_CLK_JHL_P")
  (net 73 "/TB Controller/PCIE_CLK_JHL_N")
  (net 74 "Net-(C10-Pad2)")
  (net 75 "Net-(C32-Pad2)")
  (net 76 "/TB Controller/TX0_N")
  (net 77 "/TB Controller/TX1_N")
  (net 78 "/TB Controller/TX2_N")
  (net 79 "/TB Controller/TX3_N")
  (net 80 "/TB Controller/TX0_P")
  (net 81 "/TB Controller/TX1_P")
  (net 82 "/TB Controller/TX2_P")
  (net 83 "/TB Controller/TX3_P")
  (net 84 "/Power/I_SENSE_P")
  (net 85 "/Power/I_SENSE_N")
  (net 86 "/TB Controller/PA_AUX_P")
  (net 87 "/TB Controller/PA_AUX_N")
  (net 88 "/Power/DCDC_EN")
  (net 89 "/TB Controller/FLASH_HOLD")
  (net 90 "Net-(U2-VIN)")
  (net 91 "Net-(U1-INTVCC)")
  (net 92 "Net-(U1-SS)")
  (net 93 "Net-(U1-BST1)")
  (net 94 "Net-(U2-BST)")
  (net 95 "Net-(U2-SW)")
  (net 96 "Net-(U1-BST2)")
  (net 97 "Net-(U1-EXTVCC)")
  (net 98 "Net-(U3-SS)")
  (net 99 "Net-(U2-FB)")
  (net 100 "Net-(D2-A)")
  (net 101 "Net-(U3-VOUT_3V3)")
  (net 102 "Net-(U3-LDO_1V8A)")
  (net 103 "Net-(U3-LDO_1V8D)")
  (net 104 "Net-(U3-LDO_BMC)")
  (net 105 "Net-(C51-Pad2)")
  (net 106 "Net-(C53-Pad2)")
  (net 107 "Net-(C54-Pad2)")
  (net 108 "Net-(C56-Pad2)")
  (net 109 "Net-(U4A-VCC3P3_ANA_PCIE)")
  (net 110 "Net-(U4A-VCC3P3_ANA_USB2)")
  (net 111 "Net-(U4A-VCC3P3_LC)")
  (net 112 "Net-(U4A-VCC0P9_SVR_SENSE)")
  (net 113 "Net-(U4A-VCC0P9_LVR_SENSE)")
  (net 114 "Net-(U4A-VCC3P3_S0)")
  (net 115 "Net-(U6-XOUT)")
  (net 116 "Net-(U6-XIN{slash}CLKIN)")
  (net 117 "Net-(U4D-XTAL_25_IN)")
  (net 118 "Net-(U4D-XTAL_25_OUT)")
  (net 119 "Net-(D1-C)")
  (net 120 "Net-(D2-C)")
  (net 121 "Net-(D3-C)")
  (net 122 "Net-(D4-C)")
  (net 123 "Net-(D5-C)")
  (net 124 "unconnected-(J2-PRSNT#1-PadA1)")
  (net 125 "unconnected-(J2-JTAG2-PadA5)")
  (net 126 "unconnected-(J2-JTAG3-PadA6)")
  (net 127 "unconnected-(J2-JTAG4-PadA7)")
  (net 128 "unconnected-(J2-JTAG5-PadA8)")
  (net 129 "unconnected-(J2-RSVD-PadA19)")
  (net 130 "unconnected-(J2-RSVD-PadA32)")
  (net 131 "unconnected-(J2-SMCLK-PadB5)")
  (net 132 "unconnected-(J2-SMDAT-PadB6)")
  (net 133 "unconnected-(J2-JTAG1-PadB9)")
  (net 134 "unconnected-(J2-RSVD-PadB12)")
  (net 135 "unconnected-(J2-PRSNT#2-PadB17)")
  (net 136 "unconnected-(J2-RSVD-PadB30)")
  (net 137 "unconnected-(J2-PRSNT#2-PadB31)")
  (net 138 "Net-(Q1-B)")
  (net 139 "Net-(Q1-C)")
  (net 140 "Net-(Q2-B)")
  (net 141 "Net-(Q3-REF)")
  (net 142 "Net-(Q3-BIAS)")
  (net 143 "Net-(Q3-S)")
  (net 144 "Net-(Q4-REF)")
  (net 145 "Net-(Q4-BIAS)")
  (net 146 "Net-(Q4-S)")
  (net 147 "Net-(U1-CTRL)")
  (net 148 "Net-(U1-LOADEN)")
  (net 149 "Net-(U3-I2C_SDA2)")
  (net 150 "Net-(U3-I2C_SCL2)")
  (net 151 "Net-(U3-I2C_IRQ2Z)")
  (net 152 "Net-(U3-GPIO0(HD3_AMSEL))")
  (net 153 "Net-(U3-GPIO4(HPD_TXRX))")
  (net 154 "Net-(U3-GPIO6)")
  (net 155 "Net-(U3-GPIO7)")
  (net 156 "Net-(U3-UART_RX)")
  (net 157 "Net-(U1-~{PGOOD})")
  (net 158 "Net-(U2-PG)")
  (net 159 "Net-(U1-SYNC{slash}MODE)")
  (net 160 "Net-(U1-VC)")
  (net 161 "Net-(U1-RT)")
  (net 162 "Net-(U3-DEBUG_CTL2(GPIO17,_I2CADDR_B5))")
  (net 163 "Net-(U3-DEBUG_CTL1(GPIO16,_I2CADDR_B4))")
  (net 164 "Net-(U3-I2C_ADDR)")
  (net 165 "Net-(U3-MRESET(GPIO11))")
  (net 166 "Net-(U3-HRESET)")
  (net 167 "Net-(U3-BUSPOWERZ(GPIO10))")
  (net 168 "Net-(U3-R_OSC)")
  (net 169 "Net-(U1-FB)")
  (net 170 "Net-(U4B-PCIE_CLKREQ_N)")
  (net 171 "Net-(U4C-DPSNK0_HPD)")
  (net 172 "Net-(U4C-DPSNK0_DDC_CLK)")
  (net 173 "Net-(U4C-DPSNK0_DDC_DATA)")
  (net 174 "Net-(U4C-DPSNK1_HPD)")
  (net 175 "Net-(U4C-DPSNK1_DDC_CLK)")
  (net 176 "Net-(U4C-DPSNK1_DDC_DATA)")
  (net 177 "Net-(U4C-DPSNK_RBIAS)")
  (net 178 "Net-(U4D-TDI)")
  (net 179 "Net-(U4D-TMS)")
  (net 180 "Net-(U4D-TCK)")
  (net 181 "Net-(U4D-TDO)")
  (net 182 "Net-(U4E-PA_USB2_RBIAS)")
  (net 183 "Net-(U4D-RSENSE)")
  (net 184 "Net-(U4D-RBIAS)")
  (net 185 "Net-(U4E-PB_LSTX)")
  (net 186 "Net-(U4E-PB_LSRX)")
  (net 187 "Net-(U4E-PB_DPSRC_HPD)")
  (net 188 "Net-(U4E-PB_USB2_RBIAS)")
  (net 189 "Net-(U4B-PCIE_RBIAS)")
  (net 190 "Net-(U4C-DPSRC_HPD)")
  (net 191 "Net-(U4C-DPSRC_RBIAS)")
  (net 192 "Net-(U4C-GPIO_3)")
  (net 193 "Net-(U4C-GPIO_4)")
  (net 194 "Net-(U4C-GPIO_5)")
  (net 195 "Net-(U4C-GPIO_6)")
  (net 196 "Net-(U4C-GPIO_7)")
  (net 197 "Net-(U4C-GPIO_8)")
  (net 198 "Net-(U4C-POC_GPIO_1)")
  (net 199 "Net-(U4C-POC_GPIO_2)")
  (net 200 "Net-(U4C-POC_GPIO_3)")
  (net 201 "Net-(U4C-POC_GPIO_5)")
  (net 202 "Net-(U4C-POC_GPIO_6)")
  (net 203 "Net-(U4D-TEST_EN)")
  (net 204 "Net-(U4D-TEST_PWR_GOOD)")
  (net 205 "Net-(U1-LOADTG)")
  (net 206 "Net-(U1-ISMON)")
  (net 207 "Net-(U1-CLKOUT)")
  (net 208 "unconnected-(U3-HV_GATE2-PadA9)")
  (net 209 "unconnected-(U3-SENSEN-PadA10)")
  (net 210 "unconnected-(U3-HV_GATE1-PadB9)")
  (net 211 "unconnected-(U3-SENSEP-PadB10)")
  (net 212 "unconnected-(U3-GPIO1(CONFIG0)-PadC2)")
  (net 213 "unconnected-(U3-GPIO2-PadD10)")
  (net 214 "unconnected-(U3-GPIO5(HPD_RX)-PadE10)")
  (net 215 "unconnected-(U3-SWD_DATA-PadF4)")
  (net 216 "unconnected-(U3-SWD_CLK-PadG4)")
  (net 217 "unconnected-(U3-GPIO3(HD3_EN)-PadG11)")
  (net 218 "unconnected-(U3-GPIO8-PadH6)")
  (net 219 "unconnected-(U3-NC-PadL11)")
  (net 220 "unconnected-(U4E-PB_RX1_N-PadA7)")
  (net 221 "unconnected-(U4E-PB_TX1_P-PadA9)")
  (net 222 "unconnected-(U4E-PB_TX0_P-PadA11)")
  (net 223 "unconnected-(U4E-PB_RX0_P-PadA13)")
  (net 224 "unconnected-(U4F-ATEST_P-PadA23)")
  (net 225 "unconnected-(U4C-DPSNK0_ML0_P-PadAB7)")
  (net 226 "unconnected-(U4C-DPSNK0_ML1_P-PadAB9)")
  (net 227 "unconnected-(U4C-DPSNK0_ML2_P-PadAB11)")
  (net 228 "unconnected-(U4C-DPSNK0_ML3_P-PadAB13)")
  (net 229 "unconnected-(U4C-DPSNK1_ML0_P-PadAB15)")
  (net 230 "unconnected-(U4C-DPSNK1_ML1_P-PadAB17)")
  (net 231 "unconnected-(U4C-DPSNK1_ML2_P-PadAB19)")
  (net 232 "unconnected-(U4C-DPSNK1_ML3_P-PadAB21)")
  (net 233 "unconnected-(U4F-THERMDA2-PadAB23)")
  (net 234 "unconnected-(U4C-DPSNK0_ML0_N-PadAC7)")
  (net 235 "unconnected-(U4C-DPSNK0_ML1_N-PadAC9)")
  (net 236 "unconnected-(U4C-DPSNK0_ML2_N-PadAC11)")
  (net 237 "unconnected-(U4C-DPSNK0_ML3_N-PadAC13)")
  (net 238 "unconnected-(U4C-DPSNK1_ML0_N-PadAC15)")
  (net 239 "unconnected-(U4C-DPSNK1_ML1_N-PadAC17)")
  (net 240 "unconnected-(U4C-DPSNK1_ML2_N-PadAC19)")
  (net 241 "unconnected-(U4C-DPSNK1_ML3_N-PadAC21)")
  (net 242 "unconnected-(U4F-THERMDA1-PadAC23)")
  (net 243 "unconnected-(U4E-PB_RX1_P-PadB7)")
  (net 244 "unconnected-(U4E-PB_TX1_N-PadB9)")
  (net 245 "unconnected-(U4E-PB_TX0_N-PadB11)")
  (net 246 "unconnected-(U4E-PB_RX0_N-PadB13)")
  (net 247 "unconnected-(U4F-ATEST_N-PadB23)")
  (net 248 "unconnected-(U4E-PB_USB2_D_N-PadD19)")
  (net 249 "unconnected-(U4F-USB2_ATEST-PadE18)")
  (net 250 "unconnected-(U4E-PB_USB2_D_P-PadE19)")
  (net 251 "unconnected-(U4C-DPSRC_ML3_N-PadJ1)")
  (net 252 "unconnected-(U4C-DPSRC_ML3_P-PadJ2)")
  (net 253 "unconnected-(U4C-DPSRC_ML2_N-PadL1)")
  (net 254 "unconnected-(U4C-DPSRC_ML2_P-PadL2)")
  (net 255 "unconnected-(U4C-DPSRC_ML1_N-PadN1)")
  (net 256 "unconnected-(U4C-DPSRC_ML1_P-PadN2)")
  (net 257 "unconnected-(U4C-DPSRC_ML0_N-PadR1)")
  (net 258 "unconnected-(U4C-DPSRC_ML0_P-PadR2)")
  (net 259 "unconnected-(U4F-PCIE_ATEST-PadV18)")
  (net 260 "unconnected-(U4C-DPSNK0_AUX_N-PadW11)")
  (net 261 "unconnected-(U4C-DPSNK1_AUX_N-PadW12)")
  (net 262 "unconnected-(U4E-PB_DPSRC_AUX_N-PadW16)")
  (net 263 "unconnected-(U4C-DPSRC_AUX_P-PadW19)")
  (net 264 "unconnected-(U4C-DPSNK0_AUXP-PadY11)")
  (net 265 "unconnected-(U4C-DPSNK1_AUXP-PadY12)")
  (net 266 "unconnected-(U4E-PB_DPSRC_AUX_P-PadY16)")
  (net 267 "unconnected-(U4C-DPSRC_AUX_N-PadY19)")
  (net 268 "Net-(C28-Pad2)")

  (footprint "antmicro-footprints:TP_SMD_1mm" (layer "F.Cu")
    (at 110.211001 60.488 90)
    (property "Author" "Antmicro")
    (property "License" "Apache-2.0")
    (property "MPN" "")
    (property "Manufacturer" "")
    (property "Sheetfile" "power.kicad_sch")
    (property "Sheetname" "Power")
    (property "exclude_from_bom" "")
    (property "ki_description" "Test point 1mm SMD")
    (property "ki_keywords" "TESTPOINT")
    (attr exclude_from_pos_files exclude_from_bom)
    (fp_text reference "TP2" (at 0.798 -0.991001 180) (layer "F.SilkS")
        (effects (font (size 0.7 0.7) (thickness 0.15)) (justify left bottom))
    )
    (fp_text value "TP_1mm_SMD" (at 0 1.4 90) (layer "F.Fab")
        (effects (font (size 0.7 0.7) (thickness 0.15)) (justify left bottom))
    )
    (fp_text user "${REFERENCE}" (at -0.5 2.8 90) (layer "F.Fab") hide
        (effects (font (size 0.7 0.7) (thickness 0.15)) (justify left bottom))
    )
    (fp_text user "License: Apache-2.0" (at -0.5 5.2 90) (layer "F.Fab") hide
        (effects (font (size 0.7 0.7) (thickness 0.15)) (justify left bottom))
    )
    (fp_text user "Author: Antmicro" (at -0.5 4 90) (layer "F.Fab") hide
        (effects (font (size 0.7 0.7) (thickness 0.15)) (justify left bottom))
    )
    (fp_circle (center 0 0) (end 0.6 0)
      (stroke (width 0.05) (type default)) (fill none) (layer "F.CrtYd"))
    (pad "1" smd circle (at 0 0 90) (size 1 1) (layers "F.Cu" "F.Mask")
      (net 90 "Net-(U2-VIN)") (pinfunction "1") (pintype "passive"))
  )

  (footprint "antmicro-footprints:LED_0603_1608Metric_G" (layer "F.Cu")
    (at 126.25 62.75 180)
    (descr "LED SMD 0603 Green")
    (tags "LED SMD 0603 Green")
    (property "Author" "Antmicro")
    (property "Color" "Green")
    (property "License" "Apache-2.0")
    (property "MPN" "KP-1608CGCK")
    (property "Manufacturer" "Kingbright")
    (property "Sheetfile" "power.kicad_sch")
    (property "Sheetname" "Power")
    (property "ki_description" "LED, Green, SMD, 0603, 20 mA, 2.1 V, 570 nm")
    (property "ki_keywords" "SMT, DIODE, SEMICONDUCTOR, LED")
    (attr smd)
    (fp_text reference "D2" (at 0.647 -1.639 180) (layer "F.SilkS")
        (effects (font (size 0.7 0.7) (thickness 0.15)) (justify left bottom))
    )
    (fp_text value "LED_G_0603_KP-1608CGCK" (at -0.001 1.599 180) (layer "F.Fab")
        (effects (font (size 0.7 0.7) (thickness 0.15)) (justify left bottom))
    )
    (fp_text user "License: Apache-2.0" (at -1.4224 3.599 180) (layer "F.Fab") hide
        (effects (font (size 0.7 0.7) (thickness 0.15)) (justify left bottom))
    )
    (fp_text user "Author: Antmicro" (at -1.4224 4.799 180) (layer "F.Fab") hide
        (effects (font (size 0.7 0.7) (thickness 0.15)) (justify left bottom))
    )
    (fp_text user "${REFERENCE}" (at -1.4224 5.999 180) (layer "F.Fab") hide
        (effects (font (size 0.7 0.7) (thickness 0.15)) (justify left bottom))
    )
    (fp_line (start -1.18 -0.319) (end -1.18 0.321)
      (stroke (width 0.15) (type solid)) (layer "F.SilkS"))
    (fp_line (start -0.094672 0.001008) (end -0.24 0.001008)
      (stroke (width 0.1) (type solid)) (layer "F.SilkS"))
    (fp_line (start -0.094672 0.001008) (end 0.105328 -0.198992)
      (stroke (width 0.1) (type solid)) (layer "F.SilkS"))
    (fp_line (start -0.094672 0.201008) (end -0.094672 -0.198992)
      (stroke (width 0.1) (type solid)) (layer "F.SilkS"))
    (fp_line (start 0.105328 0.001008) (end 0.24 0.001)
      (stroke (width 0.1) (type solid)) (layer "F.SilkS"))
    (fp_line (start 0.105328 0.201008) (end -0.094672 0.001008)
      (stroke (width 0.1) (type solid)) (layer "F.SilkS"))
    (fp_line (start 0.105328 0.201008) (end 0.105328 -0.198992)
      (stroke (width 0.1) (type solid)) (layer "F.SilkS"))
    (fp_line (start 0.22 -0.35) (end -0.22 -0.35)
      (stroke (width 0.15) (type solid)) (layer "F.SilkS"))
    (fp_line (start 0.22 0.35) (end -0.22 0.35)
      (stroke (width 0.15) (type solid)) (layer "F.SilkS"))
    (fp_rect (start 1.25 0.65) (end -1.25 -0.65)
      (stroke (width 0.05) (type solid)) (fill none) (layer "F.CrtYd"))
    (fp_line (start -0.199 -0.202) (end -0.199 0.1)
      (stroke (width 0.15) (type solid)) (layer "F.Fab"))
    (fp_line (start -0.199 0) (end -0.597 0)
      (stroke (width 0.15) (type solid)) (layer "F.Fab"))
    (fp_line (start -0.199 0.2) (end -0.199 0.1)
      (stroke (width 0.15) (type solid)) (layer "F.Fab"))
    (fp_line (start -0.101 0) (end 0.201 0.2)
      (stroke (width 0.15) (type solid)) (layer "F.Fab"))
    (fp_line (start 0.201 -0.202) (end -0.101 0)
      (stroke (width 0.15) (type solid)) (layer "F.Fab"))
    (fp_line (start 0.201 0) (end 0.201 -0.202)
      (stroke (width 0.15) (type solid)) (layer "F.Fab"))
    (fp_line (start 0.201 0.2) (end 0.201 0)
      (stroke (width 0.15) (type solid)) (layer "F.Fab"))
    (fp_line (start 0.599 0) (end 0.201 0)
      (stroke (width 0.15) (type solid)) (layer "F.Fab"))
    (fp_rect (start 0.848 0.4) (end -0.85 -0.402)
      (stroke (width 0.15) (type solid)) (fill none) (layer "F.Fab"))
    (pad "1" smd roundrect (at -0.7 0) (size 0.8 1) (layers "F.Cu" "F.Paste" "F.Mask") (roundrect_rratio 0.2)
      (net 120 "Net-(D2-C)") (pinfunction "C") (pintype "passive"))
    (pad "2" smd roundrect (at 0.7 0) (size 0.8 1) (layers "F.Cu" "F.Paste" "F.Mask") (roundrect_rratio 0.2)
      (net 100 "Net-(D2-A)") (pinfunction "A") (pintype "passive"))
  )

  (footprint "antmicro-footprints:C_1206_3216Metric" (layer "F.Cu")
    (at 103.265 82.86 90)
    (descr "Capacitor SMD 1206")
    (tags "capacitor SMD 1206")
    (property "Author" "Antmicro")
    (property "Dielectric" "")
    (property "License" "Apache-2.0")
    (property "MPN" "3216X5R1V226M160AC")
    (property "Manufacturer" "TDK")
    (property "Sheetfile" "power.kicad_sch")
    (property "Sheetname" "Power")
    (property "Val" "22u")
    (property "Voltage" "35V")
    (property "ki_description" "SMD Multilayer Ceramic Capacitors, 22µF, 35V, X5R, 1206 [2316 Metric], 20% ")
    (property "ki_keywords" "1206, SMT, CAPACITOR, PASSIVE, CERAMIC, MLCC")
    (attr smd)
    (fp_text reference "C10" (at -0.96 -1.411 90) (layer "F.SilkS")
        (effects (font (size 0.7 0.7) (thickness 0.15)) (justify left bottom))
    )
    (fp_text value "C_22u_1206_35V" (at 0 2.101 90) (layer "F.Fab")
        (effects (font (size 0.7 0.7) (thickness 0.15)) (justify left bottom))
    )
    (fp_text user "${REFERENCE}" (at -2.625 4.101 90) (layer "F.Fab") hide
        (effects (font (size 0.7 0.7) (thickness 0.15)) (justify left bottom))
    )
    (fp_text user "Author: Antmicro" (at -2.625 5.301 90) (layer "F.Fab") hide
        (effects (font (size 0.7 0.7) (thickness 0.15)) (justify left bottom))
    )
    (fp_text user "License: Apache-2.0" (at -2.625 6.501 90) (layer "F.Fab") hide
        (effects (font (size 0.7 0.7) (thickness 0.15)) (justify left bottom))
    )
    (fp_line (start 0.8 -0.899) (end -0.8 -0.899)
      (stroke (width 0.15) (type solid)) (layer "F.SilkS"))
    (fp_line (start 0.8 0.901) (end -0.8 0.901)
      (stroke (width 0.15) (type solid)) (layer "F.SilkS"))
    (fp_rect (start -2.325 -1.15) (end 2.325 1.15)
      (stroke (width 0.05) (type default)) (fill none) (layer "F.CrtYd"))
    (fp_rect (start -1.6 -0.799) (end 1.6 0.801)
      (stroke (width 0.15) (type solid)) (fill none) (layer "F.Fab"))
    (pad "1" smd roundrect (at -1.5 0.001 90) (size 1.15 1.8) (layers "F.Cu" "F.Paste" "F.Mask") (roundrect_rratio 0.25)
      (net 1 "GND") (pintype "passive"))
    (pad "2" smd roundrect (at 1.5 0.001 90) (size 1.15 1.8) (layers "F.Cu" "F.Paste" "F.Mask") (roundrect_rratio 0.25)
      (net 74 "Net-(C10-Pad2)") (pintype "passive"))
  )

  (footprint "antmicro-footprints:D_SOD-323F" (layer "F.Cu")
    (at 116.3 62.23)
    (property "Author" "Antmicro")
    (property "License" "Apache-2.0")
    (property "MPN" "MM3Z3V3C")
    (property "Manufacturer" "ON Semiconductor")
    (property "Sheetfile" "power.kicad_sch")
    (property "Sheetname" "Power")
    (property "ki_description" "Zener Single Diode, 3.3 V, 200 mW, SOD-323F, 2 Pins, 150 °C, Surface Mount")
    (property "ki_keywords" "SMT, DIODE, SEMICONDUCTOR, ZENER")
    (attr smd)
    (fp_text reference "D1" (at -4.413 -1.016) (layer "F.SilkS")
        (effects (font (size 0.7 0.7) (thickness 0.15)) (justify left bottom))
    )
    (fp_text value "MM3Z3V3C" (at 0 1.9) (layer "F.Fab")
        (effects (font (size 0.7 0.7) (thickness 0.15)) (justify left bottom))
    )
    (fp_text user "${REFERENCE}" (at -1.7 5.099) (layer "F.Fab") hide
        (effects (font (size 0.7 0.7) (thickness 0.15)) (justify left bottom))
    )
    (fp_text user "License: Apache-2.0" (at -1.7 6.299) (layer "F.Fab") hide
        (effects (font (size 0.7 0.7) (thickness 0.15)) (justify left bottom))
    )
    (fp_text user "Author: Antmicro" (at -1.7 3.899) (layer "F.Fab") hide
        (effects (font (size 0.7 0.7) (thickness 0.15)) (justify left bottom))
    )
    (fp_line (start -0.975 -0.749) (end -0.975 -0.449)
      (stroke (width 0.15) (type solid)) (layer "F.SilkS"))
    (fp_line (start -0.975 0.749) (end -0.975 0.451)
      (stroke (width 0.15) (type solid)) (layer "F.SilkS"))
    (fp_line (start -0.625 -0.749) (end -0.975 -0.749)
      (stroke (width 0.15) (type solid)) (layer "F.SilkS"))
    (fp_line (start -0.625 0.749) (end -0.975 0.749)
      (stroke (width 0.15) (type solid)) (layer "F.SilkS"))
    (fp_line (start -0.5 -0.425) (end -0.5 0.425)
      (stroke (width 0.15) (type solid)) (layer "F.SilkS"))
    (fp_line (start 0.623 -0.749) (end 0.973 -0.749)
      (stroke (width 0.15) (type solid)) (layer "F.SilkS"))
    (fp_line (start 0.973 -0.749) (end 0.973 -0.449)
      (stroke (width 0.15) (type solid)) (layer "F.SilkS"))
    (fp_line (start 0.973 0.451) (end 0.973 0.749)
      (stroke (width 0.15) (type solid)) (layer "F.SilkS"))
    (fp_line (start 0.973 0.749) (end 0.623 0.749)
      (stroke (width 0.15) (type solid)) (layer "F.SilkS"))
    (fp_rect (start -1.55 -0.95) (end 1.55 0.95)
      (stroke (width 0.05) (type solid)) (fill none) (layer "F.CrtYd"))
    (fp_rect (start -1.25 -0.676) (end 1.245365 0.676)
      (stroke (width 0.1) (type solid)) (fill none) (layer "F.Fab"))
    (pad "1" smd roundrect (at -1.051 0.001) (size 0.8 0.6) (layers "F.Cu" "F.Paste" "F.Mask") (roundrect_rratio 0.15)
      (net 119 "Net-(D1-C)") (pinfunction "C") (pintype "passive"))
    (pad "2" smd roundrect (at 1.05 0.001) (size 0.8 0.6) (layers "F.Cu" "F.Paste" "F.Mask") (roundrect_rratio 0.15)
      (net 1 "GND") (pinfunction "A") (pintype "passive"))
  )

  (footprint "antmicro-footprints:C_1206_3216Metric" (layer "F.Cu")
    (at 105.675 82.86 90)
    (descr "Capacitor SMD 1206")
    (tags "capacitor SMD 1206")
    (property "Author" "Antmicro")
    (property "Dielectric" "")
    (property "License" "Apache-2.0")
    (property "MPN" "3216X5R1V226M160AC")
    (property "Manufacturer" "TDK")
    (property "Sheetfile" "power.kicad_sch")
    (property "Sheetname" "Power")
    (property "Val" "22u")
    (property "Voltage" "35V")
    (property "ki_description" "SMD Multilayer Ceramic Capacitors, 22µF, 35V, X5R, 1206 [2316 Metric], 20% ")
    (property "ki_keywords" "1206, SMT, CAPACITOR, PASSIVE, CERAMIC, MLCC")
    (attr smd)
    (fp_text reference "C8" (at -0.579 2.021 90) (layer "F.SilkS")
        (effects (font (size 0.7 0.7) (thickness 0.15)) (justify left bottom))
    )
    (fp_text value "C_22u_1206_35V" (at 0 2.101 90) (layer "F.Fab")
        (effects (font (size 0.7 0.7) (thickness 0.15)) (justify left bottom))
    )
    (fp_text user "License: Apache-2.0" (at -2.625 6.501 90) (layer "F.Fab") hide
        (effects (font (size 0.7 0.7) (thickness 0.15)) (justify left bottom))
    )
    (fp_text user "${REFERENCE}" (at -2.625 4.101 90) (layer "F.Fab") hide
        (effects (font (size 0.7 0.7) (thickness 0.15)) (justify left bottom))
    )
    (fp_text user "Author: Antmicro" (at -2.625 5.301 90) (layer "F.Fab") hide
        (effects (font (size 0.7 0.7) (thickness 0.15)) (justify left bottom))
    )
    (fp_line (start 0.8 -0.899) (end -0.8 -0.899)
      (stroke (width 0.15) (type solid)) (layer "F.SilkS"))
    (fp_line (start 0.8 0.901) (end -0.8 0.901)
      (stroke (width 0.15) (type solid)) (layer "F.SilkS"))
    (fp_rect (start -2.325 -1.15) (end 2.325 1.15)
      (stroke (width 0.05) (type default)) (fill none) (layer "F.CrtYd"))
    (fp_rect (start -1.6 -0.799) (end 1.6 0.801)
      (stroke (width 0.15) (type solid)) (fill none) (layer "F.Fab"))
    (pad "1" smd roundrect (at -1.5 0.001 90) (size 1.15 1.8) (layers "F.Cu" "F.Paste" "F.Mask") (roundrect_rratio 0.25)
      (net 1 "GND") (pintype "passive"))
    (pad "2" smd roundrect (at 1.5 0.001 90) (size 1.15 1.8) (layers "F.Cu" "F.Paste" "F.Mask") (roundrect_rratio 0.25)
      (net 74 "Net-(C10-Pad2)") (pintype "passive"))
  )

  (footprint "antmicro-footprints:TP_SMD_1mm" (layer "F.Cu")
    (at 105.991001 62.319 180)
    (property "Author" "Antmicro")
    (property "License" "Apache-2.0")
    (property "MPN" "")
    (property "Manufacturer" "")
    (property "Sheetfile" "power.kicad_sch")
    (property "Sheetname" "Power")
    (property "exclude_from_bom" "")
    (property "ki_description" "Test point 1mm SMD")
    (property "ki_keywords" "TESTPOINT")
    (attr exclude_from_pos_files exclude_from_bom)
    (fp_text reference "TP1" (at 2.613001 -0.419 180) (layer "F.SilkS")
        (effects (font (size 0.7 0.7) (thickness 0.15)) (justify left bottom))
    )
    (fp_text value "TP_1mm_SMD" (at 0 1.4 180) (layer "F.Fab")
        (effects (font (size 0.7 0.7) (thickness 0.15)) (justify left bottom))
    )
    (fp_text user "Author: Antmicro" (at -0.5 4 180) (layer "F.Fab") hide
        (effects (font (size 0.7 0.7) (thickness 0.15)) (justify left bottom))
    )
    (fp_text user "${REFERENCE}" (at -0.5 2.8 180) (layer "F.Fab") hide
        (effects (font (size 0.7 0.7) (thickness 0.15)) (justify left bottom))
    )
    (fp_text user "License: Apache-2.0" (at -0.5 5.2 180) (layer "F.Fab") hide
        (effects (font (size 0.7 0.7) (thickness 0.15)) (justify left bottom))
    )
    (fp_circle (center 0 0) (end 0.6 0)
      (stroke (width 0.05) (type default)) (fill none) (layer "F.CrtYd"))
    (pad "1" smd circle (at 0 0 180) (size 1 1) (layers "F.Cu" "F.Mask")
      (net 3 "5V0_USB") (pinfunction "1") (pintype "passive"))
  )

  (footprint "antmicro-footprints:FB_0805_2012Metric" (layer "F.Cu")
    (at 121.230001 59.1125)
    (descr "FERRITE BEAD 0805")
    (tags "FERRITE BEAD 0805")
    (property "Author" "Antmicro")
    (property "Current" "")
    (property "License" "Apache-2.0")
    (property "MPN" "BLM21SN300SZ1D")
    (property "Manufacturer" "Murata")
    (property "Sheetfile" "power.kicad_sch")
    (property "Sheetname" "Power")
    (property "Val" "30Z/8.5A")
    (property "ki_description" "Ferrite Bead, 0805 [2012 Metric], 30 ohm, 8.5 A, BLM21SN, 0.004 ohm, ± 10ohm, DC power line")
    (property "ki_keywords" "0805, SMT, FERRITE BEAD, PASSIVE")
    (attr smd)
    (fp_text reference "FB3" (at -0.834001 -0.9465) (layer "F.SilkS")
        (effects (font (size 0.7 0.7) (thickness 0.15)) (justify left bottom))
    )
    (fp_text value "FB_30Z_8.5A_Murata-BLM21SN_0805" (at 0.001 1.801) (layer "F.Fab")
        (effects (font (size 0.7 0.7) (thickness 0.15)) (justify left bottom))
    )
    (fp_text user "${REFERENCE}" (at -1.44 3.801) (layer "F.Fab") hide
        (effects (font (size 0.7 0.7) (thickness 0.15)) (justify left bottom))
    )
    (fp_text user "Author: Antmicro" (at -1.44 5.001) (layer "F.Fab") hide
        (effects (font (size 0.7 0.7) (thickness 0.15)) (justify left bottom))
    )
    (fp_text user "License: Apache-2.0" (at -1.44 6.201) (layer "F.Fab") hide
        (effects (font (size 0.7 0.7) (thickness 0.15)) (justify left bottom))
    )
    (fp_line (start -0.319 0.698) (end 0.281 0.698)
      (stroke (width 0.15) (type solid)) (layer "F.SilkS"))
    (fp_line (start -0.299 -0.698) (end 0.299 -0.698)
      (stroke (width 0.15) (type solid)) (layer "F.SilkS"))
    (fp_rect (start 1.95 -0.9) (end -1.95 0.9)
      (stroke (width 0.05) (type default)) (fill none) (layer "F.CrtYd"))
    (fp_line (start -0.948 -0.681) (end 0.948 -0.681)
      (stroke (width 0.15) (type solid)) (layer "F.Fab"))
    (fp_line (start -0.948 -0.676) (end -0.948 0.676)
      (stroke (width 0.15) (type solid)) (layer "F.Fab"))
    (fp_line (start -0.948 0.681) (end 0.948 0.681)
      (stroke (width 0.15) (type solid)) (layer "F.Fab"))
    (fp_line (start 0.948 -0.676) (end 0.948 0.676)
      (stroke (width 0.15) (type solid)) (layer "F.Fab"))
    (pad "1" smd roundrect (at -1.1 0) (size 1.2 1.3) (layers "F.Cu" "F.Paste" "F.Mask") (roundrect_rratio 0.25)
      (net 100 "Net-(D2-A)") (pintype "passive"))
    (pad "2" smd roundrect (at 1.1 0) (size 1.2 1.3) (layers "F.Cu" "F.Paste" "F.Mask") (roundrect_rratio 0.25)
      (net 2 "3V3_SYS") (pintype "passive"))
  )

  (footprint "antmicro-footprints:Fiducial_1mm_Mask3mm" (layer "F.Cu")
    (at 102 91)
    (descr "Circular Fiducial, 1.5mm bare copper, 3mm soldermask opening")
    (tags "fiducial")
    (property "Author" "Antmicro")
    (property "License" "Apache-2.0")
    (property "Sheetfile" "thunderbolt-pcie-adapter.kicad_sch")
    (property "Sheetname" "")
    (property "exclude_from_bom" "")
    (property "ki_description" "Fiducial mask")
    (attr through_hole exclude_from_bom)
    (fp_text reference "FID1" (at -1.797 2.472) (layer "F.SilkS")
        (effects (font (size 0.7 0.7) (thickness 0.15)) (justify left bottom))
    )
    (fp_text value "Fiducial_1mm_Mask3mm" (at 0 2.603) (layer "F.Fab")
        (effects (font (size 0.7 0.7) (thickness 0.15)) (justify left bottom))
    )
    (fp_text user "Author: Antmicro" (at -1.25 5.803) (layer "F.Fab") hide
        (effects (font (size 0.7 0.7) (thickness 0.15)) (justify left bottom))
    )
    (fp_text user "License: Apache-2.0" (at -1.25 7.003) (layer "F.Fab") hide
        (effects (font (size 0.7 0.7) (thickness 0.15)) (justify left bottom))
    )
    (fp_text user "${REFERENCE}" (at -1.25 4.603) (layer "F.Fab") hide
        (effects (font (size 0.7 0.7) (thickness 0.15)) (justify left bottom))
    )
    (fp_circle (center 0 0) (end 1.5 0)
      (stroke (width 0.05) (type solid)) (fill none) (layer "F.CrtYd"))
    (fp_circle (center 0 0) (end 1.5 0)
      (stroke (width 0.15) (type solid)) (fill none) (layer "F.Fab"))
    (pad "" smd circle (at 0 0) (size 1 1) (layers "F.Cu" "F.Mask")
      (solder_mask_margin 1) (clearance 1))
  )

  (footprint "antmicro-footprints:TP_SMD_1mm" (layer "F.Cu")
    (at 107.1 86.4)
    (property "Author" "Antmicro")
    (property "License" "Apache-2.0")
    (property "MPN" "")
    (property "Manufacturer" "")
    (property "Sheetfile" "power.kicad_sch")
    (property "Sheetname" "Power")
    (property "exclude_from_bom" "")
    (property "ki_description" "Test point 1mm SMD")
    (property "ki_keywords" "TESTPOINT")
    (attr exclude_from_pos_files exclude_from_bom)
    (fp_text reference "TP12" (at -6.643 -0.294) (layer "F.SilkS")
        (effects (font (size 0.7 0.7) (thickness 0.15)) (justify left bottom))
    )
    (fp_text value "TP_1mm_SMD" (at 0 1.4) (layer "F.Fab")
        (effects (font (size 0.7 0.7) (thickness 0.15)) (justify left bottom))
    )
    (fp_text user "${REFERENCE}" (at -0.5 2.8) (layer "F.Fab") hide
        (effects (font (size 0.7 0.7) (thickness 0.15)) (justify left bottom))
    )
    (fp_text user "License: Apache-2.0" (at -0.5 5.2) (layer "F.Fab") hide
        (effects (font (size 0.7 0.7) (thickness 0.15)) (justify left bottom))
    )
    (fp_text user "Author: Antmicro" (at -0.5 4) (layer "F.Fab") hide
        (effects (font (size 0.7 0.7) (thickness 0.15)) (justify left bottom))
    )
    (fp_circle (center 0 0) (end 0.6 0)
      (stroke (width 0.05) (type default)) (fill none) (layer "F.CrtYd"))
    (pad "1" smd circle (at 0 0) (size 1 1) (layers "F.Cu" "F.Mask")
      (net 61 "12V0_MOLEX") (pinfunction "1") (pintype "passive"))
  )

  (footprint "antmicro-footprints:JHL6340SLLSQ" (layer "F.Cu")
    (at 134.8 79.85 -90)
    (property "Author" "Antmicro")
    (property "License" "Apache-2.0")
    (property "MPN" "JHL6340SLLSQ")
    (property "Manufacturer" "Intel")
    (property "Sheetfile" "tb-power.kicad_sch")
    (property "Sheetname" "Thunderbolt Controller - Power")
    (property "ki_description" "Thunderbolt™ 3 Controller, I/O")
    (property "ki_keywords" "IC")
    (attr smd)
    (fp_text reference "U4" (at -4.666 -6.17 -90 unlocked) (layer "F.SilkS")
        (effects (font (size 0.7 0.7) (thickness 0.15)))
    )
    (fp_text value "JHL6340SLLSQ" (at 0 6.4 -90 unlocked) (layer "F.Fab")
        (effects (font (size 0.7 0.7) (thickness 0.15)))
    )
    (fp_text user "License: Apache-2.0" (at 0 10.45 -90) (layer "F.Fab") hide
        (effects (font (size 0.7 0.7) (thickness 0.15)))
    )
    (fp_text user "${REFERENCE}" (at 0 7.8 -90 unlocked) (layer "F.Fab") hide
        (effects (font (size 0.7 0.7) (thickness 0.15)))
    )
    (fp_text user "Author: Antmicro" (at 0.05 9 -90) (layer "F.Fab") hide
        (effects (font (size 0.7 0.7) (thickness 0.15)))
    )
    (fp_line (start -5.35 5.35) (end -5.35 -5.35)
      (stroke (width 0.1) (type solid)) (layer "F.SilkS"))
    (fp_line (start -5.35 5.35) (end 5.35 5.35)
      (stroke (width 0.1) (type solid)) (layer "F.SilkS"))
    (fp_line (start 5.35 -5.35) (end -5.35 -5.35)
      (stroke (width 0.1) (type solid)) (layer "F.SilkS"))
    (fp_line (start 5.35 -5.35) (end 5.35 5.35)
      (stroke (width 0.1) (type solid)) (layer "F.SilkS"))
    (fp_circle (center -5.7 -5.7) (end -5.6 -5.7)
      (stroke (width 0.2) (type solid)) (fill none) (layer "F.SilkS"))
    (fp_rect (start -5.6 -5.6) (end 5.6 5.6)
      (stroke (width 0.05) (type solid)) (fill none) (layer "F.CrtYd"))
    (fp_line (start -5.35 5.35) (end -5.35 -4.35)
      (stroke (width 0.15) (type solid)) (layer "F.Fab"))
    (fp_line (start -4.35 -5.35) (end -5.35 -4.35)
      (stroke (width 0.15) (type solid)) (layer "F.Fab"))
    (fp_line (start -4.35 -5.35) (end 5.35 -5.35)
      (stroke (width 0.15) (type solid)) (layer "F.Fab"))
    (fp_line (start 5.35 -5.35) (end 5.35 5.35)
      (stroke (width 0.15) (type solid)) (layer "F.Fab"))
    (fp_line (start 5.35 5.35) (end -5.35 5.35)
      (stroke (width 0.15) (type solid)) (layer "F.Fab"))
    (pad "A1" smd circle (at -5.06 -5.06 270) (size 0.254 0.254) (layers "F.Cu" "F.Paste" "F.Mask")
      (net 1 "GND") (pinfunction "SVR_VSS") (pintype "power_in"))
    (pad "A2" smd oval (at -4.6 -5.06 270) (size 0.1578 0.3302) (layers "F.Cu" "F.Paste" "F.Mask")
      (net 2 "3V3_SYS") (pinfunction "VCC3P3_SVR") (pintype "power_in"))
    (pad "A3" smd oval (at -4.14 -5.06 270) (size 0.1578 0.3302) (layers "F.Cu" "F.Paste" "F.Mask")
      (net 2 "3V3_SYS") (pinfunction "VCC3P3_SVR") (pintype "passive"))
    (pad "A4" smd oval (at -3.68 -5.06 270) (size 0.1578 0.3302) (layers "F.Cu" "F.Paste" "F.Mask")
      (net 66 "LSX_P2R") (pinfunction "PA_LSRX") (pintype "input"))
    (pad "A5" smd oval (at -3.22 -5.06 270) (size 0.1578 0.3302) (layers "F.Cu" "F.Paste" "F.Mask")
      (net 67 "LSX_R2P") (pinfunction "PA_LSTX") (pintype "output"))
    (pad "A6" smd oval (at -2.76 -5.06 270) (size 0.1578 0.3302) (layers "F.Cu" "F.Paste" "F.Mask")
      (net 1 "GND") (pinfunction "VSS_ANA") (pintype "passive"))
    (pad "A7" smd oval (at -2.3 -5.06 270) (size 0.1578 0.3302) (layers "F.Cu" "F.Paste" "F.Mask")
      (net 220 "unconnected-(U4E-PB_RX1_N-PadA7)") (pinfunction "PB_RX1_N") (pintype "input+no_connect"))
    (pad "A8" smd oval (at -1.84 -5.06 270) (size 0.1578 0.3302) (layers "F.Cu" "F.Paste" "F.Mask")
      (net 1 "GND") (pinfunction "VSS_ANA") (pintype "passive"))
    (pad "A9" smd oval (at -1.38 -5.06 270) (size 0.1578 0.3302) (layers "F.Cu" "F.Paste" "F.Mask")
      (net 221 "unconnected-(U4E-PB_TX1_P-PadA9)") (pinfunction "PB_TX1_P") (pintype "output+no_connect"))
    (pad "A10" smd oval (at -0.92 -5.06 270) (size 0.1578 0.3302) (layers "F.Cu" "F.Paste" "F.Mask")
      (net 1 "GND") (pinfunction "VSS_ANA") (pintype "passive"))
    (pad "A11" smd oval (at -0.46 -5.06 270) (size 0.1578 0.3302) (layers "F.Cu" "F.Paste" "F.Mask")
      (net 222 "unconnected-(U4E-PB_TX0_P-PadA11)") (pinfunction "PB_TX0_P") (pintype "output+no_connect"))
    (pad "A12" smd oval (at 0 -5.06 270) (size 0.1578 0.3302) (layers "F.Cu" "F.Paste" "F.Mask")
      (net 1 "GND") (pinfunction "VSS_ANA") (pintype "passive"))
    (pad "A13" smd oval (at 0.46 -5.06 270) (size 0.1578 0.3302) (layers "F.Cu" "F.Paste" "F.Mask")
      (net 223 "unconnected-(U4E-PB_RX0_P-PadA13)") (pinfunction "PB_RX0_P") (pintype "input+no_connect"))
    (pad "A14" smd oval (at 0.92 -5.06 270) (size 0.1578 0.3302) (layers "F.Cu" "F.Paste" "F.Mask")
      (net 1 "GND") (pinfunction "VSS_ANA") (pintype "passive"))
    (pad "A15" smd oval (at 1.38 -5.06 270) (size 0.1578 0.3302) (layers "F.Cu" "F.Paste" "F.Mask")
      (net 37 "TB_RX1_P") (pinfunction "PA_RX1_P") (pintype "input"))
    (pad "A16" smd oval (at 1.84 -5.06 270) (size 0.1578 0.3302) (layers "F.Cu" "F.Paste" "F.Mask")
      (net 1 "GND") (pinfunction "VSS_ANA") (pintype "passive"))
    (pad "A17" smd oval (at 2.3 -5.06 270) (size 0.1578 0.3302) (layers "F.Cu" "F.Paste" "F.Mask")
      (net 15 "/TB Controller/PA_TX1_P") (pinfunction "PA_TX1_P") (pintype "output"))
    (pad "A18" smd oval (at 2.76 -5.06 270) (size 0.1578 0.3302) (layers "F.Cu" "F.Paste" "F.Mask")
      (net 1 "GND") (pinfunction "VSS_ANA") (pintype "passive"))
    (pad "A19" smd oval (at 3.22 -5.06 270) (size 0.1578 0.3302) (layers "F.Cu" "F.Paste" "F.Mask")
      (net 13 "/TB Controller/PA_TX0_P") (pinfunction "PA_TX0_P") (pintype "output"))
    (pad "A20" smd oval (at 3.68 -5.06 270) (size 0.1578 0.3302) (layers "F.Cu" "F.Paste" "F.Mask")
      (net 1 "GND") (pinfunction "VSS_ANA") (pintype "passive"))
    (pad "A21" smd oval (at 4.14 -5.06 270) (size 0.1578 0.3302) (layers "F.Cu" "F.Paste" "F.Mask")
      (net 41 "TB_RX0_N") (pinfunction "PA_RX0_N") (pintype "input"))
    (pad "A22" smd oval (at 4.6 -5.06 270) (size 0.1578 0.3302) (layers "F.Cu" "F.Paste" "F.Mask")
      (net 1 "GND") (pinfunction "VSS_ANA") (pintype "passive"))
    (pad "A23" smd circle (at 5.06 -5.06 270) (size 0.254 0.254) (layers "F.Cu" "F.Paste" "F.Mask")
      (net 224 "unconnected-(U4F-ATEST_P-PadA23)") (pinfunction "ATEST_P") (pintype "passive+no_connect"))
    (pad "AA1" smd oval (at -5.06 4.14) (size 0.1578 0.3302) (layers "F.Cu" "F.Paste" "F.Mask")
      (net 197 "Net-(U4C-GPIO_8)") (pinfunction "GPIO_8") (pintype "bidirectional"))
    (pad "AA2" smd circle (at -4.6 4.14 270) (size 0.254 0.254) (layers "F.Cu" "F.Paste" "F.Mask")
      (net 171 "Net-(U4C-DPSNK0_HPD)") (pinfunction "DPSNK0_HPD") (pintype "passive"))
    (pad "AA22" smd circle (at 4.6 4.14 270) (size 0.254 0.254) (layers "F.Cu" "F.Paste" "F.Mask")
      (net 1 "GND") (pinfunction "VSS_ANA") (pintype "passive"))
    (pad "AA23" smd oval (at 5.06 4.14) (size 0.1578 0.3302) (layers "F.Cu" "F.Paste" "F.Mask")
      (net 1 "GND") (pinfunction "VSS_ANA") (pintype "passive"))
    (pad "AB1" smd oval (at -5.06 4.6) (size 0.1578 0.3302) (layers "F.Cu" "F.Paste" "F.Mask")
      (net 1 "GND") (pinfunction "VSS") (pintype "passive"))
    (pad "AB2" smd circle (at -4.6 4.6 270) (size 0.254 0.254) (layers "F.Cu" "F.Paste" "F.Mask")
      (net 1 "GND") (pinfunction "MONDC_DPSRC") (pintype "passive"))
    (pad "AB3" smd circle (at -4.14 4.6 270) (size 0.254 0.254) (layers "F.Cu" "F.Paste" "F.Mask")
      (net 69 "SPI_MOSI") (pinfunction "EE_DI") (pintype "output"))
    (pad "AB4" smd circle (at -3.68 4.6 270) (size 0.254 0.254) (layers "F.Cu" "F.Paste" "F.Mask")
      (net 68 "SPI_SCLK") (pinfunction "EE_CLK") (pintype "output"))
    (pad "AB5" smd circle (at -3.22 4.6 270) (size 0.254 0.254) (layers "F.Cu" "F.Paste" "F.Mask")
      (net 204 "Net-(U4D-TEST_PWR_GOOD)") (pinfunction "TEST_PWR_GOOD") (pintype "input"))
    (pad "AB6" smd circle (at -2.76 4.6 270) (size 0.254 0.254) (layers "F.Cu" "F.Paste" "F.Mask")
      (net 1 "GND") (pinfunction "VSS_ANA") (pintype "passive"))
    (pad "AB7" smd circle (at -2.3 4.6 270) (size 0.254 0.254) (layers "F.Cu" "F.Paste" "F.Mask")
      (net 225 "unconnected-(U4C-DPSNK0_ML0_P-PadAB7)") (pinfunction "DPSNK0_ML0_P") (pintype "input+no_connect"))
    (pad "AB8" smd circle (at -1.84 4.6 270) (size 0.254 0.254) (layers "F.Cu" "F.Paste" "F.Mask")
      (net 1 "GND") (pinfunction "VSS_ANA") (pintype "passive"))
    (pad "AB9" smd circle (at -1.38 4.6 270) (size 0.254 0.254) (layers "F.Cu" "F.Paste" "F.Mask")
      (net 226 "unconnected-(U4C-DPSNK0_ML1_P-PadAB9)") (pinfunction "DPSNK0_ML1_P") (pintype "input+no_connect"))
    (pad "AB10" smd circle (at -0.92 4.6 270) (size 0.254 0.254) (layers "F.Cu" "F.Paste" "F.Mask")
      (net 1 "GND") (pinfunction "VSS_ANA") (pintype "passive"))
    (pad "AB11" smd circle (at -0.46 4.6 270) (size 0.254 0.254) (layers "F.Cu" "F.Paste" "F.Mask")
      (net 227 "unconnected-(U4C-DPSNK0_ML2_P-PadAB11)") (pinfunction "DPSNK0_ML2_P") (pintype "input+no_connect"))
    (pad "AB12" smd circle (at 0 4.6 270) (size 0.254 0.254) (layers "F.Cu" "F.Paste" "F.Mask")
      (net 1 "GND") (pinfunction "VSS_ANA") (pintype "passive"))
    (pad "AB13" smd circle (at 0.46 4.6 270) (size 0.254 0.254) (layers "F.Cu" "F.Paste" "F.Mask")
      (net 228 "unconnected-(U4C-DPSNK0_ML3_P-PadAB13)") (pinfunction "DPSNK0_ML3_P") (pintype "input+no_connect"))
    (pad "AB14" smd circle (at 0.92 4.6 270) (size 0.254 0.254) (layers "F.Cu" "F.Paste" "F.Mask")
      (net 1 "GND") (pinfunction "VSS_ANA") (pintype "passive"))
    (pad "AB15" smd circle (at 1.38 4.6 270) (size 0.254 0.254) (layers "F.Cu" "F.Paste" "F.Mask")
      (net 229 "unconnected-(U4C-DPSNK1_ML0_P-PadAB15)") (pinfunction "DPSNK1_ML0_P") (pintype "input+no_connect"))
    (pad "AB16" smd circle (at 1.84 4.6 270) (size 0.254 0.254) (layers "F.Cu" "F.Paste" "F.Mask")
      (net 1 "GND") (pinfunction "VSS_ANA") (pintype "passive"))
    (pad "AB17" smd circle (at 2.3 4.6 270) (size 0.254 0.254) (layers "F.Cu" "F.Paste" "F.Mask")
      (net 230 "unconnected-(U4C-DPSNK1_ML1_P-PadAB17)") (pinfunction "DPSNK1_ML1_P") (pintype "input+no_connect"))
    (pad "AB18" smd circle (at 2.76 4.6 270) (size 0.254 0.254) (layers "F.Cu" "F.Paste" "F.Mask")
      (net 1 "GND") (pinfunction "VSS_ANA") (pintype "passive"))
    (pad "AB19" smd circle (at 3.22 4.6 270) (size 0.254 0.254) (layers "F.Cu" "F.Paste" "F.Mask")
      (net 231 "unconnected-(U4C-DPSNK1_ML2_P-PadAB19)") (pinfunction "DPSNK1_ML2_P") (pintype "input+no_connect"))
    (pad "AB20" smd circle (at 3.68 4.6 270) (size 0.254 0.254) (layers "F.Cu" "F.Paste" "F.Mask")
      (net 1 "GND") (pinfunction "VSS_ANA") (pintype "passive"))
    (pad "AB21" smd circle (at 4.14 4.6 270) (size 0.254 0.254) (layers "F.Cu" "F.Paste" "F.Mask")
      (net 232 "unconnected-(U4C-DPSNK1_ML3_P-PadAB21)") (pinfunction "DPSNK1_ML3_P") (pintype "input+no_connect"))
    (pad "AB22" smd circle (at 4.6 4.6 270) (size 0.254 0.254) (layers "F.Cu" "F.Paste" "F.Mask")
      (net 1 "GND") (pinfunction "VSS_ANA") (pintype "passive"))
    (pad "AB23" smd oval (at 5.06 4.6) (size 0.1578 0.3302) (layers "F.Cu" "F.Paste" "F.Mask")
      (net 233 "unconnected-(U4F-THERMDA2-PadAB23)") (pinfunction "THERMDA2") (pintype "passive+no_connect"))
    (pad "AC1" smd circle (at -5.06 5.06 270) (size 0.254 0.254) (layers "F.Cu" "F.Paste" "F.Mask")
      (net 1 "GND") (pinfunction "TEST_EDM") (pintype "passive"))
    (pad "AC2" smd oval (at -4.6 5.06 270) (size 0.1578 0.3302) (layers "F.Cu" "F.Paste" "F.Mask")
      (net 1 "GND") (pinfunction "VSS") (pintype "passive"))
    (pad "AC3" smd oval (at -4.14 5.06 270) (size 0.1578 0.3302) (layers "F.Cu" "F.Paste" "F.Mask")
      (net 65 "SPI_CS") (pinfunction "EE_CS_N") (pintype "output"))
    (pad "AC4" smd oval (at -3.68 5.06 270) (size 0.1578 0.3302) (layers "F.Cu" "F.Paste" "F.Mask")
      (net 63 "SPI_MISO") (pinfunction "EE_D0") (pintype "input"))
    (pad "AC5" smd oval (at -3.22 5.06 270) (size 0.1578 0.3302) (layers "F.Cu" "F.Paste" "F.Mask")
      (net 170 "Net-(U4B-PCIE_CLKREQ_N)") (pinfunction "PCIE_CLKREQ_N") (pintype "output"))
    (pad "AC6" smd oval (at -2.76 5.06 270) (size 0.1578 0.3302) (layers "F.Cu" "F.Paste" "F.Mask")
      (net 1 "GND") (pinfunction "VSS_ANA") (pintype "passive"))
    (pad "AC7" smd oval (at -2.3 5.06 270) (size 0.1578 0.3302) (layers "F.Cu" "F.Paste" "F.Mask")
      (net 234 "unconnected-(U4C-DPSNK0_ML0_N-PadAC7)") (pinfunction "DPSNK0_ML0_N") (pintype "input+no_connect"))
    (pad "AC8" smd oval (at -1.84 5.06 270) (size 0.1578 0.3302) (layers "F.Cu" "F.Paste" "F.Mask")
      (net 1 "GND") (pinfunction "VSS_ANA") (pintype "passive"))
    (pad "AC9" smd oval (at -1.38 5.06 270) (size 0.1578 0.3302) (layers "F.Cu" "F.Paste" "F.Mask")
      (net 235 "unconnected-(U4C-DPSNK0_ML1_N-PadAC9)") (pinfunction "DPSNK0_ML1_N") (pintype "input+no_connect"))
    (pad "AC10" smd oval (at -0.92 5.06 270) (size 0.1578 0.3302) (layers "F.Cu" "F.Paste" "F.Mask")
      (net 1 "GND") (pinfunction "VSS_ANA") (pintype "passive"))
    (pad "AC11" smd oval (at -0.46 5.06 270) (size 0.1578 0.3302) (layers "F.Cu" "F.Paste" "F.Mask")
      (net 236 "unconnected-(U4C-DPSNK0_ML2_N-PadAC11)") (pinfunction "DPSNK0_ML2_N") (pintype "input+no_connect"))
    (pad "AC12" smd oval (at 0 5.06 270) (size 0.1578 0.3302) (layers "F.Cu" "F.Paste" "F.Mask")
      (net 1 "GND") (pinfunction "VSS_ANA") (pintype "passive"))
    (pad "AC13" smd oval (at 0.46 5.06 270) (size 0.1578 0.3302) (layers "F.Cu" "F.Paste" "F.Mask")
      (net 237 "unconnected-(U4C-DPSNK0_ML3_N-PadAC13)") (pinfunction "DPSNK0_ML3_N") (pintype "input+no_connect"))
    (pad "AC14" smd oval (at 0.92 5.06 270) (size 0.1578 0.3302) (layers "F.Cu" "F.Paste" "F.Mask")
      (net 1 "GND") (pinfunction "VSS_ANA") (pintype "passive"))
    (pad "AC15" smd oval (at 1.38 5.06 270) (size 0.1578 0.3302) (layers "F.Cu" "F.Paste" "F.Mask")
      (net 238 "unconnected-(U4C-DPSNK1_ML0_N-PadAC15)") (pinfunction "DPSNK1_ML0_N") (pintype "input+no_connect"))
    (pad "AC16" smd oval (at 1.84 5.06 270) (size 0.1578 0.3302) (layers "F.Cu" "F.Paste" "F.Mask")
      (net 1 "GND") (pinfunction "VSS_ANA") (pintype "passive"))
    (pad "AC17" smd oval (at 2.3 5.06 270) (size 0.1578 0.3302) (layers "F.Cu" "F.Paste" "F.Mask")
      (net 239 "unconnected-(U4C-DPSNK1_ML1_N-PadAC17)") (pinfunction "DPSNK1_ML1_N") (pintype "input+no_connect"))
    (pad "AC18" smd oval (at 2.76 5.06 270) (size 0.1578 0.3302) (layers "F.Cu" "F.Paste" "F.Mask")
      (net 1 "GND") (pinfunction "VSS_ANA") (pintype "passive"))
    (pad "AC19" smd oval (at 3.22 5.06 270) (size 0.1578 0.3302) (layers "F.Cu" "F.Paste" "F.Mask")
      (net 240 "unconnected-(U4C-DPSNK1_ML2_N-PadAC19)") (pinfunction "DPSNK1_ML2_N") (pintype "input+no_connect"))
    (pad "AC20" smd oval (at 3.68 5.06 270) (size 0.1578 0.3302) (layers "F.Cu" "F.Paste" "F.Mask")
      (net 1 "GND") (pinfunction "VSS_ANA") (pintype "passive"))
    (pad "AC21" smd oval (at 4.14 5.06 270) (size 0.1578 0.3302) (layers "F.Cu" "F.Paste" "F.Mask")
      (net 241 "unconnected-(U4C-DPSNK1_ML3_N-PadAC21)") (pinfunction "DPSNK1_ML3_N") (pintype "input+no_connect"))
    (pad "AC22" smd oval (at 4.6 5.06 270) (size 0.1578 0.3302) (layers "F.Cu" "F.Paste" "F.Mask")
      (net 1 "GND") (pinfunction "VSS_ANA") (pintype "passive"))
    (pad "AC23" smd circle (at 5.06 5.06 270) (size 0.254 0.254) (layers "F.Cu" "F.Paste" "F.Mask")
      (net 242 "unconnected-(U4F-THERMDA1-PadAC23)") (pinfunction "THERMDA1") (pintype "passive+no_connect"))
    (pad "B1" smd oval (at -5.06 -4.6) (size 0.1578 0.3302) (layers "F.Cu" "F.Paste" "F.Mask")
      (net 1 "GND") (pinfunction "SVR_VSS") (pintype "passive"))
    (pad "B2" smd circle (at -4.6 -4.6 270) (size 0.254 0.254) (layers "F.Cu" "F.Paste" "F.Mask")
      (net 1 "GND") (pinfunction "SVR_VSS") (pintype "passive"))
    (pad "B3" smd circle (at -4.14 -4.6 270) (size 0.254 0.254) (layers "F.Cu" "F.Paste" "F.Mask")
      (net 2 "3V3_SYS") (pinfunction "VCC3P3_SVR") (pintype "passive"))
    (pad "B4" smd circle (at -3.68 -4.6 270) (size 0.254 0.254) (layers "F.Cu" "F.Paste" "F.Mask")
      (net 185 "Net-(U4E-PB_LSTX)") (pinfunction "PB_LSTX") (pintype "output"))
    (pad "B5" smd circle (at -3.22 -4.6 270) (size 0.254 0.254) (layers "F.Cu" "F.Paste" "F.Mask")
      (net 186 "Net-(U4E-PB_LSRX)") (pinfunction "PB_LSRX") (pintype "input"))
    (pad "B6" smd circle (at -2.76 -4.6 270) (size 0.254 0.254) (layers "F.Cu" "F.Paste" "F.Mask")
      (net 1 "GND") (pinfunction "VSS_ANA") (pintype "passive"))
    (pad "B7" smd circle (at -2.3 -4.6 270) (size 0.254 0.254) (layers "F.Cu" "F.Paste" "F.Mask")
      (net 243 "unconnected-(U4E-PB_RX1_P-PadB7)") (pinfunction "PB_RX1_P") (pintype "input+no_connect"))
    (pad "B8" smd circle (at -1.84 -4.6 270) (size 0.254 0.254) (layers "F.Cu" "F.Paste" "F.Mask")
      (net 1 "GND") (pinfunction "VSS_ANA") (pintype "passive"))
    (pad "B9" smd circle (at -1.38 -4.6 270) (size 0.254 0.254) (layers "F.Cu" "F.Paste" "F.Mask")
      (net 244 "unconnected-(U4E-PB_TX1_N-PadB9)") (pinfunction "PB_TX1_N") (pintype "output+no_connect"))
    (pad "B10" smd circle (at -0.92 -4.6 270) (size 0.254 0.254) (layers "F.Cu" "F.Paste" "F.Mask")
      (net 1 "GND") (pinfunction "VSS_ANA") (pintype "passive"))
    (pad "B11" smd circle (at -0.46 -4.6 270) (size 0.254 0.254) (layers "F.Cu" "F.Paste" "F.Mask")
      (net 245 "unconnected-(U4E-PB_TX0_N-PadB11)") (pinfunction "PB_TX0_N") (pintype "output+no_connect"))
    (pad "B12" smd circle (at 0 -4.6 270) (size 0.254 0.254) (layers "F.Cu" "F.Paste" "F.Mask")
      (net 1 "GND") (pinfunction "VSS_ANA") (pintype "passive"))
    (pad "B13" smd circle (at 0.46 -4.6 270) (size 0.254 0.254) (layers "F.Cu" "F.Paste" "F.Mask")
      (net 246 "unconnected-(U4E-PB_RX0_N-PadB13)") (pinfunction "PB_RX0_N") (pintype "input+no_connect"))
    (pad "B14" smd circle (at 0.92 -4.6 270) (size 0.254 0.254) (layers "F.Cu" "F.Paste" "F.Mask")
      (net 1 "GND") (pinfunction "VSS_ANA") (pintype "passive"))
    (pad "B15" smd circle (at 1.38 -4.6 270) (size 0.254 0.254) (layers "F.Cu" "F.Paste" "F.Mask")
      (net 36 "TB_RX1_N") (pinfunction "PA_RX1_N") (pintype "input"))
    (pad "B16" smd circle (at 1.84 -4.6 270) (size 0.254 0.254) (layers "F.Cu" "F.Paste" "F.Mask")
      (net 1 "GND") (pinfunction "VSS_ANA") (pintype "passive"))
    (pad "B17" smd circle (at 2.3 -4.6 270) (size 0.254 0.254) (layers "F.Cu" "F.Paste" "F.Mask")
      (net 22 "/TB Controller/PA_TX1_N") (pinfunction "PA_TX1_N") (pintype "output"))
    (pad "B18" smd circle (at 2.76 -4.6 270) (size 0.254 0.254) (layers "F.Cu" "F.Paste" "F.Mask")
      (net 1 "GND") (pinfunction "VSS_ANA") (pintype "passive"))
    (pad "B19" smd circle (at 3.22 -4.6 270) (size 0.254 0.254) (layers "F.Cu" "F.Paste" "F.Mask")
      (net 18 "/TB Controller/PA_TX0_N") (pinfunction "PA_TX0_N") (pintype "output"))
    (pad "B20" smd circle (at 3.68 -4.6 270) (size 0.254 0.254) (layers "F.Cu" "F.Paste" "F.Mask")
      (net 1 "GND") (pinfunction "VSS_ANA") (pintype "passive"))
    (pad "B21" smd circle (at 4.14 -4.6 270) (size 0.254 0.254) (layers "F.Cu" "F.Paste" "F.Mask")
      (net 42 "TB_RX0_P") (pinfunction "PA_RX0_P") (pintype "input"))
    (pad "B22" smd circle (at 4.6 -4.6 270) (size 0.254 0.254) (layers "F.Cu" "F.Paste" "F.Mask")
      (net 1 "GND") (pinfunction "VSS_ANA") (pintype "passive"))
    (pad "B23" smd oval (at 5.06 -4.6) (size 0.1578 0.3302) (layers "F.Cu" "F.Paste" "F.Mask")
      (net 247 "unconnected-(U4F-ATEST_N-PadB23)") (pinfunction "ATEST_N") (pintype "passive+no_connect"))
    (pad "C1" smd oval (at -5.06 -4.14) (size 0.1578 0.3302) (layers "F.Cu" "F.Paste" "F.Mask")
      (net 55 "Net-(L3-Pad1)") (pinfunction "SVR_IND") (pintype "power_out"))
    (pad "C2" smd circle (at -4.6 -4.14 270) (size 0.254 0.254) (layers "F.Cu" "F.Paste" "F.Mask")
      (net 55 "Net-(L3-Pad1)") (pinfunction "SVR_IND") (pintype "passive"))
    (pad "C22" smd circle (at 4.6 -4.14 270) (size 0.254 0.254) (layers "F.Cu" "F.Paste" "F.Mask")
      (net 1 "GND") (pinfunction "MONDC_CIO_1") (pintype "passive"))
    (pad "C23" smd oval (at 5.06 -4.14) (size 0.1578 0.3302) (layers "F.Cu" "F.Paste" "F.Mask")
      (net 1 "GND") (pinfunction "MONDC_CIO_0") (pintype "passive"))
    (pad "D1" smd oval (at -5.06 -3.68) (size 0.1578 0.3302) (layers "F.Cu" "F.Paste" "F.Mask")
      (net 55 "Net-(L3-Pad1)") (pinfunction "SVR_IND") (pintype "passive"))
    (pad "D2" smd circle (at -4.6 -3.68 270) (size 0.254 0.254) (layers "F.Cu" "F.Paste" "F.Mask")
      (net 201 "Net-(U4C-POC_GPIO_5)") (pinfunction "POC_GPIO_5") (pintype "bidirectional"))
    (pad "D4" smd circle (at -3.9 -3.9 270) (size 0.254 0.254) (layers "F.Cu" "F.Paste" "F.Mask")
      (net 199 "Net-(U4C-POC_GPIO_2)") (pinfunction "POC_GPIO_2") (pintype "bidirectional"))
    (pad "D5" smd circle (at -3.25 -3.9 270) (size 0.254 0.254) (layers "F.Cu" "F.Paste" "F.Mask")
      (net 1 "GND") (pinfunction "VSS") (pintype "passive"))
    (pad "D6" smd circle (at -2.6 -3.9 270) (size 0.254 0.254) (layers "F.Cu" "F.Paste" "F.Mask")
      (net 1 "GND") (pinfunction "MONDC_SVR") (pintype "passive"))
    (pad "D8" smd circle (at -1.95 -3.9 270) (size 0.254 0.254) (layers "F.Cu" "F.Paste" "F.Mask")
      (net 1 "GND") (pinfunction "VSS_ANA") (pintype "passive"))
    (pad "D9" smd circle (at -1.3 -3.9 270) (size 0.254 0.254) (layers "F.Cu" "F.Paste" "F.Mask")
      (net 1 "GND") (pinfunction "VSS_ANA") (pintype "passive"))
    (pad "D11" smd circle (at -0.65 -3.9 270) (size 0.254 0.254) (layers "F.Cu" "F.Paste" "F.Mask")
      (net 1 "GND") (pinfunction "VSS_ANA") (pintype "passive"))
    (pad "D12" smd circle (at 0 -3.9 270) (size 0.254 0.254) (layers "F.Cu" "F.Paste" "F.Mask")
      (net 1 "GND") (pinfunction "VSS_ANA") (pintype "passive"))
    (pad "D13" smd circle (at 0.65 -3.9 270) (size 0.254 0.254) (layers "F.Cu" "F.Paste" "F.Mask")
      (net 1 "GND") (pinfunction "VSS_ANA") (pintype "passive"))
    (pad "D15" smd circle (at 1.3 -3.9 270) (size 0.254 0.254) (layers "F.Cu" "F.Paste" "F.Mask")
      (net 1 "GND") (pinfunction "VSS_ANA") (pintype "passive"))
    (pad "D16" smd circle (at 1.95 -3.9 270) (size 0.254 0.254) (layers "F.Cu" "F.Paste" "F.Mask")
      (net 1 "GND") (pinfunction "VSS_ANA") (pintype "passive"))
    (pad "D18" smd circle (at 2.6 -3.9 270) (size 0.254 0.254) (layers "F.Cu" "F.Paste" "F.Mask")
      (net 1 "GND") (pinfunction "VSS_ANA") (pintype "passive"))
    (pad "D19" smd circle (at 3.25 -3.9 270) (size 0.254 0.254) (layers "F.Cu" "F.Paste" "F.Mask")
      (net 248 "unconnected-(U4E-PB_USB2_D_N-PadD19)") (pinfunction "PB_USB2_D_N") (pintype "bidirectional+no_connect"))
    (pad "D20" smd circle (at 3.9 -3.9 270) (size 0.254 0.254) (layers "F.Cu" "F.Paste" "F.Mask")
      (net 70 "USB_RP_N") (pinfunction "PA_USB2_D_N") (pintype "bidirectional"))
    (pad "D22" smd circle (at 4.6 -3.68 270) (size 0.254 0.254) (layers "F.Cu" "F.Paste" "F.Mask")
      (net 117 "Net-(U4D-XTAL_25_IN)") (pinfunction "XTAL_25_IN") (pintype "input"))
    (pad "D23" smd oval (at 5.06 -3.68) (size 0.1578 0.3302) (layers "F.Cu" "F.Paste" "F.Mask")
      (net 118 "Net-(U4D-XTAL_25_OUT)") (pinfunction "XTAL_25_OUT") (pintype "input"))
    (pad "E1" smd oval (at -5.06 -3.22) (size 0.1578 0.3302) (layers "F.Cu" "F.Paste" "F.Mask")
      (net 203 "Net-(U4D-TEST_EN)") (pinfunction "TEST_EN") (pintype "input"))
    (pad "E2" smd circle (at -4.6 -3.22 270) (size 0.254 0.254) (layers "F.Cu" "F.Paste" "F.Mask")
      (net 198 "Net-(U4C-POC_GPIO_1)") (pinfunction "POC_GPIO_1") (pintype "bidirectional"))
    (pad "E4" smd circle (at -3.9 -3.25 270) (size 0.254 0.254) (layers "F.Cu" "F.Paste" "F.Mask")
      (net 1 "GND") (pinfunction "VSS") (pintype "passive"))
    (pad "E5" smd circle (at -3.25 -3.25 270) (size 0.254 0.254) (layers "F.Cu" "F.Paste" "F.Mask")
      (net 1 "GND") (pinfunction "VSS") (pintype "passive"))
    (pad "E6" smd circle (at -2.6 -3.25 270) (size 0.254 0.254) (layers "F.Cu" "F.Paste" "F.Mask")
      (net 1 "GND") (pinfunction "VSS") (pintype "passive"))
    (pad "E8" smd circle (at -1.95 -3.25 270) (size 0.254 0.254) (layers "F.Cu" "F.Paste" "F.Mask")
      (net 1 "GND") (pinfunction "VSS_ANA") (pintype "passive"))
    (pad "E9" smd circle (at -1.3 -3.25 270) (size 0.254 0.254) (layers "F.Cu" "F.Paste" "F.Mask")
      (net 1 "GND") (pinfunction "VSS_ANA") (pintype "passive"))
    (pad "E11" smd circle (at -0.65 -3.25 270) (size 0.254 0.254) (layers "F.Cu" "F.Paste" "F.Mask")
      (net 1 "GND") (pinfunction "VSS_ANA") (pintype "passive"))
    (pad "E12" smd circle (at 0 -3.25 270) (size 0.254 0.254) (layers "F.Cu" "F.Paste" "F.Mask")
      (net 112 "Net-(U4A-VCC0P9_SVR_SENSE)") (pinfunction "VCC0P9_SVR_ANA") (pintype "power_in"))
    (pad "E13" smd circle (at 0.65 -3.25 270) (size 0.254 0.254) (layers "F.Cu" "F.Paste" "F.Mask")
      (net 112 "Net-(U4A-VCC0P9_SVR_SENSE)") (pinfunction "VCC0P9_SVR_ANA") (pintype "passive"))
    (pad "E15" smd circle (at 1.3 -3.25 270) (size 0.254 0.254) (layers "F.Cu" "F.Paste" "F.Mask")
      (net 1 "GND") (pinfunction "VSS_ANA") (pintype "passive"))
    (pad "E16" smd circle (at 1.95 -3.25 270) (size 0.254 0.254) (layers "F.Cu" "F.Paste" "F.Mask")
      (net 1 "GND") (pinfunction "VSS_ANA") (pintype "passive"))
    (pad "E18" smd circle (at 2.6 -3.25 270) (size 0.254 0.254) (layers "F.Cu" "F.Paste" "F.Mask")
      (net 249 "unconnected-(U4F-USB2_ATEST-PadE18)") (pinfunction "USB2_ATEST") (pintype "passive+no_connect"))
    (pad "E19" smd circle (at 3.25 -3.25 270) (size 0.254 0.254) (layers "F.Cu" "F.Paste" "F.Mask")
      (net 250 "unconnected-(U4E-PB_USB2_D_P-PadE19)") (pinfunction "PB_USB2_D_P") (pintype "bidirectional+no_connect"))
    (pad "E20" smd circle (at 3.9 -3.25 270) (size 0.254 0.254) (layers "F.Cu" "F.Paste" "F.Mask")
      (net 71 "USB_RP_P") (pinfunction "PA_USB2_D_P") (pintype "bidirectional"))
    (pad "E22" smd circle (at 4.6 -3.22 270) (size 0.254 0.254) (layers "F.Cu" "F.Paste" "F.Mask")
      (net 1 "GND") (pinfunction "VSS_ANA") (pintype "passive"))
    (pad "E23" smd oval (at 5.06 -3.22) (size 0.1578 0.3302) (layers "F.Cu" "F.Paste" "F.Mask")
      (net 1 "GND") (pinfunction "VSS_ANA") (pintype "passive"))
    (pad "F1" smd oval (at -5.06 -2.76) (size 0.1578 0.3302) (layers "F.Cu" "F.Paste" "F.Mask")
      (net 202 "Net-(U4C-POC_GPIO_6)") (pinfunction "POC_GPIO_6") (pintype "bidirectional"))
    (pad "F2" smd circle (at -4.6 -2.76 270) (size 0.254 0.254) (layers "F.Cu" "F.Paste" "F.Mask")
      (net 54 "PCIE_WAKE") (pinfunction "POC_GPIO_4") (pintype "bidirectional"))
    (pad "F4" smd circle (at -3.9 -2.6 270) (size 0.254 0.254) (layers "F.Cu" "F.Paste" "F.Mask")
      (net 62 "RESET_N") (pinfunction "RESET_N") (pintype "input"))
    (pad "F5" smd circle (at -3.25 -2.6 270) (size 0.254 0.254) (layers "F.Cu" "F.Paste" "F.Mask")
      (net 1 "GND") (pinfunction "VSS") (pintype "passive"))
    (pad "F6" smd circle (at -2.6 -2.6 270) (size 0.254 0.254) (layers "F.Cu" "F.Paste" "F.Mask")
      (net 1 "GND") (pinfunction "VSS") (pintype "passive"))
    (pad "F8" smd circle (at -1.95 -2.6 270) (size 0.254 0.254) (layers "F.Cu" "F.Paste" "F.Mask")
      (net 2 "3V3_SYS") (pinfunction "VCC3P3_SX") (pintype "power_in"))
    (pad "F9" smd circle (at -1.3 -2.6 270) (size 0.254 0.254) (layers "F.Cu" "F.Paste" "F.Mask")
      (net 1 "GND") (pinfunction "VSS_ANA") (pintype "passive"))
    (pad "F11" smd circle (at -0.65 -2.6 270) (size 0.254 0.254) (layers "F.Cu" "F.Paste" "F.Mask")
      (net 112 "Net-(U4A-VCC0P9_SVR_SENSE)") (pinfunction "VCC0P9_SVR_ANA") (pintype "passive"))
    (pad "F12" smd circle (at 0 -2.6 270) (size 0.254 0.254) (layers "F.Cu" "F.Paste" "F.Mask")
      (net 112 "Net-(U4A-VCC0P9_SVR_SENSE)") (pinfunction "VCC0P9_SVR_ANA") (pintype "passive"))
    (pad "F13" smd circle (at 0.65 -2.6 270) (size 0.254 0.254) (layers "F.Cu" "F.Paste" "F.Mask")
      (net 112 "Net-(U4A-VCC0P9_SVR_SENSE)") (pinfunction "VCC0P9_SVR_ANA") (pintype "passive"))
    (pad "F15" smd circle (at 1.3 -2.6 270) (size 0.254 0.254) (layers "F.Cu" "F.Paste" "F.Mask")
      (net 112 "Net-(U4A-VCC0P9_SVR_SENSE)") (pinfunction "VCC0P9_SVR_ANA") (pintype "passive"))
    (pad "F16" smd circle (at 1.95 -2.6 270) (size 0.254 0.254) (layers "F.Cu" "F.Paste" "F.Mask")
      (net 1 "GND") (pinfunction "VSS_ANA") (pintype "passive"))
    (pad "F18" smd circle (at 2.6 -2.6 270) (size 0.254 0.254) (layers "F.Cu" "F.Paste" "F.Mask")
      (net 113 "Net-(U4A-VCC0P9_LVR_SENSE)") (pinfunction "VCC0P9_LVR") (pintype "power_in"))
    (pad "F19" smd circle (at 3.25 -2.6 270) (size 0.254 0.254) (layers "F.Cu" "F.Paste" "F.Mask")
      (net 188 "Net-(U4E-PB_USB2_RBIAS)") (pinfunction "PB_USB2_RBIAS") (pintype "passive"))
    (pad "F20" smd circle (at 3.9 -2.6 270) (size 0.254 0.254) (layers "F.Cu" "F.Paste" "F.Mask")
      (net 1 "GND") (pinfunction "VSS_ANA") (pintype "passive"))
    (pad "F22" smd circle (at 4.6 -2.76 270) (size 0.254 0.254) (layers "F.Cu" "F.Paste" "F.Mask")
      (net 79 "/TB Controller/TX3_N") (pinfunction "PCIE_TX3_N") (pintype "input"))
    (pad "F23" smd oval (at 5.06 -2.76) (size 0.1578 0.3302) (layers "F.Cu" "F.Paste" "F.Mask")
      (net 83 "/TB Controller/TX3_P") (pinfunction "PCIE_TX3_P") (pintype "input"))
    (pad "G1" smd oval (at -5.06 -2.3) (size 0.1578 0.3302) (layers "F.Cu" "F.Paste" "F.Mask")
      (net 190 "Net-(U4C-DPSRC_HPD)") (pinfunction "DPSRC_HPD") (pintype "passive"))
    (pad "G2" smd circle (at -4.6 -2.3 270) (size 0.254 0.254) (layers "F.Cu" "F.Paste" "F.Mask")
      (net 187 "Net-(U4E-PB_DPSRC_HPD)") (pinfunction "PB_DPSRC_HPD") (pintype "input"))
    (pad "G22" smd circle (at 4.6 -2.3 270) (size 0.254 0.254) (layers "F.Cu" "F.Paste" "F.Mask")
      (net 1 "GND") (pinfunction "VSS_ANA") (pintype "passive"))
    (pad "G23" smd oval (at 5.06 -2.3) (size 0.1578 0.3302) (layers "F.Cu" "F.Paste" "F.Mask")
      (net 1 "GND") (pinfunction "VSS_ANA") (pintype "passive"))
    (pad "H1" smd oval (at -5.06 -1.84) (size 0.1578 0.3302) (layers "F.Cu" "F.Paste" "F.Mask")
      (net 1 "GND") (pinfunction "VSS_ANA") (pintype "passive"))
    (pad "H2" smd circle (at -4.6 -1.84 270) (size 0.254 0.254) (layers "F.Cu" "F.Paste" "F.Mask")
      (net 1 "GND") (pinfunction "VSS_ANA") (pintype "passive"))
    (pad "H4" smd circle (at -3.9 -1.95 270) (size 0.254 0.254) (layers "F.Cu" "F.Paste" "F.Mask")
      (net 200 "Net-(U4C-POC_GPIO_3)") (pinfunction "POC_GPIO_3") (pintype "bidirectional"))
    (pad "H5" smd circle (at -3.25 -1.95 270) (size 0.254 0.254) (layers "F.Cu" "F.Paste" "F.Mask")
      (net 1 "GND") (pinfunction "VSS") (pintype "passive"))
    (pad "H6" smd circle (at -2.6 -1.95 270) (size 0.254 0.254) (layers "F.Cu" "F.Paste" "F.Mask")
      (net 184 "Net-(U4D-RBIAS)") (pinfunction "RBIAS") (pintype "passive"))
    (pad "H8" smd circle (at -1.95 -1.95 270) (size 0.254 0.254) (layers "F.Cu" "F.Paste" "F.Mask")
      (net 1 "GND") (pinfunction "VSS") (pintype "passive"))
    (pad "H9" smd circle (at -1.3 -1.95 270) (size 0.254 0.254) (layers "F.Cu" "F.Paste" "F.Mask")
      (net 2 "3V3_SYS") (pinfunction "VCC3P3A") (pintype "power_in"))
    (pad "H11" smd circle (at -0.65 -1.95 270) (size 0.254 0.254) (layers "F.Cu" "F.Paste" "F.Mask")
      (net 113 "Net-(U4A-VCC0P9_LVR_SENSE)") (pinfunction "VCC0P9_LVR_SENSE") (pintype "power_in"))
    (pad "H12" smd circle (at 0 -1.95 270) (size 0.254 0.254) (layers "F.Cu" "F.Paste" "F.Mask")
      (net 1 "GND") (pinfunction "VSS_ANA") (pintype "passive"))
    (pad "H13" smd circle (at 0.65 -1.95 270) (size 0.254 0.254) (layers "F.Cu" "F.Paste" "F.Mask")
      (net 1 "GND") (pinfunction "VSS_ANA") (pintype "passive"))
    (pad "H15" smd circle (at 1.3 -1.95 270) (size 0.254 0.254) (layers "F.Cu" "F.Paste" "F.Mask")
      (net 1 "GND") (pinfunction "VSS_ANA") (pintype "passive"))
    (pad "H16" smd circle (at 1.95 -1.95 270) (size 0.254 0.254) (layers "F.Cu" "F.Paste" "F.Mask")
      (net 1 "GND") (pinfunction "VSS_ANA") (pintype "passive"))
    (pad "H18" smd circle (at 2.6 -1.95 270) (size 0.254 0.254) (layers "F.Cu" "F.Paste" "F.Mask")
      (net 113 "Net-(U4A-VCC0P9_LVR_SENSE)") (pinfunction "VCC0P9_LVR") (pintype "passive"))
    (pad "H19" smd circle (at 3.25 -1.95 270) (size 0.254 0.254) (layers "F.Cu" "F.Paste" "F.Mask")
      (net 182 "Net-(U4E-PA_USB2_RBIAS)") (pinfunction "PA_USB2_RBIAS") (pintype "passive"))
    (pad "H20" smd circle (at 3.9 -1.95 270) (size 0.254 0.254) (layers "F.Cu" "F.Paste" "F.Mask")
      (net 1 "GND") (pinfunction "VSS_ANA") (pintype "passive"))
    (pad "H22" smd circle (at 4.6 -1.84 270) (size 0.254 0.254) (layers "F.Cu" "F.Paste" "F.Mask")
      (net 53 "PCIE_RX3_N") (pinfunction "PCIE_RX3_N") (pintype "input"))
    (pad "H23" smd oval (at 5.06 -1.84) (size 0.1578 0.3302) (layers "F.Cu" "F.Paste" "F.Mask")
      (net 52 "PCIE_RX3_P") (pinfunction "PCIE_RX3_P") (pintype "input"))
    (pad "J1" smd oval (at -5.06 -1.38) (size 0.1578 0.3302) (layers "F.Cu" "F.Paste" "F.Mask")
      (net 251 "unconnected-(U4C-DPSRC_ML3_N-PadJ1)") (pinfunction "DPSRC_ML3_N") (pintype "output+no_connect"))
    (pad "J2" smd circle (at -4.6 -1.38 270) (size 0.254 0.254) (layers "F.Cu" "F.Paste" "F.Mask")
      (net 252 "unconnected-(U4C-DPSRC_ML3_P-PadJ2)") (pinfunction "DPSRC_ML3_P") (pintype "output+no_connect"))
    (pad "J4" smd circle (at -3.9 -1.3 270) (size 0.254 0.254) (layers "F.Cu" "F.Paste" "F.Mask")
      (net 56 "I2C1_IRQ") (pinfunction "POC_GPIO_0") (pintype "bidirectional"))
    (pad "J5" smd circle (at -3.25 -1.3 270) (size 0.254 0.254) (layers "F.Cu" "F.Paste" "F.Mask")
      (net 1 "GND") (pinfunction "VSS_ANA") (pintype "passive"))
    (pad "J6" smd circle (at -2.6 -1.3 270) (size 0.254 0.254) (layers "F.Cu" "F.Paste" "F.Mask")
      (net 183 "Net-(U4D-RSENSE)") (pinfunction "RSENSE") (pintype "passive"))
    (pad "J8" smd circle (at -1.95 -1.3 270) (size 0.254 0.254) (layers "F.Cu" "F.Paste" "F.Mask")
      (net 1 "GND") (pinfunction "VSS") (pintype "passive"))
    (pad "J9" smd circle (at -1.3 -1.3 270) (size 0.254 0.254) (layers "F.Cu" "F.Paste" "F.Mask")
      (net 112 "Net-(U4A-VCC0P9_SVR_SENSE)") (pinfunction "VCC0P9_SVR_SENSE") (pintype "power_in"))
    (pad "J11" smd circle (at -0.65 -1.3 270) (size 0.254 0.254) (layers "F.Cu" "F.Paste" "F.Mask")
      (net 113 "Net-(U4A-VCC0P9_LVR_SENSE)") (pinfunction "VCC0P9_LVR") (pintype "passive"))
    (pad "J12" smd circle (at 0 -1.3 270) (size 0.254 0.254) (layers "F.Cu" "F.Paste" "F.Mask")
      (net 1 "GND") (pinfunction "VSS") (pintype "passive"))
    (pad "J13" smd circle (at 0.65 -1.3 270) (size 0.254 0.254) (layers "F.Cu" "F.Paste" "F.Mask")
      (net 1 "GND") (pinfunction "VSS") (pintype "passive"))
    (pad "J15" smd circle (at 1.3 -1.3 270) (size 0.254 0.254) (layers "F.Cu" "F.Paste" "F.Mask")
      (net 1 "GND") (pinfunction "VSS") (pintype "passive"))
    (pad "J16" smd circle (at 1.95 -1.3 270) (size 0.254 0.254) (layers "F.Cu" "F.Paste" "F.Mask")
      (net 110 "Net-(U4A-VCC3P3_ANA_USB2)") (pinfunction "VCC3P3_ANA_USB2") (pintype "power_in"))
    (pad "J18" smd circle (at 2.6 -1.3 270) (size 0.254 0.254) (layers "F.Cu" "F.Paste" "F.Mask")
      (net 1 "GND") (pinfunction "VSS_ANA") (pintype "passive"))
    (pad "J19" smd circle (at 3.25 -1.3 270) (size 0.254 0.254) (layers "F.Cu" "F.Paste" "F.Mask")
      (net 1 "GND") (pinfunction "VSS_ANA") (pintype "passive"))
    (pad "J20" smd circle (at 3.9 -1.3 270) (size 0.254 0.254) (layers "F.Cu" "F.Paste" "F.Mask")
      (net 1 "GND") (pinfunction "VSS_ANA") (pintype "passive"))
    (pad "J22" smd circle (at 4.6 -1.38 270) (size 0.254 0.254) (layers "F.Cu" "F.Paste" "F.Mask")
      (net 1 "GND") (pinfunction "VSS_ANA") (pintype "passive"))
    (pad "J23" smd oval (at 5.06 -1.38) (size 0.1578 0.3302) (layers "F.Cu" "F.Paste" "F.Mask")
      (net 1 "GND") (pinfunction "VSS_ANA") (pintype "passive"))
    (pad "K1" smd oval (at -5.06 -0.92) (size 0.1578 0.3302) (layers "F.Cu" "F.Paste" "F.Mask")
      (net 1 "GND") (pinfunction "VSS_ANA") (pintype "passive"))
    (pad "K2" smd circle (at -4.6 -0.92 270) (size 0.254 0.254) (layers "F.Cu" "F.Paste" "F.Mask")
      (net 1 "GND") (pinfunction "VSS_ANA") (pintype "passive"))
    (pad "K22" smd circle (at 4.6 -0.92 270) (size 0.254 0.254) (layers "F.Cu" "F.Paste" "F.Mask")
      (net 78 "/TB Controller/TX2_N") (pinfunction "PCIE_TX2_N") (pintype "input"))
    (pad "K23" smd oval (at 5.06 -0.92) (size 0.1578 0.3302) (layers "F.Cu" "F.Paste" "F.Mask")
      (net 82 "/TB Controller/TX2_P") (pinfunction "PCIE_TX2_P") (pintype "input"))
    (pad "L1" smd oval (at -5.06 -0.46) (size 0.1578 0.3302) (layers "F.Cu" "F.Paste" "F.Mask")
      (net 253 "unconnected-(U4C-DPSRC_ML2_N-PadL1)") (pinfunction "DPSRC_ML2_N") (pintype "output+no_connect"))
    (pad "L2" smd circle (at -4.6 -0.46 270) (size 0.254 0.254) (layers "F.Cu" "F.Paste" "F.Mask")
      (net 254 "unconnected-(U4C-DPSRC_ML2_P-PadL2)") (pinfunction "DPSRC_ML2_P") (pintype "output+no_connect"))
    (pad "L4" smd circle (at -3.9 -0.65 270) (size 0.254 0.254) (layers "F.Cu" "F.Paste" "F.Mask")
      (net 43 "PCIE_PWRGD") (pinfunction "PERST_N") (pintype "input"))
    (pad "L5" smd circle (at -3.25 -0.65 270) (size 0.254 0.254) (layers "F.Cu" "F.Paste" "F.Mask")
      (net 1 "GND") (pinfunction "VSS_ANA") (pintype "passive"))
    (pad "L6" smd circle (at -2.6 -0.65 270) (size 0.254 0.254) (layers "F.Cu" "F.Paste" "F.Mask")
      (net 106 "Net-(C53-Pad2)") (pinfunction "VCC0P9_ANA_DPSRC") (pintype "power_in"))
    (pad "L8" smd circle (at -1.95 -0.65 270) (size 0.254 0.254) (layers "F.Cu" "F.Paste" "F.Mask")
      (net 106 "Net-(C53-Pad2)") (pinfunction "VCC0P9_DP") (pintype "passive"))
    (pad "L9" smd circle (at -1.3 -0.65 270) (size 0.254 0.254) (layers "F.Cu" "F.Paste" "F.Mask")
      (net 112 "Net-(U4A-VCC0P9_SVR_SENSE)") (pinfunction "VCC0P9_SVR") (pintype "power_in"))
    (pad "L11" smd circle (at -0.65 -0.65 270) (size 0.254 0.254) (layers "F.Cu" "F.Paste" "F.Mask")
      (net 106 "Net-(C53-Pad2)") (pinfunction "VCC0P9_DP") (pintype "power_in"))
    (pad "L12" smd circle (at 0 -0.65 270) (size 0.254 0.254) (layers "F.Cu" "F.Paste" "F.Mask")
      (net 106 "Net-(C53-Pad2)") (pinfunction "VCC0P9_DP") (pintype "passive"))
    (pad "L13" smd circle (at 0.65 -0.65 270) (size 0.254 0.254) (layers "F.Cu" "F.Paste" "F.Mask")
      (net 1 "GND") (pinfunction "VSS") (pintype "passive"))
    (pad "L15" smd circle (at 1.3 -0.65 270) (size 0.254 0.254) (layers "F.Cu" "F.Paste" "F.Mask")
      (net 1 "GND") (pinfunction "FUSE_VQPS_64") (pintype "passive"))
    (pad "L16" smd circle (at 1.95 -0.65 270) (size 0.254 0.254) (layers "F.Cu" "F.Paste" "F.Mask")
      (net 109 "Net-(U4A-VCC3P3_ANA_PCIE)") (pinfunction "VCC3P3_ANA_PCIE") (pintype "power_in"))
    (pad "L18" smd circle (at 2.6 -0.65 270) (size 0.254 0.254) (layers "F.Cu" "F.Paste" "F.Mask")
      (net 108 "Net-(C56-Pad2)") (pinfunction "VCC0P9_ANA_PCIE_2") (pintype "power_in"))
    (pad "L19" smd circle (at 3.25 -0.65 270) (size 0.254 0.254) (layers "F.Cu" "F.Paste" "F.Mask")
      (net 108 "Net-(C56-Pad2)") (pinfunction "VCC0P9_ANA_PCIE_1") (pintype "power_in"))
    (pad "L20" smd circle (at 3.9 -0.65 270) (size 0.254 0.254) (layers "F.Cu" "F.Paste" "F.Mask")
      (net 1 "GND") (pinfunction "VSS_ANA") (pintype "passive"))
    (pad "L22" smd circle (at 4.6 -0.46 270) (size 0.254 0.254) (layers "F.Cu" "F.Paste" "F.Mask")
      (net 1 "GND") (pinfunction "VSS_ANA") (pintype "passive"))
    (pad "L23" smd oval (at 5.06 -0.46) (size 0.1578 0.3302) (layers "F.Cu" "F.Paste" "F.Mask")
      (net 1 "GND") (pinfunction "VSS_ANA") (pintype "passive"))
    (pad "M1" smd oval (at -5.06 0) (size 0.1578 0.3302) (layers "F.Cu" "F.Paste" "F.Mask")
      (net 1 "GND") (pinfunction "VSS_ANA") (pintype "passive"))
    (pad "M2" smd circle (at -4.6 0 270) (size 0.254 0.254) (layers "F.Cu" "F.Paste" "F.Mask")
      (net 1 "GND") (pinfunction "VSS_ANA") (pintype "passive"))
    (pad "M4" smd circle (at -3.9 0 270) (size 0.254 0.254) (layers "F.Cu" "F.Paste" "F.Mask")
      (net 58 "HPD") (pinfunction "PA_DPSRC_HPD") (pintype "input"))
    (pad "M5" smd circle (at -3.25 0 270) (size 0.254 0.254) (layers "F.Cu" "F.Paste" "F.Mask")
      (net 1 "GND") (pinfunction "VSS_ANA") (pintype "passive"))
    (pad "M6" smd circle (at -2.6 0 270) (size 0.254 0.254) (layers "F.Cu" "F.Paste" "F.Mask")
      (net 106 "Net-(C53-Pad2)") (pinfunction "VCC0P9_ANA_DPSRC") (pintype "passive"))
    (pad "M8" smd circle (at -1.95 0 270) (size 0.254 0.254) (layers "F.Cu" "F.Paste" "F.Mask")
      (net 106 "Net-(C53-Pad2)") (pinfunction "VCC0P9_DP") (pintype "passive"))
    (pad "M9" smd circle (at -1.3 0 270) (size 0.254 0.254) (layers "F.Cu" "F.Paste" "F.Mask")
      (net 112 "Net-(U4A-VCC0P9_SVR_SENSE)") (pinfunction "VCC0P9_SVR") (pintype "passive"))
    (pad "M11" smd circle (at -0.65 0 270) (size 0.254 0.254) (layers "F.Cu" "F.Paste" "F.Mask")
      (net 1 "GND") (pinfunction "VSS") (pintype "passive"))
    (pad "M12" smd circle (at 0 0 270) (size 0.254 0.254) (layers "F.Cu" "F.Paste" "F.Mask")
      (net 1 "GND") (pinfunction "VSS") (pintype "passive"))
    (pad "M13" smd circle (at 0.65 0 270) (size 0.254 0.254) (layers "F.Cu" "F.Paste" "F.Mask")
      (net 108 "Net-(C56-Pad2)") (pinfunction "VCC0P9_PCIE") (pintype "power_in"))
    (pad "M15" smd circle (at 1.3 0 270) (size 0.254 0.254) (layers "F.Cu" "F.Paste" "F.Mask")
      (net 108 "Net-(C56-Pad2)") (pinfunction "VCC0P9_PCIE") (pintype "passive"))
    (pad "M16" smd circle (at 1.95 0 270) (size 0.254 0.254) (layers "F.Cu" "F.Paste" "F.Mask")
      (net 108 "Net-(C56-Pad2)") (pinfunction "VCC0P9_PCIE") (pintype "passive"))
    (pad "M18" smd circle (at 2.6 0 270) (size 0.254 0.254) (layers "F.Cu" "F.Paste" "F.Mask")
      (net 108 "Net-(C56-Pad2)") (pinfunction "VCC0P9_ANA_PCIE_2") (pintype "passive"))
    (pad "M19" smd circle (at 3.25 0 270) (size 0.254 0.254) (layers "F.Cu" "F.Paste" "F.Mask")
      (net 1 "GND") (pinfunction "VSS_ANA") (pintype "passive"))
    (pad "M20" smd circle (at 3.9 0 270) (size 0.254 0.254) (layers "F.Cu" "F.Paste" "F.Mask")
      (net 1 "GND") (pinfunction "VSS_ANA") (pintype "passive"))
    (pad "M22" smd circle (at 4.6 0 270) (size 0.254 0.254) (layers "F.Cu" "F.Paste" "F.Mask")
      (net 51 "PCIE_RX2_N") (pinfunction "PCIE_RX2_N") (pintype "input"))
    (pad "M23" smd oval (at 5.06 0) (size 0.1578 0.3302) (layers "F.Cu" "F.Paste" "F.Mask")
      (net 50 "PCIE_RX2_P") (pinfunction "PCIE_RX2_P") (pintype "input"))
    (pad "N1" smd oval (at -5.06 0.46) (size 0.1578 0.3302) (layers "F.Cu" "F.Paste" "F.Mask")
      (net 255 "unconnected-(U4C-DPSRC_ML1_N-PadN1)") (pinfunction "DPSRC_ML1_N") (pintype "output+no_connect"))
    (pad "N2" smd circle (at -4.6 0.46 270) (size 0.254 0.254) (layers "F.Cu" "F.Paste" "F.Mask")
      (net 256 "unconnected-(U4C-DPSRC_ML1_P-PadN2)") (pinfunction "DPSRC_ML1_P") (pintype "output+no_connect"))
    (pad "N4" smd circle (at -3.9 0.65 270) (size 0.254 0.254) (layers "F.Cu" "F.Paste" "F.Mask")
      (net 176 "Net-(U4C-DPSNK1_DDC_DATA)") (pinfunction "DPSNK1_DDC_DATA") (pintype "passive"))
    (pad "N5" smd circle (at -3.25 0.65 270) (size 0.254 0.254) (layers "F.Cu" "F.Paste" "F.Mask")
      (net 1 "GND") (pinfunction "VSS_ANA") (pintype "passive"))
    (pad "N6" smd circle (at -2.6 0.65 270) (size 0.254 0.254) (layers "F.Cu" "F.Paste" "F.Mask")
      (net 191 "Net-(U4C-DPSRC_RBIAS)") (pinfunction "DPSRC_RBIAS") (pintype "passive"))
    (pad "N8" smd circle (at -1.95 0.65 270) (size 0.254 0.254) (layers "F.Cu" "F.Paste" "F.Mask")
      (net 1 "GND") (pinfunction "VSS") (pintype "passive"))
    (pad "N9" smd circle (at -1.3 0.65 270) (size 0.254 0.254) (layers "F.Cu" "F.Paste" "F.Mask")
      (net 1 "GND") (pinfunction "VSS") (pintype "passive"))
    (pad "N11" smd circle (at -0.65 0.65 270) (size 0.254 0.254) (layers "F.Cu" "F.Paste" "F.Mask")
      (net 1 "GND") (pinfunction "VSS") (pintype "passive"))
    (pad "N12" smd circle (at 0 0.65 270) (size 0.254 0.254) (layers "F.Cu" "F.Paste" "F.Mask")
      (net 1 "GND") (pinfunction "VSS") (pintype "passive"))
    (pad "N13" smd circle (at 0.65 0.65 270) (size 0.254 0.254) (layers "F.Cu" "F.Paste" "F.Mask")
      (net 1 "GND") (pinfunction "VSS") (pintype "passive"))
    (pad "N15" smd circle (at 1.3 0.65 270) (size 0.254 0.254) (layers "F.Cu" "F.Paste" "F.Mask")
      (net 1 "GND") (pinfunction "FUSE_VQPS_128") (pintype "passive"))
    (pad "N16" smd circle (at 1.95 0.65 270) (size 0.254 0.254) (layers "F.Cu" "F.Paste" "F.Mask")
      (net 189 "Net-(U4B-PCIE_RBIAS)") (pinfunction "PCIE_RBIAS") (pintype "input"))
    (pad "N18" smd circle (at 2.6 0.65 270) (size 0.254 0.254) (layers "F.Cu" "F.Paste" "F.Mask")
      (net 108 "Net-(C56-Pad2)") (pinfunction "VCC0P9_ANA_PCIE_2") (pintype "passive"))
    (pad "N19" smd circle (at 3.25 0.65 270) (size 0.254 0.254) (layers "F.Cu" "F.Paste" "F.Mask")
      (net 108 "Net-(C56-Pad2)") (pinfunction "VCC0P9_ANA_PCIE_1") (pintype "passive"))
    (pad "N20" smd circle (at 3.9 0.65 270) (size 0.254 0.254) (layers "F.Cu" "F.Paste" "F.Mask")
      (net 1 "GND") (pinfunction "VSS_ANA") (pintype "passive"))
    (pad "N22" smd circle (at 4.6 0.46 270) (size 0.254 0.254) (layers "F.Cu" "F.Paste" "F.Mask")
      (net 1 "GND") (pinfunction "VSS_ANA") (pintype "passive"))
    (pad "N23" smd oval (at 5.06 0.46) (size 0.1578 0.3302) (layers "F.Cu" "F.Paste" "F.Mask")
      (net 1 "GND") (pinfunction "VSS_ANA") (pintype "passive"))
    (pad "P1" smd oval (at -5.06 0.92) (size 0.1578 0.3302) (layers "F.Cu" "F.Paste" "F.Mask")
      (net 1 "GND") (pinfunction "VSS_ANA") (pintype "passive"))
    (pad "P2" smd circle (at -4.6 0.92 270) (size 0.254 0.254) (layers "F.Cu" "F.Paste" "F.Mask")
      (net 1 "GND") (pinfunction "VSS_ANA") (pintype "passive"))
    (pad "P22" smd circle (at 4.6 0.92 270) (size 0.254 0.254) (layers "F.Cu" "F.Paste" "F.Mask")
      (net 77 "/TB Controller/TX1_N") (pinfunction "PCIE_TX1_N") (pintype "input"))
    (pad "P23" smd oval (at 5.06 0.92) (size 0.1578 0.3302) (layers "F.Cu" "F.Paste" "F.Mask")
      (net 81 "/TB Controller/TX1_P") (pinfunction "PCIE_TX1_P") (pintype "input"))
    (pad "R1" smd oval (at -5.06 1.38) (size 0.1578 0.3302) (layers "F.Cu" "F.Paste" "F.Mask")
      (net 257 "unconnected-(U4C-DPSRC_ML0_N-PadR1)") (pinfunction "DPSRC_ML0_N") (pintype "output+no_connect"))
    (pad "R2" smd circle (at -4.6 1.38 270) (size 0.254 0.254) (layers "F.Cu" "F.Paste" "F.Mask")
      (net 258 "unconnected-(U4C-DPSRC_ML0_P-PadR2)") (pinfunction "DPSRC_ML0_P") (pintype "output+no_connect"))
    (pad "R4" smd circle (at -3.9 1.3 270) (size 0.254 0.254) (layers "F.Cu" "F.Paste" "F.Mask")
      (net 173 "Net-(U4C-DPSNK0_DDC_DATA)") (pinfunction "DPSNK0_DDC_DATA") (pintype "passive"))
    (pad "R5" smd circle (at -3.25 1.3 270) (size 0.254 0.254) (layers "F.Cu" "F.Paste" "F.Mask")
      (net 1 "GND") (pinfunction "VSS_ANA") (pintype "passive"))
    (pad "R6" smd circle (at -2.6 1.3 270) (size 0.254 0.254) (layers "F.Cu" "F.Paste" "F.Mask")
      (net 111 "Net-(U4A-VCC3P3_LC)") (pinfunction "VCC3P3_LC") (pintype "power_in"))
    (pad "R8" smd circle (at -1.95 1.3 270) (size 0.254 0.254) (layers "F.Cu" "F.Paste" "F.Mask")
      (net 107 "Net-(C54-Pad2)") (pinfunction "VCC0P9_CIO") (pintype "passive"))
    (pad "R9" smd circle (at -1.3 1.3 270) (size 0.254 0.254) (layers "F.Cu" "F.Paste" "F.Mask")
      (net 107 "Net-(C54-Pad2)") (pinfunction "VCC0P9_CIO") (pintype "passive"))
    (pad "R11" smd circle (at -0.65 1.3 270) (size 0.254 0.254) (layers "F.Cu" "F.Paste" "F.Mask")
      (net 107 "Net-(C54-Pad2)") (pinfunction "VCC0P9_CIO") (pintype "power_in"))
    (pad "R12" smd circle (at 0 1.3 270) (size 0.254 0.254) (layers "F.Cu" "F.Paste" "F.Mask")
      (net 107 "Net-(C54-Pad2)") (pinfunction "VCC0P9_CIO") (pintype "passive"))
    (pad "R13" smd circle (at 0.65 1.3 270) (size 0.254 0.254) (layers "F.Cu" "F.Paste" "F.Mask")
      (net 114 "Net-(U4A-VCC3P3_S0)") (pinfunction "VCC3P3_S0") (pintype "power_in"))
    (pad "R15" smd circle (at 1.3 1.3 270) (size 0.254 0.254) (layers "F.Cu" "F.Paste" "F.Mask")
      (net 105 "Net-(C51-Pad2)") (pinfunction "VCC0P9_USB") (pintype "power_in"))
    (pad "R16" smd circle (at 1.95 1.3 270) (size 0.254 0.254) (layers "F.Cu" "F.Paste" "F.Mask")
      (net 105 "Net-(C51-Pad2)") (pinfunction "VCC0P9_USB") (pintype "passive"))
    (pad "R18" smd circle (at 2.6 1.3 270) (size 0.254 0.254) (layers "F.Cu" "F.Paste" "F.Mask")
      (net 1 "GND") (pinfunction "VSS_ANA") (pintype "passive"))
    (pad "R19" smd circle (at 3.25 1.3 270) (size 0.254 0.254) (layers "F.Cu" "F.Paste" "F.Mask")
      (net 1 "GND") (pinfunction "VSS_ANA") (pintype "passive"))
    (pad "R20" smd circle (at 3.9 1.3 270) (size 0.254 0.254) (layers "F.Cu" "F.Paste" "F.Mask")
      (net 1 "GND") (pinfunction "VSS_ANA") (pintype "passive"))
    (pad "R22" smd circle (at 4.6 1.38 270) (size 0.254 0.254) (layers "F.Cu" "F.Paste" "F.Mask")
      (net 1 "GND") (pinfunction "VSS_ANA") (pintype "passive"))
    (pad "R23" smd oval (at 5.06 1.38) (size 0.1578 0.3302) (layers "F.Cu" "F.Paste" "F.Mask")
      (net 1 "GND") (pinfunction "VSS_ANA") (pintype "passive"))
    (pad "T1" smd oval (at -5.06 1.84) (size 0.1578 0.3302) (layers "F.Cu" "F.Paste" "F.Mask")
      (net 1 "GND") (pinfunction "VSS_ANA") (pintype "passive"))
    (pad "T2" smd circle (at -4.6 1.84 270) (size 0.254 0.254) (layers "F.Cu" "F.Paste" "F.Mask")
      (net 1 "GND") (pinfunction "VSS_ANA") (pintype "passive"))
    (pad "T4" smd circle (at -3.9 1.95 270) (size 0.254 0.254) (layers "F.Cu" "F.Paste" "F.Mask")
      (net 180 "Net-(U4D-TCK)") (pinfunction "TCK") (pintype "input"))
    (pad "T5" smd circle (at -3.25 1.95 270) (size 0.254 0.254) (layers "F.Cu" "F.Paste" "F.Mask")
      (net 1 "GND") (pinfunction "VSS_ANA") (pintype "passive"))
    (pad "T6" smd circle (at -2.6 1.95 270) (size 0.254 0.254) (layers "F.Cu" "F.Paste" "F.Mask")
      (net 1 "GND") (pinfunction "VSS") (pintype "passive"))
    (pad "T8" smd circle (at -1.95 1.95 270) (size 0.254 0.254) (layers "F.Cu" "F.Paste" "F.Mask")
      (net 1 "GND") (pinfunction "VSS") (pintype "passive"))
    (pad "T9" smd circle (at -1.3 1.95 270) (size 0.254 0.254) (layers "F.Cu" "F.Paste" "F.Mask")
      (net 1 "GND") (pinfunction "VSS") (pintype "passive"))
    (pad "T11" smd circle (at -0.65 1.95 270) (size 0.254 0.254) (layers "F.Cu" "F.Paste" "F.Mask")
      (net 106 "Net-(C53-Pad2)") (pinfunction "VCC0P9_DP") (pintype "passive"))
    (pad "T12" smd circle (at 0 1.95 270) (size 0.254 0.254) (layers "F.Cu" "F.Paste" "F.Mask")
      (net 106 "Net-(C53-Pad2)") (pinfunction "VCC0P9_DP") (pintype "passive"))
    (pad "T13" smd circle (at 0.65 1.95 270) (size 0.254 0.254) (layers "F.Cu" "F.Paste" "F.Mask")
      (net 1 "GND") (pinfunction "VSS") (pintype "passive"))
    (pad "T15" smd circle (at 1.3 1.95 270) (size 0.254 0.254) (layers "F.Cu" "F.Paste" "F.Mask")
      (net 1 "GND") (pinfunction "VSS") (pintype "passive"))
    (pad "T16" smd circle (at 1.95 1.95 270) (size 0.254 0.254) (layers "F.Cu" "F.Paste" "F.Mask")
      (net 1 "GND") (pinfunction "VSS") (pintype "passive"))
    (pad "T18" smd circle (at 2.6 1.95 270) (size 0.254 0.254) (layers "F.Cu" "F.Paste" "F.Mask")
      (net 1 "GND") (pinfunction "VSS") (pintype "passive"))
    (pad "T19" smd circle (at 3.25 1.95 270) (size 0.254 0.254) (layers "F.Cu" "F.Paste" "F.Mask")
      (net 73 "/TB Controller/PCIE_CLK_JHL_N") (pinfunction "PCIE_REFCLK_100_IN_N") (pintype "input"))
    (pad "T20" smd circle (at 3.9 1.95 270) (size 0.254 0.254) (layers "F.Cu" "F.Paste" "F.Mask")
      (net 1 "GND") (pinfunction "VSS_ANA") (pintype "passive"))
    (pad "T22" smd circle (at 4.6 1.84 270) (size 0.254 0.254) (layers "F.Cu" "F.Paste" "F.Mask")
      (net 49 "PCIE_RX1_N") (pinfunction "PCIE_RX1_N") (pintype "input"))
    (pad "T23" smd oval (at 5.06 1.84) (size 0.1578 0.3302) (layers "F.Cu" "F.Paste" "F.Mask")
      (net 48 "PCIE_RX1_P") (pinfunction "PCIE_RX1_P") (pintype "input"))
    (pad "U1" smd oval (at -5.06 2.3) (size 0.1578 0.3302) (layers "F.Cu" "F.Paste" "F.Mask")
      (net 59 "I2C1_SDA") (pinfunction "GPIO_0") (pintype "bidirectional"))
    (pad "U2" smd circle (at -4.6 2.3 270) (size 0.254 0.254) (layers "F.Cu" "F.Paste" "F.Mask")
      (net 57 "I2C1_SCL") (pinfunction "GPIO_1") (pintype "bidirectional"))
    (pad "U22" smd circle (at 4.6 2.3 270) (size 0.254 0.254) (layers "F.Cu" "F.Paste" "F.Mask")
      (net 1 "GND") (pinfunction "VSS_ANA") (pintype "passive"))
    (pad "U23" smd oval (at 5.06 2.3) (size 0.1578 0.3302) (layers "F.Cu" "F.Paste" "F.Mask")
      (net 1 "GND") (pinfunction "VSS_ANA") (pintype "passive"))
    (pad "V1" smd oval (at -5.06 2.76) (size 0.1578 0.3302) (layers "F.Cu" "F.Paste" "F.Mask")
      (net 64 "/TB Controller/FLASH_WP") (pinfunction "GPIO_2") (pintype "bidirectional"))
    (pad "V2" smd circle (at -4.6 2.76 270) (size 0.254 0.254) (layers "F.Cu" "F.Paste" "F.Mask")
      (net 192 "Net-(U4C-GPIO_3)") (pinfunction "GPIO_3") (pintype "bidirectional"))
    (pad "V4" smd circle (at -3.9 2.6 270) (size 0.254 0.254) (layers "F.Cu" "F.Paste" "F.Mask")
      (net 179 "Net-(U4D-TMS)") (pinfunction "TMS") (pintype "input"))
    (pad "V5" smd circle (at -3.25 2.6 270) (size 0.254 0.254) (layers "F.Cu" "F.Paste" "F.Mask")
      (net 1 "GND") (pinfunction "VSS_ANA") (pintype "passive"))
    (pad "V6" smd circle (at -2.6 2.6 270) (size 0.254 0.254) (layers "F.Cu" "F.Paste" "F.Mask")
      (net 1 "GND") (pinfunction "VSS_ANA") (pintype "passive"))
    (pad "V8" smd circle (at -1.95 2.6 270) (size 0.254 0.254) (layers "F.Cu" "F.Paste" "F.Mask")
      (net 1 "GND") (pinfunction "VSS_ANA") (pintype "passive"))
    (pad "V9" smd circle (at -1.3 2.6 270) (size 0.254 0.254) (layers "F.Cu" "F.Paste" "F.Mask")
      (net 1 "GND") (pinfunction "VSS_ANA") (pintype "passive"))
    (pad "V11" smd circle (at -0.65 2.6 270) (size 0.254 0.254) (layers "F.Cu" "F.Paste" "F.Mask")
      (net 106 "Net-(C53-Pad2)") (pinfunction "VCC0P9_ANA_DPSNK") (pintype "power_in"))
    (pad "V12" smd circle (at 0 2.6 270) (size 0.254 0.254) (layers "F.Cu" "F.Paste" "F.Mask")
      (net 106 "Net-(C53-Pad2)") (pinfunction "VCC0P9_ANA_DPSNK") (pintype "passive"))
    (pad "V13" smd circle (at 0.65 2.6 270) (size 0.254 0.254) (layers "F.Cu" "F.Paste" "F.Mask")
      (net 106 "Net-(C53-Pad2)") (pinfunction "VCC0P9_ANA_DPSNK") (pintype "passive"))
    (pad "V15" smd circle (at 1.3 2.6 270) (size 0.254 0.254) (layers "F.Cu" "F.Paste" "F.Mask")
      (net 1 "GND") (pinfunction "VSS_ANA") (pintype "passive"))
    (pad "V16" smd circle (at 1.95 2.6 270) (size 0.254 0.254) (layers "F.Cu" "F.Paste" "F.Mask")
      (net 1 "GND") (pinfunction "VSS_ANA") (pintype "passive"))
    (pad "V18" smd circle (at 2.6 2.6 270) (size 0.254 0.254) (layers "F.Cu" "F.Paste" "F.Mask")
      (net 259 "unconnected-(U4F-PCIE_ATEST-PadV18)") (pinfunction "PCIE_ATEST") (pintype "passive+no_connect"))
    (pad "V19" smd circle (at 3.25 2.6 270) (size 0.254 0.254) (layers "F.Cu" "F.Paste" "F.Mask")
      (net 72 "/TB Controller/PCIE_CLK_JHL_P") (pinfunction "PCIE_REFCLK_100_IN_P") (pintype "input"))
    (pad "V20" smd circle (at 3.9 2.6 270) (size 0.254 0.254) (layers "F.Cu" "F.Paste" "F.Mask")
      (net 1 "GND") (pinfunction "VSS_ANA") (pintype "passive"))
    (pad "V22" smd circle (at 4.6 2.76 270) (size 0.254 0.254) (layers "F.Cu" "F.Paste" "F.Mask")
      (net 76 "/TB Controller/TX0_N") (pinfunction "PCIE_TX0_N") (pintype "input"))
    (pad "V23" smd oval (at 5.06 2.76) (size 0.1578 0.3302) (layers "F.Cu" "F.Paste" "F.Mask")
      (net 80 "/TB Controller/TX0_P") (pinfunction "PCIE_TX0_P") (pintype "input"))
    (pad "W1" smd oval (at -5.06 3.22) (size 0.1578 0.3302) (layers "F.Cu" "F.Paste" "F.Mask")
      (net 193 "Net-(U4C-GPIO_4)") (pinfunction "GPIO_4") (pintype "bidirectional"))
    (pad "W2" smd circle (at -4.6 3.22 270) (size 0.254 0.254) (layers "F.Cu" "F.Paste" "F.Mask")
      (net 194 "Net-(U4C-GPIO_5)") (pinfunction "GPIO_5") (pintype "bidirectional"))
    (pad "W4" smd circle (at -3.9 3.25 270) (size 0.254 0.254) (layers "F.Cu" "F.Paste" "F.Mask")
      (net 181 "Net-(U4D-TDO)") (pinfunction "TDO") (pintype "output"))
    (pad "W5" smd circle (at -3.25 3.25 270) (size 0.254 0.254) (layers "F.Cu" "F.Paste" "F.Mask")
      (net 1 "GND") (pinfunction "VSS_ANA") (pintype "passive"))
    (pad "W6" smd circle (at -2.6 3.25 270) (size 0.254 0.254) (layers "F.Cu" "F.Paste" "F.Mask")
      (net 1 "GND") (pinfunction "VSS_ANA") (pintype "passive"))
    (pad "W8" smd circle (at -1.95 3.25 270) (size 0.254 0.254) (layers "F.Cu" "F.Paste" "F.Mask")
      (net 1 "GND") (pinfunction "VSS_ANA") (pintype "passive"))
    (pad "W9" smd circle (at -1.3 3.25 270) (size 0.254 0.254) (layers "F.Cu" "F.Paste" "F.Mask")
      (net 1 "GND") (pinfunction "VSS_ANA") (pintype "passive"))
    (pad "W11" smd circle (at -0.65 3.25 270) (size 0.254 0.254) (layers "F.Cu" "F.Paste" "F.Mask")
      (net 260 "unconnected-(U4C-DPSNK0_AUX_N-PadW11)") (pinfunction "DPSNK0_AUX_N") (pintype "bidirectional+no_connect"))
    (pad "W12" smd circle (at 0 3.25 270) (size 0.254 0.254) (layers "F.Cu" "F.Paste" "F.Mask")
      (net 261 "unconnected-(U4C-DPSNK1_AUX_N-PadW12)") (pinfunction "DPSNK1_AUX_N") (pintype "bidirectional+no_connect"))
    (pad "W13" smd circle (at 0.65 3.25 270) (size 0.254 0.254) (layers "F.Cu" "F.Paste" "F.Mask")
      (net 1 "GND") (pinfunction "MONDC_DPSNK_0") (pintype "passive"))
    (pad "W15" smd circle (at 1.3 3.25 270) (size 0.254 0.254) (layers "F.Cu" "F.Paste" "F.Mask")
      (net 87 "/TB Controller/PA_AUX_N") (pinfunction "PA_DPSRC_AUX_N") (pintype "bidirectional"))
    (pad "W16" smd circle (at 1.95 3.25 270) (size 0.254 0.254) (layers "F.Cu" "F.Paste" "F.Mask")
      (net 262 "unconnected-(U4E-PB_DPSRC_AUX_N-PadW16)") (pinfunction "PB_DPSRC_AUX_N") (pintype "bidirectional+no_connect"))
    (pad "W18" smd circle (at 2.6 3.25 270) (size 0.254 0.254) (layers "F.Cu" "F.Paste" "F.Mask")
      (net 1 "GND") (pinfunction "MONDC_DPSNK_1") (pintype "passive"))
    (pad "W19" smd circle (at 3.25 3.25 270) (size 0.254 0.254) (layers "F.Cu" "F.Paste" "F.Mask")
      (net 263 "unconnected-(U4C-DPSRC_AUX_P-PadW19)") (pinfunction "DPSRC_AUX_P") (pintype "bidirectional+no_connect"))
    (pad "W20" smd circle (at 3.9 3.25 270) (size 0.254 0.254) (layers "F.Cu" "F.Paste" "F.Mask")
      (net 1 "GND") (pinfunction "VSS_ANA") (pintype "passive"))
    (pad "W22" smd circle (at 4.6 3.22 270) (size 0.254 0.254) (layers "F.Cu" "F.Paste" "F.Mask")
      (net 1 "GND") (pinfunction "VSS_ANA") (pintype "passive"))
    (pad "W23" smd oval (at 5.06 3.22) (size 0.1578 0.3302) (layers "F.Cu" "F.Paste" "F.Mask")
      (net 1 "GND") (pinfunction "VSS_ANA") (pintype "passive"))
    (pad "Y1" smd oval (at -5.06 3.68) (size 0.1578 0.3302) (layers "F.Cu" "F.Paste" "F.Mask")
      (net 195 "Net-(U4C-GPIO_6)") (pinfunction "GPIO_6") (pintype "bidirectional"))
    (pad "Y2" smd circle (at -4.6 3.68 270) (size 0.254 0.254) (layers "F.Cu" "F.Paste" "F.Mask")
      (net 196 "Net-(U4C-GPIO_7)") (pinfunction "GPIO_7") (pintype "bidirectional"))
    (pad "Y4" smd circle (at -3.9 3.9 270) (size 0.254 0.254) (layers "F.Cu" "F.Paste" "F.Mask")
      (net 178 "Net-(U4D-TDI)") (pinfunction "TDI") (pintype "input"))
    (pad "Y5" smd circle (at -3.25 3.9 270) (size 0.254 0.254) (layers "F.Cu" "F.Paste" "F.Mask")
      (net 172 "Net-(U4C-DPSNK0_DDC_CLK)") (pinfunction "DPSNK0_DDC_CLK") (pintype "passive"))
    (pad "Y6" smd circle (at -2.6 3.9 270) (size 0.254 0.254) (layers "F.Cu" "F.Paste" "F.Mask")
      (net 174 "Net-(U4C-DPSNK1_HPD)") (pinfunction "DPSNK1_HPD") (pintype "passive"))
    (pad "Y8" smd circle (at -1.95 3.9 270) (size 0.254 0.254) (layers "F.Cu" "F.Paste" "F.Mask")
      (net 175 "Net-(U4C-DPSNK1_DDC_CLK)") (pinfunction "DPSNK1_DDC_CLK") (pintype "passive"))
    (pad "Y9" smd circle (at -1.3 3.9 270) (size 0.254 0.254) (layers "F.Cu" "F.Paste" "F.Mask")
      (net 1 "GND") (pinfunction "VSS_ANA") (pintype "passive"))
    (pad "Y11" smd circle (at -0.65 3.9 270) (size 0.254 0.254) (layers "F.Cu" "F.Paste" "F.Mask")
      (net 264 "unconnected-(U4C-DPSNK0_AUXP-PadY11)") (pinfunction "DPSNK0_AUXP") (pintype "bidirectional+no_connect"))
    (pad "Y12" smd circle (at 0 3.9 270) (size 0.254 0.254) (layers "F.Cu" "F.Paste" "F.Mask")
      (net 265 "unconnected-(U4C-DPSNK1_AUXP-PadY12)") (pinfunction "DPSNK1_AUXP") (pintype "bidirectional+no_connect"))
    (pad "Y13" smd circle (at 0.65 3.9 270) (size 0.254 0.254) (layers "F.Cu" "F.Paste" "F.Mask")
      (net 1 "GND") (pinfunction "VSS_ANA") (pintype "passive"))
    (pad "Y15" smd circle (at 1.3 3.9 270) (size 0.254 0.254) (layers "F.Cu" "F.Paste" "F.Mask")
      (net 86 "/TB Controller/PA_AUX_P") (pinfunction "PA_DPSRC_AUX_P") (pintype "bidirectional"))
    (pad "Y16" smd circle (at 1.95 3.9 270) (size 0.254 0.254) (layers "F.Cu" "F.Paste" "F.Mask")
      (net 266 "unconnected-(U4E-PB_DPSRC_AUX_P-PadY16)") (pinfunction "PB_DPSRC_AUX_P") (pintype "bidirectional+no_connect"))
    (pad "Y18" smd circle (at 2.6 3.9 270) (size 0.254 0.254) (layers "F.Cu" "F.Paste" "F.Mask")
      (net 177 "Net-(U4C-DPSNK_RBIAS)") (pinfunction "DPSNK_RBIAS") (pintype "passive"))
    (pad "Y19" smd circle (at 3.25 3.9 270) (size 0.254 0.254) (layers "F.Cu" "F.Paste" "F.Mask")
      (net 267 "unconnected-(U4C-DPSRC_AUX_N-PadY19)") (pinfunction "DPSRC_AUX_N") (pintype "bidirectional+no_connect"))
    (pad "Y20" smd circle (at 3.9 3.9 270) (size 0.254 0.254) (layers "F.Cu" "F.Paste" "F.Mask")
      (net 1 "GND") (pinfunction "VSS_ANA") (pintype "passive"))
    (pad "Y22" smd circle (at 4.6 3.68 270) (size 0.254 0.254) (layers "F.Cu" "F.Paste" "F.Mask")
      (net 47 "PCIE_RX0_N") (pinfunction "PCIE_RX0_N") (pintype "input"))
    (pad "Y23" smd oval (at 5.06 3.68) (size 0.1578 0.3302) (layers "F.Cu" "F.Paste" "F.Mask")
      (net 46 "PCIE_RX0_P") (pinfunction "PCIE_RX0_P") (pintype "input"))
  )

  (footprint "antmicro-footprints:Fiducial_1mm_Mask3mm" (layer "F.Cu")
    (at 161 98)
    (descr "Circular Fiducial, 1.5mm bare copper, 3mm soldermask opening")
    (tags "fiducial")
    (property "Author" "Antmicro")
    (property "License" "Apache-2.0")
    (property "Sheetfile" "thunderbolt-pcie-adapter.kicad_sch")
    (property "Sheetname" "")
    (property "exclude_from_bom" "")
    (property "ki_description" "Fiducial mask")
    (attr through_hole exclude_from_bom)
    (fp_text reference "FID4" (at -1.107 -1.734) (layer "F.SilkS")
        (effects (font (size 0.7 0.7) (thickness 0.15)) (justify left bottom))
    )
    (fp_text value "Fiducial_1mm_Mask3mm" (at 0 2.603) (layer "F.Fab")
        (effects (font (size 0.7 0.7) (thickness 0.15)) (justify left bottom))
    )
    (fp_text user "License: Apache-2.0" (at -1.25 7.003) (layer "F.Fab") hide
        (effects (font (size 0.7 0.7) (thickness 0.15)) (justify left bottom))
    )
    (fp_text user "${REFERENCE}" (at -1.25 4.603) (layer "F.Fab") hide
        (effects (font (size 0.7 0.7) (thickness 0.15)) (justify left bottom))
    )
    (fp_text user "Author: Antmicro" (at -1.25 5.803) (layer "F.Fab") hide
        (effects (font (size 0.7 0.7) (thickness 0.15)) (justify left bottom))
    )
    (fp_circle (center 0 0) (end 1.5 0)
      (stroke (width 0.05) (type solid)) (fill none) (layer "F.CrtYd"))
    (fp_circle (center 0 0) (end 1.5 0)
      (stroke (width 0.15) (type solid)) (fill none) (layer "F.Fab"))
    (pad "" smd circle (at 0 0) (size 1 1) (layers "F.Cu" "F.Mask")
      (solder_mask_margin 1) (clearance 1))
  )

  (footprint "antmicro-footprints:C_0603_1608Metric" (layer "F.Cu")
    (at 114.135001 79.9 -90)
    (descr "Capacitor SMD 0603")
    (tags "capacitor 0603")
    (property "Author" "Antmicro")
    (property "Dielectric" "")
    (property "License" "Apache-2.0")
    (property "MPN" "CL10A226MO7JZNC")
    (property "Manufacturer" "Samsung Electro-Mechanics")
    (property "Sheetfile" "power.kicad_sch")
    (property "Sheetname" "Power")
    (property "Val" "22u")
    (property "Voltage" "16V")
    (property "ki_description" "SMD Multilayer Ceramic Capacitor")
    (property "ki_keywords" "0603, SMT, CAPACITOR, PASSIVE, CERAMIC")
    (attr smd)
    (fp_text reference "C38" (at 1.126 0.597001 -90) (layer "F.SilkS")
        (effects (font (size 0.7 0.7) (thickness 0.15)) (justify left bottom))
    )
    (fp_text value "C_22u_16V_0603" (at -1.42757 1.770288 -90) (layer "F.Fab")
        (effects (font (size 0.7 0.7) (thickness 0.15)) (justify left bottom))
    )
    (fp_text user "${REFERENCE}" (at -1.682 3.895 -90) (layer "F.Fab") hide
        (effects (font (size 0.7 0.7) (thickness 0.15)) (justify left bottom))
    )
    (fp_text user "License: Apache-2.0" (at -1.682 5.895 -90) (layer "F.Fab") hide
        (effects (font (size 0.7 0.7) (thickness 0.15)) (justify left bottom))
    )
    (fp_text user "Author: Antmicro" (at -1.682 4.894 -90) (layer "F.Fab") hide
        (effects (font (size 0.7 0.7) (thickness 0.15)) (justify left bottom))
    )
    (fp_line (start -0.15 -0.4) (end 0.15 -0.4)
      (stroke (width 0.15) (type solid)) (layer "F.SilkS"))
    (fp_line (start -0.15 0.4) (end 0.15 0.4)
      (stroke (width 0.15) (type solid)) (layer "F.SilkS"))
    (fp_rect (start -1.25 -0.65) (end 1.25 0.65)
      (stroke (width 0.05) (type solid)) (fill none) (layer "F.CrtYd"))
    (fp_rect (start -0.8 -0.4) (end 0.8 0.4)
      (stroke (width 0.15) (type solid)) (fill none) (layer "F.Fab"))
    (pad "1" smd roundrect (at -0.7 0 270) (size 0.8 1) (layers "F.Cu" "F.Paste" "F.Mask") (roundrect_rratio 0.2)
      (net 1 "GND") (pintype "passive"))
    (pad "2" smd roundrect (at 0.7 0 270) (size 0.8 1) (layers "F.Cu" "F.Paste" "F.Mask") (roundrect_rratio 0.2)
      (net 75 "Net-(C32-Pad2)") (pintype "passive"))
  )

  (footprint "antmicro-footprints:FB_0805_2012Metric" (layer "F.Cu")
    (at 103.06 74.06 -90)
    (descr "FERRITE BEAD 0805")
    (tags "FERRITE BEAD 0805")
    (property "Author" "Antmicro")
    (property "Current" "")
    (property "License" "Apache-2.0")
    (property "MPN" "BLM21SN300SZ1D")
    (property "Manufacturer" "Murata")
    (property "Sheetfile" "power.kicad_sch")
    (property "Sheetname" "Power")
    (property "Val" "30Z/8.5A")
    (property "ki_description" "Ferrite Bead, 0805 [2012 Metric], 30 ohm, 8.5 A, BLM21SN, 0.004 ohm, ± 10ohm, DC power line")
    (property "ki_keywords" "0805, SMT, FERRITE BEAD, PASSIVE")
    (attr smd)
    (fp_text reference "FB1" (at 0.997 1.079 -90) (layer "F.SilkS")
        (effects (font (size 0.7 0.7) (thickness 0.15)) (justify left bottom))
    )
    (fp_text value "FB_30Z_8.5A_Murata-BLM21SN_0805" (at 0.001 1.801 -90) (layer "F.Fab")
        (effects (font (size 0.7 0.7) (thickness 0.15)) (justify left bottom))
    )
    (fp_text user "${REFERENCE}" (at -1.44 3.801 -90) (layer "F.Fab") hide
        (effects (font (size 0.7 0.7) (thickness 0.15)) (justify left bottom))
    )
    (fp_text user "License: Apache-2.0" (at -1.44 6.201 -90) (layer "F.Fab") hide
        (effects (font (size 0.7 0.7) (thickness 0.15)) (justify left bottom))
    )
    (fp_text user "Author: Antmicro" (at -1.44 5.001 -90) (layer "F.Fab") hide
        (effects (font (size 0.7 0.7) (thickness 0.15)) (justify left bottom))
    )
    (fp_line (start -0.319 0.698) (end 0.281 0.698)
      (stroke (width 0.15) (type solid)) (layer "F.SilkS"))
    (fp_line (start -0.299 -0.698) (end 0.299 -0.698)
      (stroke (width 0.15) (type solid)) (layer "F.SilkS"))
    (fp_rect (start 1.95 -0.9) (end -1.95 0.9)
      (stroke (width 0.05) (type default)) (fill none) (layer "F.CrtYd"))
    (fp_line (start -0.948 -0.681) (end 0.948 -0.681)
      (stroke (width 0.15) (type solid)) (layer "F.Fab"))
    (fp_line (start -0.948 -0.676) (end -0.948 0.676)
      (stroke (width 0.15) (type solid)) (layer "F.Fab"))
    (fp_line (start -0.948 0.681) (end 0.948 0.681)
      (stroke (width 0.15) (type solid)) (layer "F.Fab"))
    (fp_line (start 0.948 -0.676) (end 0.948 0.676)
      (stroke (width 0.15) (type solid)) (layer "F.Fab"))
    (pad "1" smd roundrect (at -1.1 0 270) (size 1.2 1.3) (layers "F.Cu" "F.Paste" "F.Mask") (roundrect_rratio 0.25)
      (net 3 "5V0_USB") (pintype "passive"))
    (pad "2" smd roundrect (at 1.1 0 270) (size 1.2 1.3) (layers "F.Cu" "F.Paste" "F.Mask") (roundrect_rratio 0.25)
      (net 74 "Net-(C10-Pad2)") (pintype "passive"))
  )

  (footprint "antmicro-footprints:SOT-363" (layer "F.Cu")
    (at 118.9475 91.269999 -90)
    (property "Author" "Antmicro")
    (property "License" "Apache-2.0")
    (property "MPN" "DZDH0401DW")
    (property "Manufacturer" "Diodes Incorporated")
    (property "Sheetfile" "power.kicad_sch")
    (property "Sheetname" "Power")
    (property "ki_description" "OR Controller N+1 ORing Controller P-Channel 1:1 SOT-363")
    (property "ki_keywords" "SMT, CONTROLLER, SEMICONDUCTOR, DIODE, PMOS")
    (attr smd)
    (fp_text reference "Q4" (at 0.805001 -2.3375 -90) (layer "F.SilkS")
        (effects (font (size 0.7 0.7) (thickness 0.15)) (justify left bottom))
    )
    (fp_text value "DZDH0401DW" (at 0 2.2 -90) (layer "F.Fab")
        (effects (font (size 0.7 0.7) (thickness 0.15)) (justify left bottom))
    )
    (fp_text user "License: Apache-2.0" (at -1.3 5.2 -90) (layer "F.Fab") hide
        (effects (font (size 0.7 0.7) (thickness 0.15)) (justify left bottom))
    )
    (fp_text user "Author: Antmicro" (at -1.3 6.4 -90) (layer "F.Fab") hide
        (effects (font (size 0.7 0.7) (thickness 0.15)) (justify left bottom))
    )
    (fp_text user "${REFERENCE}" (at -1.3 4 -90) (layer "F.Fab") hide
        (effects (font (size 0.7 0.7) (thickness 0.15)) (justify left bottom))
    )
    (fp_line (start -0.8 1.146) (end -0.8 1.223)
      (stroke (width 0.15) (type solid)) (layer "F.SilkS"))
    (fp_line (start -0.8 1.223) (end 0.803 1.223)
      (stroke (width 0.15) (type solid)) (layer "F.SilkS"))
    (fp_line (start -0.72 -1.153) (end -0.72 -1.228)
      (stroke (width 0.15) (type solid)) (layer "F.SilkS"))
    (fp_line (start 0.803 -1.228) (end -0.72 -1.228)
      (stroke (width 0.15) (type solid)) (layer "F.SilkS"))
    (fp_line (start 0.803 -1.153) (end 0.803 -1.228)
      (stroke (width 0.15) (type solid)) (layer "F.SilkS"))
    (fp_line (start 0.803 1.146) (end 0.803 1.223)
      (stroke (width 0.15) (type solid)) (layer "F.SilkS"))
    (fp_circle (center -0.978102 -1.2) (end -0.928102 -1.2)
      (stroke (width 0.15) (type solid)) (fill solid) (layer "F.SilkS"))
    (fp_rect (start 1.3 -1.3) (end -1.3 1.3)
      (stroke (width 0.05) (type solid)) (fill none) (layer "F.CrtYd"))
    (fp_line (start -0.1 -1.1) (end -0.68 -0.52)
      (stroke (width 0.15) (type solid)) (layer "F.Fab"))
    (fp_rect (start 0.68 1.1) (end -0.68 -1.1)
      (stroke (width 0.15) (type solid)) (fill none) (layer "F.Fab"))
    (pad "1" smd custom (at -0.948 -0.752 180) (size 0.6 0.6) (layers "F.Cu" "F.Paste" "F.Mask")
      (options (clearance outline) (anchor rect))
      (primitives
      ))
    (pad "2" smd rect (at -0.948 -0.002 180) (size 0.4 0.6) (layers "F.Cu" "F.Paste" "F.Mask")
      (net 144 "Net-(Q4-REF)") (pinfunction "REF") (pintype "input"))
    (pad "3" smd custom (at -0.948 0.745 180) (size 0.6 0.6) (layers "F.Cu" "F.Paste" "F.Mask")
      (net 145 "Net-(Q4-BIAS)") (pinfunction "BIAS") (pintype "output")
      (options (clearance outline) (anchor rect))
      (primitives
      ))
    (pad "4" smd custom (at 0.951 0.745 180) (size 0.6 0.6) (layers "F.Cu" "F.Paste" "F.Mask")
      (net 146 "Net-(Q4-S)") (pinfunction "S") (pintype "power_in")
      (options (clearance outline) (anchor rect))
      (primitives
      ))
    (pad "5" smd rect (at 0.951 -0.002 180) (size 0.4 0.6) (layers "F.Cu" "F.Paste" "F.Mask"))
    (pad "6" smd custom (at 0.951 -0.752 180) (size 0.6 0.6) (layers "F.Cu" "F.Paste" "F.Mask")
      (net 60 "12V0_DCDC") (pinfunction "D") (pintype "power_in")
      (options (clearance outline) (anchor rect))
      (primitives
      ))
  )

  (footprint "antmicro-footprints:LED_0603_1608Metric_G" (layer "F.Cu")
    (at 118.9475 89.169999)
    (descr "LED SMD 0603 Green")
    (tags "LED SMD 0603 Green")
    (property "Author" "Antmicro")
    (property "Color" "Green")
    (property "License" "Apache-2.0")
    (property "MPN" "KP-1608CGCK")
    (property "Manufacturer" "Kingbright")
    (property "Sheetfile" "power.kicad_sch")
    (property "Sheetname" "Power")
    (property "ki_description" "LED, Green, SMD, 0603, 20 mA, 2.1 V, 570 nm")
    (property "ki_keywords" "SMT, DIODE, SEMICONDUCTOR, LED")
    (attr smd)
    (fp_text reference "D3" (at 1.1945 0.492001) (layer "F.SilkS")
        (effects (font (size 0.7 0.7) (thickness 0.15)) (justify left bottom))
    )
    (fp_text value "LED_G_0603_KP-1608CGCK" (at -0.001 1.599) (layer "F.Fab")
        (effects (font (size 0.7 0.7) (thickness 0.15)) (justify left bottom))
    )
    (fp_text user "License: Apache-2.0" (at -1.4224 3.599) (layer "F.Fab") hide
        (effects (font (size 0.7 0.7) (thickness 0.15)) (justify left bottom))
    )
    (fp_text user "${REFERENCE}" (at -1.4224 5.999) (layer "F.Fab") hide
        (effects (font (size 0.7 0.7) (thickness 0.15)) (justify left bottom))
    )
    (fp_text user "Author: Antmicro" (at -1.4224 4.799) (layer "F.Fab") hide
        (effects (font (size 0.7 0.7) (thickness 0.15)) (justify left bottom))
    )
    (fp_line (start -1.18 -0.319) (end -1.18 0.321)
      (stroke (width 0.15) (type solid)) (layer "F.SilkS"))
    (fp_line (start -0.094672 0.001008) (end -0.24 0.001008)
      (stroke (width 0.1) (type solid)) (layer "F.SilkS"))
    (fp_line (start -0.094672 0.001008) (end 0.105328 -0.198992)
      (stroke (width 0.1) (type solid)) (layer "F.SilkS"))
    (fp_line (start -0.094672 0.201008) (end -0.094672 -0.198992)
      (stroke (width 0.1) (type solid)) (layer "F.SilkS"))
    (fp_line (start 0.105328 0.001008) (end 0.24 0.001)
      (stroke (width 0.1) (type solid)) (layer "F.SilkS"))
    (fp_line (start 0.105328 0.201008) (end -0.094672 0.001008)
      (stroke (width 0.1) (type solid)) (layer "F.SilkS"))
    (fp_line (start 0.105328 0.201008) (end 0.105328 -0.198992)
      (stroke (width 0.1) (type solid)) (layer "F.SilkS"))
    (fp_line (start 0.22 -0.35) (end -0.22 -0.35)
      (stroke (width 0.15) (type solid)) (layer "F.SilkS"))
    (fp_line (start 0.22 0.35) (end -0.22 0.35)
      (stroke (width 0.15) (type solid)) (layer "F.SilkS"))
    (fp_rect (start 1.25 0.65) (end -1.25 -0.65)
      (stroke (width 0.05) (type solid)) (fill none) (layer "F.CrtYd"))
    (fp_line (start -0.199 -0.202) (end -0.199 0.1)
      (stroke (width 0.15) (type solid)) (layer "F.Fab"))
    (fp_line (start -0.199 0) (end -0.597 0)
      (stroke (width 0.15) (type solid)) (layer "F.Fab"))
    (fp_line (start -0.199 0.2) (end -0.199 0.1)
      (stroke (width 0.15) (type solid)) (layer "F.Fab"))
    (fp_line (start -0.101 0) (end 0.201 0.2)
      (stroke (width 0.15) (type solid)) (layer "F.Fab"))
    (fp_line (start 0.201 -0.202) (end -0.101 0)
      (stroke (width 0.15) (type solid)) (layer "F.Fab"))
    (fp_line (start 0.201 0) (end 0.201 -0.202)
      (stroke (width 0.15) (type solid)) (layer "F.Fab"))
    (fp_line (start 0.201 0.2) (end 0.201 0)
      (stroke (width 0.15) (type solid)) (layer "F.Fab"))
    (fp_line (start 0.599 0) (end 0.201 0)
      (stroke (width 0.15) (type solid)) (layer "F.Fab"))
    (fp_rect (start 0.848 0.4) (end -0.85 -0.402)
      (stroke (width 0.15) (type solid)) (fill none) (layer "F.Fab"))
    (pad "1" smd roundrect (at -0.7 0 180) (size 0.8 1) (layers "F.Cu" "F.Paste" "F.Mask") (roundrect_rratio 0.2)
      (net 121 "Net-(D3-C)") (pinfunction "C") (pintype "passive"))
    (pad "2" smd roundrect (at 0.7 0 180) (size 0.8 1) (layers "F.Cu" "F.Paste" "F.Mask") (roundrect_rratio 0.2)
      (net 60 "12V0_DCDC") (pinfunction "A") (pintype "passive"))
  )

  (footprint "antmicro-footprints:R_0603_1608Metric" (layer "F.Cu")
    (at 163.35 61.97 90)
    (descr "Resistor SMD 0603")
    (tags "resistor SMD 0603")
    (property "Author" "Antmicro")
    (property "Current" "1A")
    (property "License" "Apache-2.0")
    (property "MPN" "CR0603-J/-000ELF")
    (property "Manufacturer" "Bourns")
    (property "Sheetfile" "power.kicad_sch")
    (property "Sheetname" "Power")
    (property "Tolerance" "")
    (property "Val" "0R")
    (property "ki_description" "Zero Ohm Resistor, Jumper, 0603 [1608 Metric], Thick Film, 100 mW, 1 A, Surface Mount Device, CR")
    (property "ki_keywords" "0603, SMT, RESISTOR, PASSIVE")
    (attr smd)
    (fp_text reference "R41" (at -1.022 -0.79 90) (layer "F.SilkS")
        (effects (font (size 0.7 0.7) (thickness 0.15)) (justify left bottom))
    )
    (fp_text value "R_0R_0603" (at 0 1.6 90) (layer "F.Fab")
        (effects (font (size 0.7 0.7) (thickness 0.15)) (justify left bottom))
    )
    (fp_text user "License: Apache-2.0" (at -1.25 5.9 90) (layer "F.Fab") hide
        (effects (font (size 0.7 0.7) (thickness 0.15)) (justify left bottom))
    )
    (fp_text user "Author: Antmicro" (at -1.25 4.9 90) (layer "F.Fab") hide
        (effects (font (size 0.7 0.7) (thickness 0.15)) (justify left bottom))
    )
    (fp_text user "${REFERENCE}" (at -1.25 3.898 90) (layer "F.Fab") hide
        (effects (font (size 0.7 0.7) (thickness 0.15)) (justify left bottom))
    )
    (fp_line (start -0.15 -0.4) (end 0.15 -0.4)
      (stroke (width 0.15) (type solid)) (layer "F.SilkS"))
    (fp_line (start -0.15 0.4) (end 0.15 0.4)
      (stroke (width 0.15) (type solid)) (layer "F.SilkS"))
    (fp_rect (start -1.25 -0.65) (end 1.25 0.65)
      (stroke (width 0.05) (type solid)) (fill none) (layer "F.CrtYd"))
    (fp_rect (start -0.8 -0.4) (end 0.8 0.4)
      (stroke (width 0.15) (type solid)) (fill none) (layer "F.Fab"))
    (pad "1" smd roundrect (at -0.7 0 90) (size 0.8 1) (layers "F.Cu" "F.Paste" "F.Mask") (roundrect_rratio 0.2)
      (net 32 "VBUS") (pintype "passive"))
    (pad "2" smd roundrect (at 0.7 0 90) (size 0.8 1) (layers "F.Cu" "F.Paste" "F.Mask") (roundrect_rratio 0.2)
      (net 3 "5V0_USB") (pintype "passive"))
  )

  (footprint "antmicro-footprints:Resonator_SMD_Abracon_ABM8G_3.2x2.5mm" (layer "F.Cu")
    (at 143.495415 90.001645 -45)
    (property "Author" "Antmicro")
    (property "License" "Apache-2.0")
    (property "MPN" "ABM8G-25.000MHZ-18-D2Y-T3")
    (property "Manufacturer" "Abracon")
    (property "Sheetfile" "tb.kicad_sch")
    (property "Sheetname" "TB Controller")
    (property "Val" "25 MHz")
    (property "ki_description" "Crystal, 25 MHz, SMD, 3.2mm x 2.5mm, 30 ppm, 18 pF, 20 ppm, ABM8G")
    (property "ki_keywords" "SMT, CERAMIC, OSCILLATOR")
    (attr smd)
    (fp_text reference "Y2" (at -2.025903 0.827152 -135) (layer "F.SilkS")
        (effects (font (size 0.7 0.7) (thickness 0.15)) (justify left bottom))
    )
    (fp_text value "Resonator_25MHz_ABM8G" (at -1.75 2.548 -45) (layer "F.Fab")
        (effects (font (size 0.7 0.7) (thickness 0.15)) (justify left bottom))
    )
    (fp_text user "Author: Antmicro" (at -1.75 5 -45) (layer "F.Fab") hide
        (effects (font (size 0.7 0.7) (thickness 0.15)) (justify left bottom))
    )
    (fp_text user "${REFERENCE}" (at -1.75 3.75 -45) (layer "F.Fab") hide
        (effects (font (size 0.7 0.7) (thickness 0.15)) (justify left bottom))
    )
    (fp_text user "License: Apache-2.0" (at -1.75 6.5 -45) (layer "F.Fab") hide
        (effects (font (size 0.7 0.7) (thickness 0.15)) (justify left bottom))
    )
    (fp_line (start -1.6 0.3) (end -1.6 -0.2)
      (stroke (width 0.15) (type solid)) (layer "F.SilkS"))
    (fp_line (start -0.35 -1.25) (end 0.45 -1.25)
      (stroke (width 0.15) (type solid)) (layer "F.SilkS"))
    (fp_line (start -0.35 1.25) (end 0.45 1.25)
      (stroke (width 0.15) (type solid)) (layer "F.SilkS"))
    (fp_line (start 1.6 0.3) (end 1.6 -0.2)
      (stroke (width 0.15) (type solid)) (layer "F.SilkS"))
    (fp_circle (center -1.75 1.5) (end -1.7 1.5)
      (stroke (width 0.15) (type solid)) (fill none) (layer "F.SilkS"))
    (fp_rect (start -1.907 -1.55) (end 2.006 1.649)
      (stroke (width 0.05) (type solid)) (fill none) (layer "F.CrtYd"))
    (pad "1" smd roundrect (at -1.101 0.949 315) (size 1.3 1.1) (layers "F.Cu" "F.Paste" "F.Mask") (roundrect_rratio 0)
      (chamfer_ratio 0.2) (chamfer bottom_left)
      (net 118 "Net-(U4D-XTAL_25_OUT)") (pintype "passive"))
    (pad "2" smd rect (at 1.199 0.949 315) (size 1.3 1.1) (layers "F.Cu" "F.Paste" "F.Mask")
      (net 1 "GND") (pinfunction "SH") (pintype "passive"))
    (pad "3" smd rect (at 1.199 -0.85 315) (size 1.3 1.1) (layers "F.Cu" "F.Paste" "F.Mask")
      (net 117 "Net-(U4D-XTAL_25_IN)") (pintype "passive"))
    (pad "4" smd rect (at -1.101 -0.85 315) (size 1.3 1.1) (layers "F.Cu" "F.Paste" "F.Mask")
      (net 1 "GND") (pinfunction "SH") (pintype "passive"))
  )

  (footprint "antmicro-footprints:TP_SMD_1mm" (layer "F.Cu")
    (at 118.53 86.38)
    (property "Author" "Antmicro")
    (property "License" "Apache-2.0")
    (property "MPN" "")
    (property "Manufacturer" "")
    (property "Sheetfile" "power.kicad_sch")
    (property "Sheetname" "Power")
    (property "exclude_from_bom" "")
    (property "ki_description" "Test point 1mm SMD")
    (property "ki_keywords" "TESTPOINT")
    (attr exclude_from_pos_files exclude_from_bom)
    (fp_text reference "TP8" (at -1.055 -0.731898) (layer "F.SilkS")
        (effects (font (size 0.7 0.7) (thickness 0.15)) (justify left bottom))
    )
    (fp_text value "TP_1mm_SMD" (at 0 1.4) (layer "F.Fab")
        (effects (font (size 0.7 0.7) (thickness 0.15)) (justify left bottom))
    )
    (fp_text user "Author: Antmicro" (at -0.5 4) (layer "F.Fab") hide
        (effects (font (size 0.7 0.7) (thickness 0.15)) (justify left bottom))
    )
    (fp_text user "License: Apache-2.0" (at -0.5 5.2) (layer "F.Fab") hide
        (effects (font (size 0.7 0.7) (thickness 0.15)) (justify left bottom))
    )
    (fp_text user "${REFERENCE}" (at -0.5 2.8) (layer "F.Fab") hide
        (effects (font (size 0.7 0.7) (thickness 0.15)) (justify left bottom))
    )
    (fp_circle (center 0 0) (end 0.6 0)
      (stroke (width 0.05) (type default)) (fill none) (layer "F.CrtYd"))
    (pad "1" smd circle (at 0 0) (size 1 1) (layers "F.Cu" "F.Mask")
      (net 60 "12V0_DCDC") (pinfunction "1") (pintype "passive"))
  )

  (footprint "antmicro-footprints:C_0603_1608Metric" (layer "F.Cu")
    (at 118.560002 79.9 -90)
    (descr "Capacitor SMD 0603")
    (tags "capacitor 0603")
    (property "Author" "Antmicro")
    (property "Dielectric" "")
    (property "License" "Apache-2.0")
    (property "MPN" "CL10A226MO7JZNC")
    (property "Manufacturer" "Samsung Electro-Mechanics")
    (property "Sheetfile" "power.kicad_sch")
    (property "Sheetname" "Power")
    (property "Val" "22u")
    (property "Voltage" "16V")
    (property "ki_description" "SMD Multilayer Ceramic Capacitor")
    (property "ki_keywords" "0603, SMT, CAPACITOR, PASSIVE, CERAMIC")
    (attr smd)
    (fp_text reference "C40" (at -1.16 -0.340998 -90) (layer "F.SilkS")
        (effects (font (size 0.7 0.7) (thickness 0.15)) (justify left bottom))
    )
    (fp_text value "C_22u_16V_0603" (at -1.42757 1.770288 -90) (layer "F.Fab")
        (effects (font (size 0.7 0.7) (thickness 0.15)) (justify left bottom))
    )
    (fp_text user "Author: Antmicro" (at -1.682 4.894 -90) (layer "F.Fab") hide
        (effects (font (size 0.7 0.7) (thickness 0.15)) (justify left bottom))
    )
    (fp_text user "License: Apache-2.0" (at -1.682 5.895 -90) (layer "F.Fab") hide
        (effects (font (size 0.7 0.7) (thickness 0.15)) (justify left bottom))
    )
    (fp_text user "${REFERENCE}" (at -1.682 3.895 -90) (layer "F.Fab") hide
        (effects (font (size 0.7 0.7) (thickness 0.15)) (justify left bottom))
    )
    (fp_line (start -0.15 -0.4) (end 0.15 -0.4)
      (stroke (width 0.15) (type solid)) (layer "F.SilkS"))
    (fp_line (start -0.15 0.4) (end 0.15 0.4)
      (stroke (width 0.15) (type solid)) (layer "F.SilkS"))
    (fp_rect (start -1.25 -0.65) (end 1.25 0.65)
      (stroke (width 0.05) (type solid)) (fill none) (layer "F.CrtYd"))
    (fp_rect (start -0.8 -0.4) (end 0.8 0.4)
      (stroke (width 0.15) (type solid)) (fill none) (layer "F.Fab"))
    (pad "1" smd roundrect (at -0.7 0 270) (size 0.8 1) (layers "F.Cu" "F.Paste" "F.Mask") (roundrect_rratio 0.2)
      (net 1 "GND") (pintype "passive"))
    (pad "2" smd roundrect (at 0.7 0 270) (size 0.8 1) (layers "F.Cu" "F.Paste" "F.Mask") (roundrect_rratio 0.2)
      (net 75 "Net-(C32-Pad2)") (pintype "passive"))
  )

  (footprint "antmicro-footprints:C_0805_2012Metric" (layer "F.Cu")
    (at 103.055 78.0825 -90)
    (descr "Capacitor SMD 0805")
    (tags "capacitor SMD 0805")
    (property "Author" "Antmicro")
    (property "Dielectric" "")
    (property "License" "Apache-2.0")
    (property "MPN" "GRM21BR6YA106KE43L")
    (property "Manufacturer" "Murata")
    (property "Sheetfile" "power.kicad_sch")
    (property "Sheetname" "Power")
    (property "Val" "10u")
    (property "Voltage" "35V")
    (property "ki_description" "SMD Multilayer Ceramic Capacitor, 10 µF, 35 V, 0805 [2012 Metric], ± 10%, X5R, GRM Series")
    (property "ki_keywords" "0805, SMT, CAPACITOR, PASSIVE")
    (attr smd)
    (fp_text reference "C12" (at 1.1655 1.074 -90) (layer "F.SilkS")
        (effects (font (size 0.7 0.7) (thickness 0.15)) (justify left bottom))
    )
    (fp_text value "C_10u_0805_35V" (at -2.055717 1.963152 -90) (layer "F.Fab")
        (effects (font (size 0.7 0.7) (thickness 0.15)) (justify left bottom))
    )
    (fp_text user "${REFERENCE}" (at -1.9 3.947 -90) (layer "F.Fab") hide
        (effects (font (size 0.7 0.7) (thickness 0.15)) (justify left bottom))
    )
    (fp_text user "Author: Antmicro" (at -1.9 5.947 -90) (layer "F.Fab") hide
        (effects (font (size 0.7 0.7) (thickness 0.15)) (justify left bottom))
    )
    (fp_text user "License: Apache-2.0" (at -1.9 4.947 -90) (layer "F.Fab") hide
        (effects (font (size 0.7 0.7) (thickness 0.15)) (justify left bottom))
    )
    (fp_line (start -0.3 -0.7) (end 0.3 -0.7)
      (stroke (width 0.15) (type solid)) (layer "F.SilkS"))
    (fp_line (start -0.3 0.7) (end 0.3 0.7)
      (stroke (width 0.15) (type solid)) (layer "F.SilkS"))
    (fp_rect (start 1.95 -0.9) (end -1.95 0.9)
      (stroke (width 0.05) (type default)) (fill none) (layer "F.CrtYd"))
    (fp_rect (start -0.95 -0.675) (end 0.95 0.675)
      (stroke (width 0.15) (type solid)) (fill none) (layer "F.Fab"))
    (pad "1" smd roundrect (at -1.1 0 270) (size 1.2 1.3) (layers "F.Cu" "F.Paste" "F.Mask") (roundrect_rratio 0.25)
      (net 1 "GND") (pintype "passive"))
    (pad "2" smd roundrect (at 1.1 0 270) (size 1.2 1.3) (layers "F.Cu" "F.Paste" "F.Mask") (roundrect_rratio 0.25)
      (net 74 "Net-(C10-Pad2)") (pintype "passive"))
  )

  (footprint "antmicro-footprints:C_0805_2012Metric" (layer "F.Cu")
    (at 105.991001 65.219 90)
    (descr "Capacitor SMD 0805")
    (tags "capacitor SMD 0805")
    (property "Author" "Antmicro")
    (property "Dielectric" "")
    (property "License" "Apache-2.0")
    (property "MPN" "GRM21BR6YA106KE43L")
    (property "Manufacturer" "Murata")
    (property "Sheetfile" "power.kicad_sch")
    (property "Sheetname" "Power")
    (property "Val" "10u")
    (property "Voltage" "35V")
    (property "ki_description" "SMD Multilayer Ceramic Capacitor, 10 µF, 35 V, 0805 [2012 Metric], ± 10%, X5R, GRM Series")
    (property "ki_keywords" "0805, SMT, CAPACITOR, PASSIVE")
    (attr smd)
    (fp_text reference "C9" (at -0.694 -1.089001 90) (layer "F.SilkS")
        (effects (font (size 0.7 0.7) (thickness 0.15)) (justify left bottom))
    )
    (fp_text value "C_10u_0805_35V" (at -2.055717 1.963152 90) (layer "F.Fab")
        (effects (font (size 0.7 0.7) (thickness 0.15)) (justify left bottom))
    )
    (fp_text user "${REFERENCE}" (at -1.9 3.947 90) (layer "F.Fab") hide
        (effects (font (size 0.7 0.7) (thickness 0.15)) (justify left bottom))
    )
    (fp_text user "License: Apache-2.0" (at -1.9 4.947 90) (layer "F.Fab") hide
        (effects (font (size 0.7 0.7) (thickness 0.15)) (justify left bottom))
    )
    (fp_text user "Author: Antmicro" (at -1.9 5.947 90) (layer "F.Fab") hide
        (effects (font (size 0.7 0.7) (thickness 0.15)) (justify left bottom))
    )
    (fp_line (start -0.3 -0.7) (end 0.3 -0.7)
      (stroke (width 0.15) (type solid)) (layer "F.SilkS"))
    (fp_line (start -0.3 0.7) (end 0.3 0.7)
      (stroke (width 0.15) (type solid)) (layer "F.SilkS"))
    (fp_rect (start 1.95 -0.9) (end -1.95 0.9)
      (stroke (width 0.05) (type default)) (fill none) (layer "F.CrtYd"))
    (fp_rect (start -0.95 -0.675) (end 0.95 0.675)
      (stroke (width 0.15) (type solid)) (fill none) (layer "F.Fab"))
    (pad "1" smd roundrect (at -1.1 0 90) (size 1.2 1.3) (layers "F.Cu" "F.Paste" "F.Mask") (roundrect_rratio 0.25)
      (net 1 "GND") (pintype "passive"))
    (pad "2" smd roundrect (at 1.1 0 90) (size 1.2 1.3) (layers "F.Cu" "F.Paste" "F.Mask") (roundrect_rratio 0.25)
      (net 3 "5V0_USB") (pintype "passive"))
  )

  (footprint "antmicro-footprints:Conn_Molex_Nano-Fit_1x2_1053131102" (layer "F.Cu")
    (at 160.01 88.55 90)
    (property "Author" "Antmicro")
    (property "License" "Apache-2.0")
    (property "MPN" "1053131102")
    (property "Manufacturer" "Molex")
    (property "Sheetfile" "connectors.kicad_sch")
    (property "Sheetname" "Connectors")
    (property "ki_description" "Rectangular connector, header")
    (property "ki_keywords" "CONNECTOR, THT")
    (attr through_hole)
    (fp_text reference "J3" (at 2.444 4.328 180) (layer "F.SilkS")
        (effects (font (size 0.7 0.7) (thickness 0.15)) (justify left bottom))
    )
    (fp_text value "Molex_Nano-Fit_1x2_1053131102" (at 0 13.1 90) (layer "F.Fab")
        (effects (font (size 0.7 0.7) (thickness 0.15)) (justify left bottom))
    )
    (fp_text user "${REFERENCE}" (at -4.221 14.55 90) (layer "F.Fab") hide
        (effects (font (size 0.7 0.7) (thickness 0.15)) (justify left bottom))
    )
    (fp_text user "Author: Antmicro" (at -4.221 15.749 90) (layer "F.Fab") hide
        (effects (font (size 0.7 0.7) (thickness 0.15)) (justify left bottom))
    )
    (fp_text user "License: Apache-2.0" (at -4.221 16.949 90) (layer "F.Fab") hide
        (effects (font (size 0.7 0.7) (thickness 0.15)) (justify left bottom))
    )
    (fp_line (start -4.221 1.918) (end -4.221 10.38)
      (stroke (width 0.15) (type solid)) (layer "F.SilkS"))
    (fp_line (start -4.221 1.918) (end 1.719 1.918)
      (stroke (width 0.15) (type solid)) (layer "F.SilkS"))
    (fp_line (start -4.221 10.38) (end 1.719 10.38)
      (stroke (width 0.15) (type solid)) (layer "F.SilkS"))
    (fp_line (start 0.998 1.199) (end 1.699 1.199)
      (stroke (width 0.15) (type solid)) (layer "F.SilkS"))
    (fp_line (start 1.35 1.55) (end 1.35 0.848)
      (stroke (width 0.15) (type solid)) (layer "F.SilkS"))
    (fp_line (start 1.719 1.918) (end 1.719 10.38)
      (stroke (width 0.15) (type solid)) (layer "F.SilkS"))
    (fp_rect (start -4.721 -1.1) (end 2.219 12.1)
      (stroke (width 0.05) (type solid)) (fill none) (layer "F.CrtYd"))
    (pad "" np_thru_hole circle (at -2.5 7.179 90) (size 1.71 1.71) (drill 1.7) (layers "*.Cu" "*.Mask"))
    (pad "" np_thru_hole circle (at 0 7.179 90) (size 1.71 1.71) (drill 1.7) (layers "*.Cu" "*.Mask"))
    (pad "1" thru_hole circle (at 0 0 90) (size 2 2) (drill 1.3) (layers "*.Cu" "*.Mask")
      (net 61 "12V0_MOLEX") (pintype "input"))
    (pad "2" thru_hole circle (at -2.5 0 90) (size 2 2) (drill 1.3) (layers "*.Cu" "*.Mask")
      (net 1 "GND") (pintype "input"))
  )

  (footprint "antmicro-footprints:C_0603_1608Metric" (layer "F.Cu")
    (at 115.610002 79.9 -90)
    (descr "Capacitor SMD 0603")
    (tags "capacitor 0603")
    (property "Author" "Antmicro")
    (property "Dielectric" "")
    (property "License" "Apache-2.0")
    (property "MPN" "CL10A226MO7JZNC")
    (property "Manufacturer" "Samsung Electro-Mechanics")
    (property "Sheetfile" "power.kicad_sch")
    (property "Sheetname" "Power")
    (property "Val" "22u")
    (property "Voltage" "16V")
    (property "ki_description" "SMD Multilayer Ceramic Capacitor")
    (property "ki_keywords" "0603, SMT, CAPACITOR, PASSIVE, CERAMIC")
    (attr smd)
    (fp_text reference "C43" (at -1.16 -0.340998 -90) (layer "F.SilkS")
        (effects (font (size 0.7 0.7) (thickness 0.15)) (justify left bottom))
    )
    (fp_text value "C_22u_16V_0603" (at -1.42757 1.770288 -90) (layer "F.Fab")
        (effects (font (size 0.7 0.7) (thickness 0.15)) (justify left bottom))
    )
    (fp_text user "${REFERENCE}" (at -1.682 3.895 -90) (layer "F.Fab") hide
        (effects (font (size 0.7 0.7) (thickness 0.15)) (justify left bottom))
    )
    (fp_text user "Author: Antmicro" (at -1.682 4.894 -90) (layer "F.Fab") hide
        (effects (font (size 0.7 0.7) (thickness 0.15)) (justify left bottom))
    )
    (fp_text user "License: Apache-2.0" (at -1.682 5.895 -90) (layer "F.Fab") hide
        (effects (font (size 0.7 0.7) (thickness 0.15)) (justify left bottom))
    )
    (fp_line (start -0.15 -0.4) (end 0.15 -0.4)
      (stroke (width 0.15) (type solid)) (layer "F.SilkS"))
    (fp_line (start -0.15 0.4) (end 0.15 0.4)
      (stroke (width 0.15) (type solid)) (layer "F.SilkS"))
    (fp_rect (start -1.25 -0.65) (end 1.25 0.65)
      (stroke (width 0.05) (type solid)) (fill none) (layer "F.CrtYd"))
    (fp_rect (start -0.8 -0.4) (end 0.8 0.4)
      (stroke (width 0.15) (type solid)) (fill none) (layer "F.Fab"))
    (pad "1" smd roundrect (at -0.7 0 270) (size 0.8 1) (layers "F.Cu" "F.Paste" "F.Mask") (roundrect_rratio 0.2)
      (net 1 "GND") (pintype "passive"))
    (pad "2" smd roundrect (at 0.7 0 270) (size 0.8 1) (layers "F.Cu" "F.Paste" "F.Mask") (roundrect_rratio 0.2)
      (net 75 "Net-(C32-Pad2)") (pintype "passive"))
  )

  (footprint "antmicro-footprints:LED_0603_1608Metric_G" (layer "F.Cu")
    (at 147.5 68.74 180)
    (descr "LED SMD 0603 Green")
    (tags "LED SMD 0603 Green")
    (property "Author" "Antmicro")
    (property "Color" "Green")
    (property "License" "Apache-2.0")
    (property "MPN" "KP-1608CGCK")
    (property "Manufacturer" "Kingbright")
    (property "Sheetfile" "tb-power.kicad_sch")
    (property "Sheetname" "Thunderbolt Controller - Power")
    (property "ki_description" "LED, Green, SMD, 0603, 20 mA, 2.1 V, 570 nm")
    (property "ki_keywords" "SMT, DIODE, SEMICONDUCTOR, LED")
    (attr smd)
    (fp_text reference "D4" (at -1.344 -0.475 180) (layer "F.SilkS")
        (effects (font (size 0.7 0.7) (thickness 0.15)) (justify left bottom))
    )
    (fp_text value "LED_G_0603_KP-1608CGCK" (at -0.001 1.599 180) (layer "F.Fab")
        (effects (font (size 0.7 0.7) (thickness 0.15)) (justify left bottom))
    )
    (fp_text user "${REFERENCE}" (at -1.4224 5.999 180) (layer "F.Fab") hide
        (effects (font (size 0.7 0.7) (thickness 0.15)) (justify left bottom))
    )
    (fp_text user "License: Apache-2.0" (at -1.4224 3.599 180) (layer "F.Fab") hide
        (effects (font (size 0.7 0.7) (thickness 0.15)) (justify left bottom))
    )
    (fp_text user "Author: Antmicro" (at -1.4224 4.799 180) (layer "F.Fab") hide
        (effects (font (size 0.7 0.7) (thickness 0.15)) (justify left bottom))
    )
    (fp_line (start -1.18 -0.319) (end -1.18 0.321)
      (stroke (width 0.15) (type solid)) (layer "F.SilkS"))
    (fp_line (start -0.094672 0.001008) (end -0.24 0.001008)
      (stroke (width 0.1) (type solid)) (layer "F.SilkS"))
    (fp_line (start -0.094672 0.001008) (end 0.105328 -0.198992)
      (stroke (width 0.1) (type solid)) (layer "F.SilkS"))
    (fp_line (start -0.094672 0.201008) (end -0.094672 -0.198992)
      (stroke (width 0.1) (type solid)) (layer "F.SilkS"))
    (fp_line (start 0.105328 0.001008) (end 0.24 0.001)
      (stroke (width 0.1) (type solid)) (layer "F.SilkS"))
    (fp_line (start 0.105328 0.201008) (end -0.094672 0.001008)
      (stroke (width 0.1) (type solid)) (layer "F.SilkS"))
    (fp_line (start 0.105328 0.201008) (end 0.105328 -0.198992)
      (stroke (width 0.1) (type solid)) (layer "F.SilkS"))
    (fp_line (start 0.22 -0.35) (end -0.22 -0.35)
      (stroke (width 0.15) (type solid)) (layer "F.SilkS"))
    (fp_line (start 0.22 0.35) (end -0.22 0.35)
      (stroke (width 0.15) (type solid)) (layer "F.SilkS"))
    (fp_rect (start 1.25 0.65) (end -1.25 -0.65)
      (stroke (width 0.05) (type solid)) (fill none) (layer "F.CrtYd"))
    (fp_line (start -0.199 -0.202) (end -0.199 0.1)
      (stroke (width 0.15) (type solid)) (layer "F.Fab"))
    (fp_line (start -0.199 0) (end -0.597 0)
      (stroke (width 0.15) (type solid)) (layer "F.Fab"))
    (fp_line (start -0.199 0.2) (end -0.199 0.1)
      (stroke (width 0.15) (type solid)) (layer "F.Fab"))
    (fp_line (start -0.101 0) (end 0.201 0.2)
      (stroke (width 0.15) (type solid)) (layer "F.Fab"))
    (fp_line (start 0.201 -0.202) (end -0.101 0)
      (stroke (width 0.15) (type solid)) (layer "F.Fab"))
    (fp_line (start 0.201 0) (end 0.201 -0.202)
      (stroke (width 0.15) (type solid)) (layer "F.Fab"))
    (fp_line (start 0.201 0.2) (end 0.201 0)
      (stroke (width 0.15) (type solid)) (layer "F.Fab"))
    (fp_line (start 0.599 0) (end 0.201 0)
      (stroke (width 0.15) (type solid)) (layer "F.Fab"))
    (fp_rect (start 0.848 0.4) (end -0.85 -0.402)
      (stroke (width 0.15) (type solid)) (fill none) (layer "F.Fab"))
    (pad "1" smd roundrect (at -0.7 0) (size 0.8 1) (layers "F.Cu" "F.Paste" "F.Mask") (roundrect_rratio 0.2)
      (net 122 "Net-(D4-C)") (pinfunction "C") (pintype "passive"))
    (pad "2" smd roundrect (at 0.7 0) (size 0.8 1) (layers "F.Cu" "F.Paste" "F.Mask") (roundrect_rratio 0.2)
      (net 2 "3V3_SYS") (pinfunction "A") (pintype "passive"))
  )

  (footprint "antmicro-footprints:TP_SMD_0.75mm" (layer "F.Cu")
    (at 113.7 82.9)
    (property "Author" "Antmicro")
    (property "License" "Apache-2.0")
    (property "MPN" "")
    (property "Manufacturer" "")
    (property "Sheetfile" "power.kicad_sch")
    (property "Sheetname" "Power")
    (property "exclude_from_bom" "")
    (property "ki_description" "SMT test point")
    (property "ki_keywords" "TESTPOINT")
    (attr exclude_from_pos_files exclude_from_bom)
    (fp_text reference "TP6" (at 0.6 0.539) (layer "F.SilkS")
        (effects (font (size 0.7 0.7) (thickness 0.15)) (justify left bottom))
    )
    (fp_text value "TP_0.75mm_SMD" (at 0 1.2) (layer "F.Fab")
        (effects (font (size 0.7 0.7) (thickness 0.15)) (justify left bottom))
    )
    (fp_text user "Author: Antmicro" (at -0.4 3.901) (layer "F.Fab") hide
        (effects (font (size 0.7 0.7) (thickness 0.15)) (justify left bottom))
    )
    (fp_text user "License: Apache-2.0" (at -0.4 5.101) (layer "F.Fab") hide
        (effects (font (size 0.7 0.7) (thickness 0.15)) (justify left bottom))
    )
    (fp_text user "${REFERENCE}" (at -0.4 2.7) (layer "F.Fab") hide
        (effects (font (size 0.7 0.7) (thickness 0.15)) (justify left bottom))
    )
    (fp_circle (center 0 0) (end 0.475 0)
      (stroke (width 0.05) (type default)) (fill none) (layer "F.CrtYd"))
    (pad "1" smd circle (at 0 0) (size 0.75 0.75) (layers "F.Cu" "F.Mask")
      (net 207 "Net-(U1-CLKOUT)") (pinfunction "1") (pintype "passive"))
  )

  (footprint "antmicro-footprints:LED_0603_1608Metric_G" (layer "F.Cu")
    (at 106.9455 89.2)
    (descr "LED SMD 0603 Green")
    (tags "LED SMD 0603 Green")
    (property "Author" "Antmicro")
    (property "Color" "Green")
    (property "License" "Apache-2.0")
    (property "MPN" "KP-1608CGCK")
    (property "Manufacturer" "Kingbright")
    (property "Sheetfile" "power.kicad_sch")
    (property "Sheetname" "Power")
    (property "ki_description" "LED, Green, SMD, 0603, 20 mA, 2.1 V, 570 nm")
    (property "ki_keywords" "SMT, DIODE, SEMICONDUCTOR, LED")
    (attr smd)
    (fp_text reference "D5" (at -2.6785 0.462) (layer "F.SilkS")
        (effects (font (size 0.7 0.7) (thickness 0.15)) (justify left bottom))
    )
    (fp_text value "LED_G_0603_KP-1608CGCK" (at -0.001 1.599) (layer "F.Fab")
        (effects (font (size 0.7 0.7) (thickness 0.15)) (justify left bottom))
    )
    (fp_text user "License: Apache-2.0" (at -1.4224 3.599) (layer "F.Fab") hide
        (effects (font (size 0.7 0.7) (thickness 0.15)) (justify left bottom))
    )
    (fp_text user "Author: Antmicro" (at -1.4224 4.799) (layer "F.Fab") hide
        (effects (font (size 0.7 0.7) (thickness 0.15)) (justify left bottom))
    )
    (fp_text user "${REFERENCE}" (at -1.4224 5.999) (layer "F.Fab") hide
        (effects (font (size 0.7 0.7) (thickness 0.15)) (justify left bottom))
    )
    (fp_line (start -1.18 -0.319) (end -1.18 0.321)
      (stroke (width 0.15) (type solid)) (layer "F.SilkS"))
    (fp_line (start -0.094672 0.001008) (end -0.24 0.001008)
      (stroke (width 0.1) (type solid)) (layer "F.SilkS"))
    (fp_line (start -0.094672 0.001008) (end 0.105328 -0.198992)
      (stroke (width 0.1) (type solid)) (layer "F.SilkS"))
    (fp_line (start -0.094672 0.201008) (end -0.094672 -0.198992)
      (stroke (width 0.1) (type solid)) (layer "F.SilkS"))
    (fp_line (start 0.105328 0.001008) (end 0.24 0.001)
      (stroke (width 0.1) (type solid)) (layer "F.SilkS"))
    (fp_line (start 0.105328 0.201008) (end -0.094672 0.001008)
      (stroke (width 0.1) (type solid)) (layer "F.SilkS"))
    (fp_line (start 0.105328 0.201008) (end 0.105328 -0.198992)
      (stroke (width 0.1) (type solid)) (layer "F.SilkS"))
    (fp_line (start 0.22 -0.35) (end -0.22 -0.35)
      (stroke (width 0.15) (type solid)) (layer "F.SilkS"))
    (fp_line (start 0.22 0.35) (end -0.22 0.35)
      (stroke (width 0.15) (type solid)) (layer "F.SilkS"))
    (fp_rect (start 1.25 0.65) (end -1.25 -0.65)
      (stroke (width 0.05) (type solid)) (fill none) (layer "F.CrtYd"))
    (fp_line (start -0.199 -0.202) (end -0.199 0.1)
      (stroke (width 0.15) (type solid)) (layer "F.Fab"))
    (fp_line (start -0.199 0) (end -0.597 0)
      (stroke (width 0.15) (type solid)) (layer "F.Fab"))
    (fp_line (start -0.199 0.2) (end -0.199 0.1)
      (stroke (width 0.15) (type solid)) (layer "F.Fab"))
    (fp_line (start -0.101 0) (end 0.201 0.2)
      (stroke (width 0.15) (type solid)) (layer "F.Fab"))
    (fp_line (start 0.201 -0.202) (end -0.101 0)
      (stroke (width 0.15) (type solid)) (layer "F.Fab"))
    (fp_line (start 0.201 0) (end 0.201 -0.202)
      (stroke (width 0.15) (type solid)) (layer "F.Fab"))
    (fp_line (start 0.201 0.2) (end 0.201 0)
      (stroke (width 0.15) (type solid)) (layer "F.Fab"))
    (fp_line (start 0.599 0) (end 0.201 0)
      (stroke (width 0.15) (type solid)) (layer "F.Fab"))
    (fp_rect (start 0.848 0.4) (end -0.85 -0.402)
      (stroke (width 0.15) (type solid)) (fill none) (layer "F.Fab"))
    (pad "1" smd roundrect (at -0.7 0 180) (size 0.8 1) (layers "F.Cu" "F.Paste" "F.Mask") (roundrect_rratio 0.2)
      (net 123 "Net-(D5-C)") (pinfunction "C") (pintype "passive"))
    (pad "2" smd roundrect (at 0.7 0 180) (size 0.8 1) (layers "F.Cu" "F.Paste" "F.Mask") (roundrect_rratio 0.2)
      (net 61 "12V0_MOLEX") (pinfunction "A") (pintype "passive"))
  )

  (footprint "antmicro-footprints:C_0805_2012Metric" (layer "F.Cu")
    (at 105.01 74.11 90)
    (descr "Capacitor SMD 0805")
    (tags "capacitor SMD 0805")
    (property "Author" "Antmicro")
    (property "Dielectric" "")
    (property "License" "Apache-2.0")
    (property "MPN" "GRM21BR6YA106KE43L")
    (property "Manufacturer" "Murata")
    (property "Sheetfile" "power.kicad_sch")
    (property "Sheetname" "Power")
    (property "Val" "10u")
    (property "Voltage" "35V")
    (property "ki_description" "SMD Multilayer Ceramic Capacitor, 10 µF, 35 V, 0805 [2012 Metric], ± 10%, X5R, GRM Series")
    (property "ki_keywords" "0805, SMT, CAPACITOR, PASSIVE")
    (attr smd)
    (fp_text reference "C7" (at 1.974 0.4 90) (layer "F.SilkS")
        (effects (font (size 0.7 0.7) (thickness 0.15)) (justify left bottom))
    )
    (fp_text value "C_10u_0805_35V" (at -2.055717 1.963152 90) (layer "F.Fab")
        (effects (font (size 0.7 0.7) (thickness 0.15)) (justify left bottom))
    )
    (fp_text user "${REFERENCE}" (at -1.9 3.947 90) (layer "F.Fab") hide
        (effects (font (size 0.7 0.7) (thickness 0.15)) (justify left bottom))
    )
    (fp_text user "License: Apache-2.0" (at -1.9 4.947 90) (layer "F.Fab") hide
        (effects (font (size 0.7 0.7) (thickness 0.15)) (justify left bottom))
    )
    (fp_text user "Author: Antmicro" (at -1.9 5.947 90) (layer "F.Fab") hide
        (effects (font (size 0.7 0.7) (thickness 0.15)) (justify left bottom))
    )
    (fp_line (start -0.3 -0.7) (end 0.3 -0.7)
      (stroke (width 0.15) (type solid)) (layer "F.SilkS"))
    (fp_line (start -0.3 0.7) (end 0.3 0.7)
      (stroke (width 0.15) (type solid)) (layer "F.SilkS"))
    (fp_rect (start 1.95 -0.9) (end -1.95 0.9)
      (stroke (width 0.05) (type default)) (fill none) (layer "F.CrtYd"))
    (fp_rect (start -0.95 -0.675) (end 0.95 0.675)
      (stroke (width 0.15) (type solid)) (fill none) (layer "F.Fab"))
    (pad "1" smd roundrect (at -1.1 0 90) (size 1.2 1.3) (layers "F.Cu" "F.Paste" "F.Mask") (roundrect_rratio 0.25)
      (net 1 "GND") (pintype "passive"))
    (pad "2" smd roundrect (at 1.1 0 90) (size 1.2 1.3) (layers "F.Cu" "F.Paste" "F.Mask") (roundrect_rratio 0.25)
      (net 3 "5V0_USB") (pintype "passive"))
  )

  (footprint "antmicro-footprints:C_0603_1608Metric" (layer "F.Cu")
    (at 144.4 72.3 90)
    (descr "Capacitor SMD 0603")
    (tags "capacitor 0603")
    (property "Author" "Antmicro")
    (property "Dielectric" "")
    (property "License" "Apache-2.0")
    (property "MPN" "GRM188R60J226MEA0D")
    (property "Manufacturer" "Murata")
    (property "Sheetfile" "tb-power.kicad_sch")
    (property "Sheetname" "Thunderbolt Controller - Power")
    (property "Val" "22u")
    (property "Voltage" "")
    (property "ki_description" "SMD Multilayer Ceramic Capacitor, 22 µF, 6.3 V, 0603 [1608 Metric], ± 20%, X5R, GRM Series")
    (property "ki_keywords" "0603, SMT, CAPACITOR, PASSIVE, CERAMIC, MLCC")
    (attr smd)
    (fp_text reference "C79" (at -3.519 0.483 90) (layer "F.SilkS")
        (effects (font (size 0.7 0.7) (thickness 0.15)) (justify left bottom))
    )
    (fp_text value "C_22u_0603" (at -1.42757 1.770288 90) (layer "F.Fab")
        (effects (font (size 0.7 0.7) (thickness 0.15)) (justify left bottom))
    )
    (fp_text user "Author: Antmicro" (at -1.682 4.894 90) (layer "F.Fab") hide
        (effects (font (size 0.7 0.7) (thickness 0.15)) (justify left bottom))
    )
    (fp_text user "${REFERENCE}" (at -1.682 3.895 90) (layer "F.Fab") hide
        (effects (font (size 0.7 0.7) (thickness 0.15)) (justify left bottom))
    )
    (fp_text user "License: Apache-2.0" (at -1.682 5.895 90) (layer "F.Fab") hide
        (effects (font (size 0.7 0.7) (thickness 0.15)) (justify left bottom))
    )
    (fp_line (start -0.15 -0.4) (end 0.15 -0.4)
      (stroke (width 0.15) (type solid)) (layer "F.SilkS"))
    (fp_line (start -0.15 0.4) (end 0.15 0.4)
      (stroke (width 0.15) (type solid)) (layer "F.SilkS"))
    (fp_rect (start -1.25 -0.65) (end 1.25 0.65)
      (stroke (width 0.05) (type solid)) (fill none) (layer "F.CrtYd"))
    (fp_rect (start -0.8 -0.4) (end 0.8 0.4)
      (stroke (width 0.15) (type solid)) (fill none) (layer "F.Fab"))
    (pad "1" smd roundrect (at -0.7 0 90) (size 0.8 1) (layers "F.Cu" "F.Paste" "F.Mask") (roundrect_rratio 0.2)
      (net 1 "GND") (pintype "passive"))
    (pad "2" smd roundrect (at 0.7 0 90) (size 0.8 1) (layers "F.Cu" "F.Paste" "F.Mask") (roundrect_rratio 0.2)
      (net 112 "Net-(U4A-VCC0P9_SVR_SENSE)") (pintype "passive"))
  )

  (footprint "antmicro-footprints:L_Coilcraft-XAL5030" (layer "F.Cu")
    (at 121.6 64.455 90)
    (property "Author" "Antmicro")
    (property "IMax" "9.7 A")
    (property "ISat" "9.2 A")
    (property "License" "Apache-2.0")
    (property "MPN" "XAL5030-222MEC")
    (property "Manufacturer" "Coilcraft")
    (property "Sheetfile" "power.kicad_sch")
    (property "Sheetname" "Power")
    (property "Size" "5.28x5.48")
    (property "Val" "2u2/9.7A")
    (property "ki_description" "Power Inductor (SMT), 2.2 µH, 9.7 A, Shielded, 9.2 A, XAL5030")
    (property "ki_keywords" "SMT, INDUCTOR, PASSIVE")
    (attr smd)
    (fp_text reference "L2" (at 2.987 -0.823 180) (layer "F.SilkS")
        (effects (font (size 0.7 0.7) (thickness 0.15)) (justify left bottom))
    )
    (fp_text value "L_2u2_9.7A_Coilcraft-XAL5030" (at 0 4.241 90) (layer "F.Fab")
        (effects (font (size 0.7 0.7) (thickness 0.15)) (justify left bottom))
    )
    (fp_text user "License: Apache-2.0" (at -2.89 6.241 90) (layer "F.Fab") hide
        (effects (font (size 0.7 0.7) (thickness 0.15)) (justify left bottom))
    )
    (fp_text user "${REFERENCE}" (at -2.89 8.641 90) (layer "F.Fab") hide
        (effects (font (size 0.7 0.7) (thickness 0.15)) (justify left bottom))
    )
    (fp_text user "Author: Antmicro" (at -2.89 7.441 90) (layer "F.Fab") hide
        (effects (font (size 0.7 0.7) (thickness 0.15)) (justify left bottom))
    )
    (fp_line (start -2.74 -2.84) (end 2.74 -2.84)
      (stroke (width 0.15) (type solid)) (layer "F.SilkS"))
    (fp_line (start -2.74 2.84) (end -2.74 -2.84)
      (stroke (width 0.15) (type solid)) (layer "F.SilkS"))
    (fp_line (start -2.74 2.84) (end 2.74 2.84)
      (stroke (width 0.15) (type solid)) (layer "F.SilkS"))
    (fp_line (start 2.74 2.84) (end 2.74 -2.84)
      (stroke (width 0.15) (type solid)) (layer "F.SilkS"))
    (fp_rect (start -2.89 -2.99) (end 2.89 2.99)
      (stroke (width 0.05) (type solid)) (fill none) (layer "F.CrtYd"))
    (fp_line (start -2.74 -2.84) (end 2.74 -2.84)
      (stroke (width 0.15) (type solid)) (layer "F.Fab"))
    (fp_line (start -2.74 2.84) (end -2.74 -2.84)
      (stroke (width 0.15) (type solid)) (layer "F.Fab"))
    (fp_line (start 2.74 -2.84) (end 2.74 2.84)
      (stroke (width 0.15) (type solid)) (layer "F.Fab"))
    (fp_line (start 2.74 2.84) (end -2.74 2.84)
      (stroke (width 0.15) (type solid)) (layer "F.Fab"))
    (pad "1" smd roundrect (at -1.655 0 90) (size 1.18 4.7) (layers "F.Cu" "F.Paste" "F.Mask") (roundrect_rratio 0.1)
      (net 95 "Net-(U2-SW)") (pintype "passive"))
    (pad "2" smd roundrect (at 1.655 0 90) (size 1.18 4.7) (layers "F.Cu" "F.Paste" "F.Mask") (roundrect_rratio 0.1)
      (net 100 "Net-(D2-A)") (pintype "passive"))
  )

  (footprint "antmicro-footprints:C_0603_1608Metric" (layer "F.Cu")
    (at 142.9 69.7 -90)
    (descr "Capacitor SMD 0603")
    (tags "capacitor 0603")
    (property "Author" "Antmicro")
    (property "Dielectric" "")
    (property "License" "Apache-2.0")
    (property "MPN" "GRM188R60J226MEA0D")
    (property "Manufacturer" "Murata")
    (property "Sheetfile" "tb-power.kicad_sch")
    (property "Sheetname" "Thunderbolt Controller - Power")
    (property "Val" "22u")
    (property "Voltage" "")
    (property "ki_description" "SMD Multilayer Ceramic Capacitor, 22 µF, 6.3 V, 0603 [1608 Metric], ± 20%, X5R, GRM Series")
    (property "ki_keywords" "0603, SMT, CAPACITOR, PASSIVE, CERAMIC, MLCC")
    (attr smd)
    (fp_text reference "C86" (at -1.247 -0.483 -90) (layer "F.SilkS")
        (effects (font (size 0.7 0.7) (thickness 0.15)) (justify left bottom))
    )
    (fp_text value "C_22u_0603" (at -1.42757 1.770288 -90) (layer "F.Fab")
        (effects (font (size 0.7 0.7) (thickness 0.15)) (justify left bottom))
    )
    (fp_text user "Author: Antmicro" (at -1.682 4.894 -90) (layer "F.Fab") hide
        (effects (font (size 0.7 0.7) (thickness 0.15)) (justify left bottom))
    )
    (fp_text user "License: Apache-2.0" (at -1.682 5.895 -90) (layer "F.Fab") hide
        (effects (font (size 0.7 0.7) (thickness 0.15)) (justify left bottom))
    )
    (fp_text user "${REFERENCE}" (at -1.682 3.895 -90) (layer "F.Fab") hide
        (effects (font (size 0.7 0.7) (thickness 0.15)) (justify left bottom))
    )
    (fp_line (start -0.15 -0.4) (end 0.15 -0.4)
      (stroke (width 0.15) (type solid)) (layer "F.SilkS"))
    (fp_line (start -0.15 0.4) (end 0.15 0.4)
      (stroke (width 0.15) (type solid)) (layer "F.SilkS"))
    (fp_rect (start -1.25 -0.65) (end 1.25 0.65)
      (stroke (width 0.05) (type solid)) (fill none) (layer "F.CrtYd"))
    (fp_rect (start -0.8 -0.4) (end 0.8 0.4)
      (stroke (width 0.15) (type solid)) (fill none) (layer "F.Fab"))
    (pad "1" smd roundrect (at -0.7 0 270) (size 0.8 1) (layers "F.Cu" "F.Paste" "F.Mask") (roundrect_rratio 0.2)
      (net 1 "GND") (pintype "passive"))
    (pad "2" smd roundrect (at 0.7 0 270) (size 0.8 1) (layers "F.Cu" "F.Paste" "F.Mask") (roundrect_rratio 0.2)
      (net 112 "Net-(U4A-VCC0P9_SVR_SENSE)") (pintype "passive"))
  )

  (footprint "antmicro-footprints:Fiducial_1mm_Mask3mm" (layer "F.Cu")
    (at 108.7 52)
    (descr "Circular Fiducial, 1.5mm bare copper, 3mm soldermask opening")
    (tags "fiducial")
    (property "Author" "Antmicro")
    (property "License" "Apache-2.0")
    (property "Sheetfile" "thunderbolt-pcie-adapter.kicad_sch")
    (property "Sheetname" "")
    (property "exclude_from_bom" "")
    (property "ki_description" "Fiducial mask")
    (attr through_hole exclude_from_bom)
    (fp_text reference "FID2" (at -1.258 2.61) (layer "F.SilkS")
        (effects (font (size 0.7 0.7) (thickness 0.15)) (justify left bottom))
    )
    (fp_text value "Fiducial_1mm_Mask3mm" (at 0 2.603) (layer "F.Fab")
        (effects (font (size 0.7 0.7) (thickness 0.15)) (justify left bottom))
    )
    (fp_text user "License: Apache-2.0" (at -1.25 7.003) (layer "F.Fab") hide
        (effects (font (size 0.7 0.7) (thickness 0.15)) (justify left bottom))
    )
    (fp_text user "Author: Antmicro" (at -1.25 5.803) (layer "F.Fab") hide
        (effects (font (size 0.7 0.7) (thickness 0.15)) (justify left bottom))
    )
    (fp_text user "${REFERENCE}" (at -1.25 4.603) (layer "F.Fab") hide
        (effects (font (size 0.7 0.7) (thickness 0.15)) (justify left bottom))
    )
    (fp_circle (center 0 0) (end 1.5 0)
      (stroke (width 0.05) (type solid)) (fill none) (layer "F.CrtYd"))
    (fp_circle (center 0 0) (end 1.5 0)
      (stroke (width 0.15) (type solid)) (fill none) (layer "F.Fab"))
    (pad "" smd circle (at 0 0) (size 1 1) (layers "F.Cu" "F.Mask")
      (solder_mask_margin 1) (clearance 1))
  )

  (footprint "antmicro-footprints:C_0603_1608Metric" (layer "F.Cu")
    (at 144.4 69.7 -90)
    (descr "Capacitor SMD 0603")
    (tags "capacitor 0603")
    (property "Author" "Antmicro")
    (property "Dielectric" "")
    (property "License" "Apache-2.0")
    (property "MPN" "GRM188R60J226MEA0D")
    (property "Manufacturer" "Murata")
    (property "Sheetfile" "tb-power.kicad_sch")
    (property "Sheetname" "Thunderbolt Controller - Power")
    (property "Val" "22u")
    (property "Voltage" "")
    (property "ki_description" "SMD Multilayer Ceramic Capacitor, 22 µF, 6.3 V, 0603 [1608 Metric], ± 20%, X5R, GRM Series")
    (property "ki_keywords" "0603, SMT, CAPACITOR, PASSIVE, CERAMIC, MLCC")
    (attr smd)
    (fp_text reference "C89" (at -1.247 -0.483 -90) (layer "F.SilkS")
        (effects (font (size 0.7 0.7) (thickness 0.15)) (justify left bottom))
    )
    (fp_text value "C_22u_0603" (at -1.42757 1.770288 -90) (layer "F.Fab")
        (effects (font (size 0.7 0.7) (thickness 0.15)) (justify left bottom))
    )
    (fp_text user "${REFERENCE}" (at -1.682 3.895 -90) (layer "F.Fab") hide
        (effects (font (size 0.7 0.7) (thickness 0.15)) (justify left bottom))
    )
    (fp_text user "Author: Antmicro" (at -1.682 4.894 -90) (layer "F.Fab") hide
        (effects (font (size 0.7 0.7) (thickness 0.15)) (justify left bottom))
    )
    (fp_text user "License: Apache-2.0" (at -1.682 5.895 -90) (layer "F.Fab") hide
        (effects (font (size 0.7 0.7) (thickness 0.15)) (justify left bottom))
    )
    (fp_line (start -0.15 -0.4) (end 0.15 -0.4)
      (stroke (width 0.15) (type solid)) (layer "F.SilkS"))
    (fp_line (start -0.15 0.4) (end 0.15 0.4)
      (stroke (width 0.15) (type solid)) (layer "F.SilkS"))
    (fp_rect (start -1.25 -0.65) (end 1.25 0.65)
      (stroke (width 0.05) (type solid)) (fill none) (layer "F.CrtYd"))
    (fp_rect (start -0.8 -0.4) (end 0.8 0.4)
      (stroke (width 0.15) (type solid)) (fill none) (layer "F.Fab"))
    (pad "1" smd roundrect (at -0.7 0 270) (size 0.8 1) (layers "F.Cu" "F.Paste" "F.Mask") (roundrect_rratio 0.2)
      (net 1 "GND") (pintype "passive"))
    (pad "2" smd roundrect (at 0.7 0 270) (size 0.8 1) (layers "F.Cu" "F.Paste" "F.Mask") (roundrect_rratio 0.2)
      (net 112 "Net-(U4A-VCC0P9_SVR_SENSE)") (pintype "passive"))
  )

  (footprint "antmicro-footprints:TP_SMD_0.75mm" (layer "F.Cu")
    (at 113.7 81.9)
    (property "Author" "Antmicro")
    (property "License" "Apache-2.0")
    (property "MPN" "")
    (property "Manufacturer" "")
    (property "Sheetfile" "power.kicad_sch")
    (property "Sheetname" "Power")
    (property "exclude_from_bom" "")
    (property "ki_description" "SMT test point")
    (property "ki_keywords" "TESTPOINT")
    (attr exclude_from_pos_files exclude_from_bom)
    (fp_text reference "TP4" (at 0.6 0.396) (layer "F.SilkS")
        (effects (font (size 0.7 0.7) (thickness 0.15)) (justify left bottom))
    )
    (fp_text value "TP_0.75mm_SMD" (at 0 1.2) (layer "F.Fab")
        (effects (font (size 0.7 0.7) (thickness 0.15)) (justify left bottom))
    )
    (fp_text user "${REFERENCE}" (at -0.4 2.7) (layer "F.Fab") hide
        (effects (font (size 0.7 0.7) (thickness 0.15)) (justify left bottom))
    )
    (fp_text user "License: Apache-2.0" (at -0.4 5.101) (layer "F.Fab") hide
        (effects (font (size 0.7 0.7) (thickness 0.15)) (justify left bottom))
    )
    (fp_text user "Author: Antmicro" (at -0.4 3.901) (layer "F.Fab") hide
        (effects (font (size 0.7 0.7) (thickness 0.15)) (justify left bottom))
    )
    (fp_circle (center 0 0) (end 0.475 0)
      (stroke (width 0.05) (type default)) (fill none) (layer "F.CrtYd"))
    (pad "1" smd circle (at 0 0) (size 0.75 0.75) (layers "F.Cu" "F.Mask")
      (net 205 "Net-(U1-LOADTG)") (pinfunction "1") (pintype "passive"))
  )

  (footprint "antmicro-footprints:FB_0805_2012Metric" (layer "F.Cu")
    (at 107.091001 60.489)
    (descr "FERRITE BEAD 0805")
    (tags "FERRITE BEAD 0805")
    (property "Author" "Antmicro")
    (property "Current" "")
    (property "License" "Apache-2.0")
    (property "MPN" "BLM21SN300SZ1D")
    (property "Manufacturer" "Murata")
    (property "Sheetfile" "power.kicad_sch")
    (property "Sheetname" "Power")
    (property "Val" "30Z/8.5A")
    (property "ki_description" "Ferrite Bead, 0805 [2012 Metric], 30 ohm, 8.5 A, BLM21SN, 0.004 ohm, ± 10ohm, DC power line")
    (property "ki_keywords" "0805, SMT, FERRITE BEAD, PASSIVE")
    (attr smd)
    (fp_text reference "FB2" (at -1.173001 -1.053) (layer "F.SilkS")
        (effects (font (size 0.7 0.7) (thickness 0.15)) (justify left bottom))
    )
    (fp_text value "FB_30Z_8.5A_Murata-BLM21SN_0805" (at 0.001 1.801) (layer "F.Fab")
        (effects (font (size 0.7 0.7) (thickness 0.15)) (justify left bottom))
    )
    (fp_text user "Author: Antmicro" (at -1.44 5.001) (layer "F.Fab") hide
        (effects (font (size 0.7 0.7) (thickness 0.15)) (justify left bottom))
    )
    (fp_text user "${REFERENCE}" (at -1.44 3.801) (layer "F.Fab") hide
        (effects (font (size 0.7 0.7) (thickness 0.15)) (justify left bottom))
    )
    (fp_text user "License: Apache-2.0" (at -1.44 6.201) (layer "F.Fab") hide
        (effects (font (size 0.7 0.7) (thickness 0.15)) (justify left bottom))
    )
    (fp_line (start -0.319 0.698) (end 0.281 0.698)
      (stroke (width 0.15) (type solid)) (layer "F.SilkS"))
    (fp_line (start -0.299 -0.698) (end 0.299 -0.698)
      (stroke (width 0.15) (type solid)) (layer "F.SilkS"))
    (fp_rect (start 1.95 -0.9) (end -1.95 0.9)
      (stroke (width 0.05) (type default)) (fill none) (layer "F.CrtYd"))
    (fp_line (start -0.948 -0.681) (end 0.948 -0.681)
      (stroke (width 0.15) (type solid)) (layer "F.Fab"))
    (fp_line (start -0.948 -0.676) (end -0.948 0.676)
      (stroke (width 0.15) (type solid)) (layer "F.Fab"))
    (fp_line (start -0.948 0.681) (end 0.948 0.681)
      (stroke (width 0.15) (type solid)) (layer "F.Fab"))
    (fp_line (start 0.948 -0.676) (end 0.948 0.676)
      (stroke (width 0.15) (type solid)) (layer "F.Fab"))
    (pad "1" smd roundrect (at -1.1 0) (size 1.2 1.3) (layers "F.Cu" "F.Paste" "F.Mask") (roundrect_rratio 0.25)
      (net 3 "5V0_USB") (pintype "passive"))
    (pad "2" smd roundrect (at 1.1 0) (size 1.2 1.3) (layers "F.Cu" "F.Paste" "F.Mask") (roundrect_rratio 0.25)
      (net 90 "Net-(U2-VIN)") (pintype "passive"))
  )

  (footprint "antmicro-footprints:SOT-323" (layer "F.Cu")
    (at 103.035 87.975 90)
    (property "Author" "Antmicro")
    (property "License" "Apache-2.0")
    (property "MPN" "BC817-25W,115")
    (property "Manufacturer" "Nexperia")
    (property "Sheetfile" "power.kicad_sch")
    (property "Sheetname" "Power")
    (property "ki_description" "Bipolar (BJT) Single Transistor, NPN, 45 V, 500 mA, 200 mW, SOT-323, Surface Mount")
    (property "ki_keywords" "SMT, TRANSISTOR, SEMICONDUCTOR, BIPOLAR")
    (attr smd)
    (fp_text reference "Q2" (at -0.798 -1.562 90) (layer "F.SilkS")
        (effects (font (size 0.7 0.7) (thickness 0.15)) (justify left bottom))
    )
    (fp_text value "BC817-25W" (at 0 2.749 90) (layer "F.Fab")
        (effects (font (size 0.7 0.7) (thickness 0.15)) (justify left bottom))
    )
    (fp_text user "${REFERENCE}" (at -1.35 4.749 90) (layer "F.Fab") hide
        (effects (font (size 0.7 0.7) (thickness 0.15)) (justify left bottom))
    )
    (fp_text user "Author: Antmicro" (at -1.35 7.149 90) (layer "F.Fab") hide
        (effects (font (size 0.7 0.7) (thickness 0.15)) (justify left bottom))
    )
    (fp_text user "License: Apache-2.0" (at -1.35 5.949 90) (layer "F.Fab") hide
        (effects (font (size 0.7 0.7) (thickness 0.15)) (justify left bottom))
    )
    (fp_line (start -0.802 -1.2) (end -0.802 -1.05)
      (stroke (width 0.15) (type solid)) (layer "F.SilkS"))
    (fp_line (start -0.802 1.05) (end -0.802 1.199)
      (stroke (width 0.15) (type solid)) (layer "F.SilkS"))
    (fp_line (start -0.802 1.199) (end -0.5 1.199)
      (stroke (width 0.15) (type solid)) (layer "F.SilkS"))
    (fp_line (start -0.402 -1.2) (end -0.802 -1.2)
      (stroke (width 0.15) (type solid)) (layer "F.SilkS"))
    (fp_line (start 0.498 -1.2) (end 0.8 -1.2)
      (stroke (width 0.15) (type solid)) (layer "F.SilkS"))
    (fp_line (start 0.498 1.199) (end 0.8 1.199)
      (stroke (width 0.15) (type solid)) (layer "F.SilkS"))
    (fp_line (start 0.8 -1.2) (end 0.8 -0.902)
      (stroke (width 0.15) (type solid)) (layer "F.SilkS"))
    (fp_line (start 0.8 1.199) (end 0.8 0.9)
      (stroke (width 0.15) (type solid)) (layer "F.SilkS"))
    (fp_circle (center -1.05 -1.156824) (end -1 -1.129824)
      (stroke (width 0.15) (type solid)) (fill none) (layer "F.SilkS"))
    (fp_rect (start -1.35 -1.35) (end 1.35 1.35)
      (stroke (width 0.05) (type solid)) (fill none) (layer "F.CrtYd"))
    (fp_line (start -0.677 -1.101) (end -0.677 1.1)
      (stroke (width 0.15) (type solid)) (layer "F.Fab"))
    (fp_line (start -0.677 -1.101) (end 0.675 -1.101)
      (stroke (width 0.15) (type solid)) (layer "F.Fab"))
    (fp_line (start -0.677 1.1) (end 0.675 1.1)
      (stroke (width 0.15) (type solid)) (layer "F.Fab"))
    (fp_line (start 0.675 -1.101) (end 0.675 1.1)
      (stroke (width 0.15) (type solid)) (layer "F.Fab"))
    (pad "1" smd rect (at -0.927 -0.652 90) (size 0.55 0.6) (layers "F.Cu" "F.Paste" "F.Mask")
      (net 140 "Net-(Q2-B)") (pinfunction "B") (pintype "input"))
    (pad "2" smd rect (at -0.927 0.65 90) (size 0.55 0.6) (layers "F.Cu" "F.Paste" "F.Mask")
      (net 1 "GND") (pinfunction "E") (pintype "passive"))
    (pad "3" smd rect (at 0.925 0 90) (size 0.55 0.6) (layers "F.Cu" "F.Paste" "F.Mask")
      (net 88 "/Power/DCDC_EN") (pinfunction "C") (pintype "passive"))
  )

  (footprint "antmicro-footprints:Fiducial_1mm_Mask3mm" (layer "F.Cu")
    (at 168 59)
    (descr "Circular Fiducial, 1.5mm bare copper, 3mm soldermask opening")
    (tags "fiducial")
    (property "Author" "Antmicro")
    (property "License" "Apache-2.0")
    (property "Sheetfile" "thunderbolt-pcie-adapter.kicad_sch")
    (property "Sheetname" "")
    (property "exclude_from_bom" "")
    (property "ki_description" "Fiducial mask")
    (attr through_hole exclude_from_bom)
    (fp_text reference "FID3" (at -1.122 2.595) (layer "F.SilkS")
        (effects (font (size 0.7 0.7) (thickness 0.15)) (justify left bottom))
    )
    (fp_text value "Fiducial_1mm_Mask3mm" (at 0 2.603) (layer "F.Fab")
        (effects (font (size 0.7 0.7) (thickness 0.15)) (justify left bottom))
    )
    (fp_text user "License: Apache-2.0" (at -1.25 7.003) (layer "F.Fab") hide
        (effects (font (size 0.7 0.7) (thickness 0.15)) (justify left bottom))
    )
    (fp_text user "${REFERENCE}" (at -1.25 4.603) (layer "F.Fab") hide
        (effects (font (size 0.7 0.7) (thickness 0.15)) (justify left bottom))
    )
    (fp_text user "Author: Antmicro" (at -1.25 5.803) (layer "F.Fab") hide
        (effects (font (size 0.7 0.7) (thickness 0.15)) (justify left bottom))
    )
    (fp_circle (center 0 0) (end 1.5 0)
      (stroke (width 0.05) (type solid)) (fill none) (layer "F.CrtYd"))
    (fp_circle (center 0 0) (end 1.5 0)
      (stroke (width 0.15) (type solid)) (fill none) (layer "F.Fab"))
    (pad "" smd circle (at 0 0) (size 1 1) (layers "F.Cu" "F.Mask")
      (solder_mask_margin 1) (clearance 1))
  )

  (footprint "antmicro-footprints:TP_SMD_1mm" (layer "F.Cu")
    (at 146.5 66 180)
    (property "Author" "Antmicro")
    (property "License" "Apache-2.0")
    (property "MPN" "")
    (property "Manufacturer" "")
    (property "Sheetfile" "tb-power.kicad_sch")
    (property "Sheetname" "Thunderbolt Controller - Power")
    (property "exclude_from_bom" "")
    (property "ki_description" "Test point 1mm SMD")
    (property "ki_keywords" "TESTPOINT")
    (attr exclude_from_pos_files exclude_from_bom)
    (fp_text reference "TP9" (at -0.566 -0.421 180) (layer "F.SilkS")
        (effects (font (size 0.7 0.7) (thickness 0.15)) (justify left bottom))
    )
    (fp_text value "TP_1mm_SMD" (at 0 1.4 180) (layer "F.Fab")
        (effects (font (size 0.7 0.7) (thickness 0.15)) (justify left bottom))
    )
    (fp_text user "License: Apache-2.0" (at -0.5 5.2 180) (layer "F.Fab") hide
        (effects (font (size 0.7 0.7) (thickness 0.15)) (justify left bottom))
    )
    (fp_text user "${REFERENCE}" (at -0.5 2.8 180) (layer "F.Fab") hide
        (effects (font (size 0.7 0.7) (thickness 0.15)) (justify left bottom))
    )
    (fp_text user "Author: Antmicro" (at -0.5 4 180) (layer "F.Fab") hide
        (effects (font (size 0.7 0.7) (thickness 0.15)) (justify left bottom))
    )
    (fp_circle (center 0 0) (end 0.6 0)
      (stroke (width 0.05) (type default)) (fill none) (layer "F.CrtYd"))
    (pad "1" smd circle (at 0 0 180) (size 1 1) (layers "F.Cu" "F.Mask")
      (net 112 "Net-(U4A-VCC0P9_SVR_SENSE)") (pinfunction "1") (pintype "passive"))
  )

  (footprint "antmicro-footprints:TSSOP-8_3x4.4mm_P0.65mm" (layer "F.Cu")
    (at 123 81.9 -90)
    (property "Author" "Antmicro")
    (property "License" "Apache-2.0")
    (property "MPN" "SI52112-B6-GT")
    (property "Manufacturer" "Skyworks Solutions")
    (property "Sheetfile" "tb.kicad_sch")
    (property "Sheetname" "TB Controller")
    (property "ki_description" "Clock Generator, 100MHz, 2.97V to 3.63V, 2 Outputs, TSSOP-8")
    (property "ki_keywords" "IC")
    (attr smd)
    (fp_text reference "U6" (at -1.763 -2.73 -90) (layer "F.SilkS")
        (effects (font (size 0.7 0.7) (thickness 0.15)) (justify left bottom))
    )
    (fp_text value "SI52112-B6-GT" (at 0 3 -90) (layer "F.Fab")
        (effects (font (size 0.7 0.7) (thickness 0.15)) (justify left bottom))
    )
    (fp_text user "Author: Antmicro" (at -3.55 5 -90) (layer "F.Fab") hide
        (effects (font (size 0.7 0.7) (thickness 0.15)) (justify left bottom))
    )
    (fp_text user "License: Apache-2.0" (at -3.55 6.2 -90) (layer "F.Fab") hide
        (effects (font (size 0.7 0.7) (thickness 0.15)) (justify left bottom))
    )
    (fp_text user "${REFERENCE}" (at -3.55 7.4 -90) (layer "F.Fab") hide
        (effects (font (size 0.7 0.7) (thickness 0.15)) (justify left bottom))
    )
    (fp_line (start -2.3 -1.6) (end -1.7 -1.6)
      (stroke (width 0.15) (type solid)) (layer "F.SilkS"))
    (fp_line (start -2.3 -1.3) (end -2.3 -1.6)
      (stroke (width 0.15) (type solid)) (layer "F.SilkS"))
    (fp_line (start -2.3 1.3) (end -2.3 1.6)
      (stroke (width 0.15) (type solid)) (layer "F.SilkS"))
    (fp_line (start -2.3 1.6) (end -1.7 1.6)
      (stroke (width 0.15) (type solid)) (layer "F.SilkS"))
    (fp_line (start 2.3 -1.6) (end 1.8 -1.6)
      (stroke (width 0.15) (type solid)) (layer "F.SilkS"))
    (fp_line (start 2.3 -1.3) (end 2.3 -1.6)
      (stroke (width 0.15) (type solid)) (layer "F.SilkS"))
    (fp_line (start 2.3 1.25) (end 2.3 1.6)
      (stroke (width 0.15) (type solid)) (layer "F.SilkS"))
    (fp_line (start 2.3 1.6) (end 1.8 1.6)
      (stroke (width 0.15) (type solid)) (layer "F.SilkS"))
    (fp_circle (center -2.7 -1.51) (end -2.65 -1.51)
      (stroke (width 0.15) (type solid)) (fill solid) (layer "F.SilkS"))
    (fp_rect (start -3.45 -1.75) (end 3.45 1.75)
      (stroke (width 0.05) (type solid)) (fill none) (layer "F.CrtYd"))
    (fp_line (start -2.2 -0.7) (end -2.2 1.5)
      (stroke (width 0.15) (type solid)) (layer "F.Fab"))
    (fp_line (start -2.2 -0.7) (end -1.4 -1.5)
      (stroke (width 0.15) (type solid)) (layer "F.Fab"))
    (fp_line (start -2.2 1.5) (end 2.2 1.5)
      (stroke (width 0.15) (type solid)) (layer "F.Fab"))
    (fp_line (start -1.4 -1.5) (end 2.2 -1.5)
      (stroke (width 0.15) (type solid)) (layer "F.Fab"))
    (fp_line (start 2.2 -1.5) (end 2.2 1.5)
      (stroke (width 0.15) (type solid)) (layer "F.Fab"))
    (pad "1" smd rect (at -2.7 -0.975 270) (size 1.2 0.4) (layers "F.Cu" "F.Paste" "F.Mask")
      (net 2 "3V3_SYS") (pinfunction "VDD") (pintype "power_in"))
    (pad "2" smd rect (at -2.7 -0.325 270) (size 1.2 0.4) (layers "F.Cu" "F.Paste" "F.Mask")
      (net 115 "Net-(U6-XOUT)") (pinfunction "XOUT") (pintype "output"))
    (pad "3" smd rect (at -2.7 0.325 270) (size 1.2 0.4) (layers "F.Cu" "F.Paste" "F.Mask")
      (net 116 "Net-(U6-XIN{slash}CLKIN)") (pinfunction "XIN/CLKIN") (pintype "input"))
    (pad "4" smd rect (at -2.7 0.975 270) (size 1.2 0.4) (layers "F.Cu" "F.Paste" "F.Mask")
      (net 1 "GND") (pinfunction "GND") (pintype "power_in"))
    (pad "5" smd rect (at 2.7 0.975 270) (size 1.2 0.4) (layers "F.Cu" "F.Paste" "F.Mask")
      (net 44 "PCIE_CLK_CON_P") (pinfunction "DIFF1") (pintype "output"))
    (pad "6" smd rect (at 2.7 0.325 270) (size 1.2 0.4) (layers "F.Cu" "F.Paste" "F.Mask")
      (net 45 "PCIE_CLK_CON_N") (pinfunction "~{DIFF1}") (pintype "output"))
    (pad "7" smd rect (at 2.7 -0.325 270) (size 1.2 0.4) (layers "F.Cu" "F.Paste" "F.Mask")
      (net 72 "/TB Controller/PCIE_CLK_JHL_P") (pinfunction "DIFF2") (pintype "output"))
    (pad "8" smd rect (at 2.7 -0.975 270) (size 1.2 0.4) (layers "F.Cu" "F.Paste" "F.Mask")
      (net 73 "/TB Controller/PCIE_CLK_JHL_N") (pinfunction "~{DIFF2}") (pintype "output"))
  )

  (footprint "antmicro-footprints:USB-C_Receptacle_JAE_DX07S024JJ2" (layer "F.Cu")
    (at 166.25 76.053922 90)
    (property "Author" "Antmicro")
    (property "License" "Apache-2.0")
    (property "MPN" "DX07S024JJ2")
    (property "Manufacturer" "JAE Electronics")
    (property "Sheetfile" "connectors.kicad_sch")
    (property "Sheetname" "Connectors")
    (property "ki_description" "USB-C (USB TYPE-C) USB 3.2 Gen 2 (USB 3.1 Gen 2, Superspeed + (USB 3.1)) Receptacle Connector 24 Position Surface Mount, Right Angle")
    (property "ki_keywords" "USB, CONNECTOR, SMT, HORIZONTAL")
    (attr smd)
    (fp_text reference "J1" (at -6.750078 -0.896 180) (layer "F.SilkS")
        (effects (font (size 0.7 0.7) (thickness 0.15)) (justify left bottom))
    )
    (fp_text value "USB-C_JAE_DX07S024JJ2" (at -5 5.6 90) (layer "F.Fab")
        (effects (font (size 0.7 0.7) (thickness 0.15)) (justify left bottom))
    )
    (fp_text user "Author: Antmicro" (at -5.571 7.6 90) (layer "F.Fab") hide
        (effects (font (size 0.7 0.7) (thickness 0.15)) (justify left bottom))
    )
    (fp_text user "${REFERENCE}" (at -5.571 10 90) (layer "F.Fab") hide
        (effects (font (size 0.7 0.7) (thickness 0.15)) (justify left bottom))
    )
    (fp_text user "License: Apache-2.0" (at -5.571 8.8 90) (layer "F.Fab") hide
        (effects (font (size 0.7 0.7) (thickness 0.15)) (justify left bottom))
    )
    (fp_line (start -4.47 -1.645) (end -4.47 0.313)
      (stroke (width 0.15) (type solid)) (layer "F.SilkS"))
    (fp_line (start 4.469 -1.645) (end 4.469 0.313)
      (stroke (width 0.15) (type solid)) (layer "F.SilkS"))
    (fp_circle (center -2.625 -4.885) (end -2.576 -4.885)
      (stroke (width 0.15) (type solid)) (fill solid) (layer "F.SilkS"))
    (fp_rect (start -5.571 -4.885) (end 5.669 4.584)
      (stroke (width 0.05) (type solid)) (fill none) (layer "F.CrtYd"))
    (fp_line (start -4.96 -4.4) (end -4.81 -4.55)
      (stroke (width 0.15) (type solid)) (layer "F.Fab"))
    (fp_rect (start -4.971 -4.575) (end 4.969 4.084)
      (stroke (width 0.15) (type solid)) (fill none) (layer "F.Fab"))
    (pad "" np_thru_hole circle (at -3.601 -1.115 90) (size 0.63 0.63) (drill 0.63) (layers "*.Cu" "*.Mask"))
    (pad "" np_thru_hole oval (at 3.6 -1.18 90) (size 0.88 0.53) (drill oval 0.88 0.53) (layers "F&B.Cu" "*.Mask"))
    (pad "A1" smd rect (at -2.625 -3.817 90) (size 0.27 0.9) (layers "F.Cu" "F.Paste" "F.Mask")
      (net 1 "GND") (pinfunction "GND") (pintype "power_in"))
    (pad "A2" smd rect (at -2.125 -3.817 90) (size 0.27 0.9) (layers "F.Cu" "F.Paste" "F.Mask")
      (net 12 "TB_TX0_P") (pinfunction "TX_{1}+") (pintype "bidirectional"))
    (pad "A3" smd rect (at -1.625 -3.817 90) (size 0.27 0.9) (layers "F.Cu" "F.Paste" "F.Mask")
      (net 17 "TB_TX0_N") (pinfunction "TX_{1}-") (pintype "bidirectional"))
    (pad "A4" smd rect (at -1.125 -3.817 90) (size 0.27 0.9) (layers "F.Cu" "F.Paste" "F.Mask")
      (net 3 "5V0_USB") (pinfunction "VBUS") (pintype "passive"))
    (pad "A5" smd rect (at -0.625 -3.817 90) (size 0.27 0.9) (layers "F.Cu" "F.Paste" "F.Mask")
      (net 11 "CC1") (pinfunction "CC_{1}") (pintype "bidirectional"))
    (pad "A6" smd rect (at -0.125 -3.817 90) (size 0.27 0.9) (layers "F.Cu" "F.Paste" "F.Mask")
      (net 33 "USB_T_P") (pinfunction "D_{A}+") (pintype "bidirectional"))
    (pad "A7" smd rect (at 0.374 -3.817 90) (size 0.27 0.9) (layers "F.Cu" "F.Paste" "F.Mask")
      (net 34 "USB_T_N") (pinfunction "D_{A}-") (pintype "bidirectional"))
    (pad "A8" smd rect (at 0.874 -3.817 90) (size 0.27 0.9) (layers "F.Cu" "F.Paste" "F.Mask")
      (net 35 "SBU1") (pinfunction "SBU_{1}") (pintype "bidirectional"))
    (pad "A9" smd rect (at 1.374 -3.817 90) (size 0.27 0.9) (layers "F.Cu" "F.Paste" "F.Mask")
      (net 3 "5V0_USB") (pinfunction "VBUS") (pintype "passive"))
    (pad "A10" smd rect (at 1.874 -3.817 90) (size 0.27 0.9) (layers "F.Cu" "F.Paste" "F.Mask")
      (net 36 "TB_RX1_N") (pinfunction "RX_{2}-") (pintype "bidirectional"))
    (pad "A11" smd rect (at 2.374 -3.817 90) (size 0.27 0.9) (layers "F.Cu" "F.Paste" "F.Mask")
      (net 37 "TB_RX1_P") (pinfunction "RX_{2}+") (pintype "bidirectional"))
    (pad "A12" smd rect (at 2.874 -3.817 90) (size 0.27 0.9) (layers "F.Cu" "F.Paste" "F.Mask")
      (net 1 "GND") (pinfunction "GND") (pintype "passive"))
    (pad "B1" smd rect (at 2.624 -2.215 90) (size 0.27 0.8) (layers "F.Cu" "F.Paste" "F.Mask")
      (net 1 "GND") (pinfunction "GND") (pintype "passive"))
    (pad "B2" smd rect (at 2.124 -2.215 90) (size 0.27 0.8) (layers "F.Cu" "F.Paste" "F.Mask")
      (net 14 "TB_TX1_P") (pinfunction "TX_{2}+") (pintype "bidirectional"))
    (pad "B3" smd rect (at 1.624 -2.215 90) (size 0.27 0.8) (layers "F.Cu" "F.Paste" "F.Mask")
      (net 21 "TB_TX1_N") (pinfunction "TX_{2}-") (pintype "bidirectional"))
    (pad "B4" smd rect (at 1.124 -2.215 90) (size 0.27 0.8) (layers "F.Cu" "F.Paste" "F.Mask")
      (net 3 "5V0_USB") (pinfunction "VBUS") (pintype "passive"))
    (pad "B5" smd rect (at 0.624 -2.215 90) (size 0.27 0.8) (layers "F.Cu" "F.Paste" "F.Mask")
      (net 10 "CC2") (pinfunction "CC_{2}") (pintype "bidirectional"))
    (pad "B6" smd rect (at 0.124 -2.215 90) (size 0.27 0.8) (layers "F.Cu" "F.Paste" "F.Mask")
      (net 38 "USB_B_P") (pinfunction "D_{B}+") (pintype "bidirectional"))
    (pad "B7" smd rect (at -0.375 -2.215 90) (size 0.27 0.8) (layers "F.Cu" "F.Paste" "F.Mask")
      (net 39 "USB_B_N") (pinfunction "D_{B}-") (pintype "bidirectional"))
    (pad "B8" smd rect (at -0.875 -2.215 90) (size 0.27 0.8) (layers "F.Cu" "F.Paste" "F.Mask")
      (net 40 "SBU2") (pinfunction "SBU_{2}") (pintype "bidirectional"))
    (pad "B9" smd rect (at -1.375 -2.215 90) (size 0.27 0.8) (layers "F.Cu" "F.Paste" "F.Mask")
      (net 3 "5V0_USB") (pinfunction "VBUS") (pintype "passive"))
    (pad "B10" smd rect (at -1.875 -2.215 90) (size 0.27 0.8) (layers "F.Cu" "F.Paste" "F.Mask")
      (net 41 "TB_RX0_N") (pinfunction "RX_{1}-") (pintype "bidirectional"))
    (pad "B11" smd rect (at -2.375 -2.215 90) (size 0.27 0.8) (layers "F.Cu" "F.Paste" "F.Mask")
      (net 42 "TB_RX0_P") (pinfunction "RX_{1}+") (pintype "bidirectional"))
    (pad "B12" smd rect (at -2.875 -2.215 90) (size 0.27 0.8) (layers "F.Cu" "F.Paste" "F.Mask")
      (net 1 "GND") (pinfunction "GND") (pintype "passive"))
    (pad "SH" thru_hole oval (at -4.321 1.933 90) (size 1.3 2.6) (drill oval 0.75 2.05) (layers "*.Cu" "*.Mask")
      (net 1 "GND") (pinfunction "SH") (pintype "passive"))
    (pad "SH" thru_hole custom (at -4.32 -3.12 90) (size 1.2 1.2) (drill oval 0.6 1.9) (layers "*.Cu" "*.Mask")
      (net 1 "GND") (pinfunction "SH") (pintype "passive") (thermal_bridge_angle 90)
      (options (clearance outline) (anchor circle))
      (primitives
        (gr_line (start 0.6 0.6) (end 0 0.6) (width 1.1))
        (gr_line (start 0 -0.55) (end 0 0.55) (width 1.2))
      ))
    (pad "SH" thru_hole oval (at -3.99 -2.52 180) (size 1 1.55) (drill oval 0.7 1.25) (layers "*.Cu" "*.Mask")
      (net 1 "GND") (pinfunction "SH") (pintype "passive"))
    (pad "SH" thru_hole oval (at 3.99 -2.52) (size 1 1.55) (drill oval 0.7 1.25) (layers "*.Cu" "*.Mask")
      (net 1 "GND") (pinfunction "SH") (pintype "passive"))
    (pad "SH" thru_hole custom (at 4.32 -3.12 90) (size 1.2 1.2) (drill oval 0.6 1.9) (layers "*.Cu" "*.Mask")
      (net 1 "GND") (pinfunction "SH") (pintype "passive") (thermal_bridge_angle 90)
      (options (clearance outline) (anchor circle))
      (primitives
        (gr_line (start -0.6 0.6) (end 0 0.6) (width 1.1))
        (gr_line (start 0 -0.55) (end 0 0.55) (width 1.2))
      ))
    (pad "SH" thru_hole oval (at 4.32 1.933 90) (size 1.3 2.6) (drill oval 0.75 2.05) (layers "*.Cu" "*.Mask")
      (net 1 "GND") (pinfunction "SH") (pintype "passive"))
    (zone (net 0) (net_name "") (layer "F.Cu") (name "TOP_KEEPOUT") (hatch full 0.508)
      (connect_pads (clearance 0))
      (min_thickness 0.01) (filled_areas_thickness no)
      (keepout (tracks not_allowed) (vias not_allowed) (pads not_allowed) (copperpour not_allowed) (footprints allowed))
      (fill (thermal_gap 0.508) (thermal_bridge_width 0.508))
      (polygon
        (pts
          (xy 165.419992 72.154914)
          (xy 165.420073 72.954186)
          (xy 164.734081 72.955194)
          (xy 164.734 79.293922)
          (xy 165.5 79.293922)
          (xy 165.5 79.953922)
          (xy 166.883 79.953922)
          (xy 166.883 79.604922)
          (xy 169.483 79.604922)
          (xy 169.483 79.953922)
          (xy 169.983 79.953922)
          (xy 169.983 72.154922)
          (xy 169.483 72.154922)
          (xy 169.483 72.503922)
          (xy 166.883 72.503922)
          (xy 166.883 72.154922)
        )
      )
    )
  )

  (footprint "antmicro-footprints:C_0805_2012Metric" (layer "F.Cu")
    (at 163.34 65.35 90)
    (descr "Capacitor SMD 0805")
    (tags "capacitor SMD 0805")
    (property "Author" "Antmicro")
    (property "Dielectric" "X5R")
    (property "License" "Apache-2.0")
    (property "MPN" "CL21A226MAYNNNE")
    (property "Manufacturer" "Samsung Electro-Mechanics")
    (property "Sheetfile" "power.kicad_sch")
    (property "Sheetname" "Power")
    (property "Val" "22u")
    (property "Voltage" "25V")
    (property "ki_description" "SMT Multilayer Ceramic Capacitor, 22uF, +/-20%, 25V, X5R, 0805 [2012 Metric]")
    (property "ki_keywords" "0805, SMT, CAPACITOR, PASSIVE")
    (attr smd)
    (fp_text reference "C48" (at -4.119 0.388 90) (layer "F.SilkS")
        (effects (font (size 0.7 0.7) (thickness 0.15)) (justify left bottom))
    )
    (fp_text value "C_22u_25V_0805" (at -2.055717 1.963152 90) (layer "F.Fab")
        (effects (font (size 0.7 0.7) (thickness 0.15)) (justify left bottom))
    )
    (fp_text user "License: Apache-2.0" (at -1.9 4.947 90) (layer "F.Fab") hide
        (effects (font (size 0.7 0.7) (thickness 0.15)) (justify left bottom))
    )
    (fp_text user "Author: Antmicro" (at -1.9 5.947 90) (layer "F.Fab") hide
        (effects (font (size 0.7 0.7) (thickness 0.15)) (justify left bottom))
    )
    (fp_text user "${REFERENCE}" (at -1.9 3.947 90) (layer "F.Fab") hide
        (effects (font (size 0.7 0.7) (thickness 0.15)) (justify left bottom))
    )
    (fp_line (start -0.3 -0.7) (end 0.3 -0.7)
      (stroke (width 0.15) (type solid)) (layer "F.SilkS"))
    (fp_line (start -0.3 0.7) (end 0.3 0.7)
      (stroke (width 0.15) (type solid)) (layer "F.SilkS"))
    (fp_rect (start 1.95 -0.9) (end -1.95 0.9)
      (stroke (width 0.05) (type default)) (fill none) (layer "F.CrtYd"))
    (fp_rect (start -0.95 -0.675) (end 0.95 0.675)
      (stroke (width 0.15) (type solid)) (fill none) (layer "F.Fab"))
    (pad "1" smd roundrect (at -1.1 0 90) (size 1.2 1.3) (layers "F.Cu" "F.Paste" "F.Mask") (roundrect_rratio 0.25)
      (net 1 "GND") (pintype "passive"))
    (pad "2" smd roundrect (at 1.1 0 90) (size 1.2 1.3) (layers "F.Cu" "F.Paste" "F.Mask") (roundrect_rratio 0.25)
      (net 32 "VBUS") (pintype "passive"))
  )

  (footprint "antmicro-footprints:C_0603_1608Metric" (layer "F.Cu")
    (at 113.675 87.875)
    (descr "Capacitor SMD 0603")
    (tags "capacitor 0603")
    (property "Author" "Antmicro")
    (property "Dielectric" "")
    (property "License" "Apache-2.0")
    (property "MPN" "CL10A226MO7JZNC")
    (property "Manufacturer" "Samsung Electro-Mechanics")
    (property "Sheetfile" "power.kicad_sch")
    (property "Sheetname" "Power")
    (property "Val" "22u")
    (property "Voltage" "16V")
    (property "ki_description" "SMD Multilayer Ceramic Capacitor")
    (property "ki_keywords" "0603, SMT, CAPACITOR, PASSIVE, CERAMIC")
    (attr smd)
    (fp_text reference "C50" (at -1.026 -0.753) (layer "F.SilkS")
        (effects (font (size 0.7 0.7) (thickness 0.15)) (justify left bottom))
    )
    (fp_text value "C_22u_16V_0603" (at -1.42757 1.770288) (layer "F.Fab")
        (effects (font (size 0.7 0.7) (thickness 0.15)) (justify left bottom))
    )
    (fp_text user "${REFERENCE}" (at -1.682 3.895) (layer "F.Fab") hide
        (effects (font (size 0.7 0.7) (thickness 0.15)) (justify left bottom))
    )
    (fp_text user "License: Apache-2.0" (at -1.682 5.895) (layer "F.Fab") hide
        (effects (font (size 0.7 0.7) (thickness 0.15)) (justify left bottom))
    )
    (fp_text user "Author: Antmicro" (at -1.682 4.894) (layer "F.Fab") hide
        (effects (font (size 0.7 0.7) (thickness 0.15)) (justify left bottom))
    )
    (fp_line (start -0.15 -0.4) (end 0.15 -0.4)
      (stroke (width 0.15) (type solid)) (layer "F.SilkS"))
    (fp_line (start -0.15 0.4) (end 0.15 0.4)
      (stroke (width 0.15) (type solid)) (layer "F.SilkS"))
    (fp_rect (start -1.25 -0.65) (end 1.25 0.65)
      (stroke (width 0.05) (type solid)) (fill none) (layer "F.CrtYd"))
    (fp_rect (start -0.8 -0.4) (end 0.8 0.4)
      (stroke (width 0.15) (type solid)) (fill none) (layer "F.Fab"))
    (pad "1" smd roundrect (at -0.7 0) (size 0.8 1) (layers "F.Cu" "F.Paste" "F.Mask") (roundrect_rratio 0.2)
      (net 1 "GND") (pintype "passive"))
    (pad "2" smd roundrect (at 0.7 0) (size 0.8 1) (layers "F.Cu" "F.Paste" "F.Mask") (roundrect_rratio 0.2)
      (net 60 "12V0_DCDC") (pintype "passive"))
  )

  (footprint "antmicro-footprints:C_0805_2012Metric" (layer "F.Cu")
    (at 161.41 65.35 90)
    (descr "Capacitor SMD 0805")
    (tags "capacitor SMD 0805")
    (property "Author" "Antmicro")
    (property "Dielectric" "X5R")
    (property "License" "Apache-2.0")
    (property "MPN" "CL21A226MAYNNNE")
    (property "Manufacturer" "Samsung Electro-Mechanics")
    (property "Sheetfile" "power.kicad_sch")
    (property "Sheetname" "Power")
    (property "Val" "22u")
    (property "Voltage" "25V")
    (property "ki_description" "SMT Multilayer Ceramic Capacitor, 22uF, +/-20%, 25V, X5R, 0805 [2012 Metric]")
    (property "ki_keywords" "0805, SMT, CAPACITOR, PASSIVE")
    (attr smd)
    (fp_text reference "C42" (at -4.119 0.388 90) (layer "F.SilkS")
        (effects (font (size 0.7 0.7) (thickness 0.15)) (justify left bottom))
    )
    (fp_text value "C_22u_25V_0805" (at -2.055717 1.963152 90) (layer "F.Fab")
        (effects (font (size 0.7 0.7) (thickness 0.15)) (justify left bottom))
    )
    (fp_text user "${REFERENCE}" (at -1.9 3.947 90) (layer "F.Fab") hide
        (effects (font (size 0.7 0.7) (thickness 0.15)) (justify left bottom))
    )
    (fp_text user "License: Apache-2.0" (at -1.9 4.947 90) (layer "F.Fab") hide
        (effects (font (size 0.7 0.7) (thickness 0.15)) (justify left bottom))
    )
    (fp_text user "Author: Antmicro" (at -1.9 5.947 90) (layer "F.Fab") hide
        (effects (font (size 0.7 0.7) (thickness 0.15)) (justify left bottom))
    )
    (fp_line (start -0.3 -0.7) (end 0.3 -0.7)
      (stroke (width 0.15) (type solid)) (layer "F.SilkS"))
    (fp_line (start -0.3 0.7) (end 0.3 0.7)
      (stroke (width 0.15) (type solid)) (layer "F.SilkS"))
    (fp_rect (start 1.95 -0.9) (end -1.95 0.9)
      (stroke (width 0.05) (type default)) (fill none) (layer "F.CrtYd"))
    (fp_rect (start -0.95 -0.675) (end 0.95 0.675)
      (stroke (width 0.15) (type solid)) (fill none) (layer "F.Fab"))
    (pad "1" smd roundrect (at -1.1 0 90) (size 1.2 1.3) (layers "F.Cu" "F.Paste" "F.Mask") (roundrect_rratio 0.25)
      (net 1 "GND") (pintype "passive"))
    (pad "2" smd roundrect (at 1.1 0 90) (size 1.2 1.3) (layers "F.Cu" "F.Paste" "F.Mask") (roundrect_rratio 0.25)
      (net 32 "VBUS") (pintype "passive"))
  )

  (footprint "antmicro-footprints:Vishay_PowerPAK_1212-8_Single" (layer "F.Cu")
    (at 115.2475 90.8)
    (descr "PowerPAK 1212-8 Single")
    (tags "Vishay PowerPAK 1212-8 Single")
    (property "Author" "Antmicro")
    (property "License" "Apache-2.0")
    (property "MPN" "SI7613DN-T1-GE3")
    (property "Manufacturer" "Vishay")
    (property "Sheetfile" "power.kicad_sch")
    (property "Sheetname" "Power")
    (property "ki_description" "Power MOSFET, P Channel, 20 V, 35 A, 0.0072 ohm, PowerPAK 1212, Surface Mount")
    (property "ki_keywords" "SMT, TRANSISTOR, SEMICONDUCTOR, MOSFET, PMOS")
    (attr smd)
    (fp_text reference "Q6" (at 2.4815 3.18) (layer "F.SilkS")
        (effects (font (size 0.7 0.7) (thickness 0.15)) (justify left bottom))
    )
    (fp_text value "SI7613DN-T1-GE3" (at 0 2.7) (layer "F.Fab")
        (effects (font (size 0.7 0.7) (thickness 0.15)) (justify left bottom))
    )
    (fp_text user "Author: Antmicro" (at -8 5.9) (layer "F.Fab") hide
        (effects (font (size 0.7 0.7) (thickness 0.15)) (justify left bottom))
    )
    (fp_text user "${REFERENCE}" (at -8 4.7) (layer "F.Fab") hide
        (effects (font (size 0.7 0.7) (thickness 0.15)) (justify left bottom))
    )
    (fp_text user "License: Apache-2.0" (at -8 7.1) (layer "F.Fab") hide
        (effects (font (size 0.7 0.7) (thickness 0.15)) (justify left bottom))
    )
    (fp_line (start -1.651 -1.651) (end -1.651 -1.317)
      (stroke (width 0.15) (type solid)) (layer "F.SilkS"))
    (fp_line (start -1.651 -1.651) (end 1.648 -1.651)
      (stroke (width 0.15) (type solid)) (layer "F.SilkS"))
    (fp_line (start -1.635 1.3) (end -1.635 1.634)
      (stroke (width 0.15) (type solid)) (layer "F.SilkS"))
    (fp_line (start -1.635 1.634) (end 1.634 1.634)
      (stroke (width 0.15) (type solid)) (layer "F.SilkS"))
    (fp_line (start 1.634 1.3) (end 1.634 1.634)
      (stroke (width 0.15) (type solid)) (layer "F.SilkS"))
    (fp_line (start 1.648 -1.651) (end 1.648 -1.317)
      (stroke (width 0.15) (type solid)) (layer "F.SilkS"))
    (fp_circle (center -1.9 -1.4) (end -1.85 -1.4)
      (stroke (width 0.15) (type solid)) (fill solid) (layer "F.SilkS"))
    (fp_rect (start -2 -1.8) (end 2 1.798)
      (stroke (width 0.05) (type solid)) (fill none) (layer "F.CrtYd"))
    (fp_line (start -1.6425 -1.4175) (end -1.4175 -1.6425)
      (stroke (width 0.15) (type solid)) (layer "F.Fab"))
    (fp_rect (start -1.651 -1.651) (end 1.648 1.648)
      (stroke (width 0.15) (type solid)) (fill none) (layer "F.Fab"))
    (pad "1" smd rect (at -1.436 -0.99) (size 0.99 0.405) (layers "F.Cu" "F.Paste" "F.Mask")
      (net 146 "Net-(Q4-S)") (pinfunction "S") (pintype "passive"))
    (pad "2" smd rect (at -1.436 -0.332) (size 0.99 0.405) (layers "F.Cu" "F.Paste" "F.Mask")
      (net 146 "Net-(Q4-S)") (pinfunction "S") (pintype "passive"))
    (pad "3" smd rect (at -1.436 0.33) (size 0.99 0.405) (layers "F.Cu" "F.Paste" "F.Mask")
      (net 146 "Net-(Q4-S)") (pinfunction "S") (pintype "passive"))
    (pad "4" smd rect (at -1.436 0.988) (size 0.99 0.405) (layers "F.Cu" "F.Paste" "F.Mask")
      (net 145 "Net-(Q4-BIAS)") (pinfunction "G") (pintype "passive"))
    (pad "5" smd custom (at 0.557 0) (size 1.725 2.235) (layers "F.Cu" "F.Paste" "F.Mask")
      (net 60 "12V0_DCDC") (pinfunction "D") (pintype "passive") (zone_connect 2)
      (options (clearance outline) (anchor rect))
      (primitives
        (gr_poly
          (pts
            (xy 0.8625 0.1275)
            (xy 0.8625 -0.1275)
            (xy 1.3725 -0.1275)
            (xy 1.3725 -0.5325)
            (xy 0.8625 -0.5325)
            (xy 0.8625 -0.7875)
            (xy 1.3725 -0.7875)
            (xy 1.3725 -1.195)
            (xy 0.6125 -1.195)
            (xy 0.6125 1.195)
            (xy 1.3725 1.195)
            (xy 1.3725 0.7875)
            (xy 0.8625 0.7875)
            (xy 0.8625 0.5325)
            (xy 1.3725 0.5325)
            (xy 1.3725 0.1275)
          )
          (width 0) (fill yes))
      ))
  )

  (footprint "antmicro-footprints:MP_Pad6mm_Drill3mm" (layer "F.Cu")
    (at 166 54)
    (property "Author" "Antmicro")
    (property "License" "Apache-2.0")
    (property "Sheetfile" "connectors.kicad_sch")
    (property "Sheetname" "Connectors")
    (property "exclude_from_bom" "")
    (property "ki_description" "Mechanical part")
    (property "ki_keywords" "MECHANICAL")
    (attr exclude_from_pos_files exclude_from_bom)
    (fp_text reference "MP2" (at 0 -3.2) (layer "F.SilkS") hide
        (effects (font (size 0.7 0.7) (thickness 0.15)) (justify left bottom))
    )
    (fp_text value "MP_Pad6mm_Drill3mm" (at 0 3.9) (layer "F.Fab")
        (effects (font (size 0.7 0.7) (thickness 0.15)) (justify left bottom))
    )
    (fp_text user "License: Apache-2.0" (at -0.178 8.425) (layer "F.Fab") hide
        (effects (font (size 0.7 0.7) (thickness 0.15)) (justify left bottom))
    )
    (fp_text user "${REFERENCE}" (at -0.178 6.025) (layer "F.Fab") hide
        (effects (font (size 0.7 0.7) (thickness 0.15)) (justify left bottom))
    )
    (fp_text user "Author: Antmicro" (at -0.178 7.225) (layer "F.Fab") hide
        (effects (font (size 0.7 0.7) (thickness 0.15)) (justify left bottom))
    )
    (fp_circle (center 0 0) (end 3.25 0)
      (stroke (width 0.05) (type default)) (fill none) (layer "F.CrtYd"))
    (pad "1" thru_hole circle (at 0 0) (size 6 6) (drill 3) (layers "*.Cu" "*.Mask")
      (net 1 "GND") (pintype "passive"))
  )

  (footprint "antmicro-footprints:TP_SMD_1mm" (layer "F.Cu")
    (at 125.4 59.99)
    (property "Author" "Antmicro")
    (property "License" "Apache-2.0")
    (property "MPN" "")
    (property "Manufacturer" "")
    (property "Sheetfile" "power.kicad_sch")
    (property "Sheetname" "Power")
    (property "exclude_from_bom" "")
    (property "ki_description" "Test point 1mm SMD")
    (property "ki_keywords" "TESTPOINT")
    (attr exclude_from_pos_files exclude_from_bom)
    (fp_text reference "TP7" (at 0.584 0.462) (layer "F.SilkS")
        (effects (font (size 0.7 0.7) (thickness 0.15)) (justify left bottom))
    )
    (fp_text value "TP_1mm_SMD" (at 0 1.4) (layer "F.Fab")
        (effects (font (size 0.7 0.7) (thickness 0.15)) (justify left bottom))
    )
    (fp_text user "Author: Antmicro" (at -0.5 4) (layer "F.Fab") hide
        (effects (font (size 0.7 0.7) (thickness 0.15)) (justify left bottom))
    )
    (fp_text user "License: Apache-2.0" (at -0.5 5.2) (layer "F.Fab") hide
        (effects (font (size 0.7 0.7) (thickness 0.15)) (justify left bottom))
    )
    (fp_text user "${REFERENCE}" (at -0.5 2.8) (layer "F.Fab") hide
        (effects (font (size 0.7 0.7) (thickness 0.15)) (justify left bottom))
    )
    (fp_circle (center 0 0) (end 0.6 0)
      (stroke (width 0.05) (type default)) (fill none) (layer "F.CrtYd"))
    (pad "1" smd circle (at 0 0) (size 1 1) (layers "F.Cu" "F.Mask")
      (net 100 "Net-(D2-A)") (pinfunction "1") (pintype "passive"))
  )

  (footprint "antmicro-footprints:L_Coilcraft-XAL7070" (layer "F.Cu")
    (at 110.325 72.8)
    (property "Author" "Antmicro")
    (property "IMax" "9.2 A")
    (property "ISat" "12.8 A")
    (property "License" "Apache-2.0")
    (property "MPN" "XAL7070-682MEC")
    (property "Manufacturer" "Coilcraft")
    (property "Sheetfile" "power.kicad_sch")
    (property "Sheetname" "Power")
    (property "Size" "7.7x8")
    (property "Val" "6u8/12.8A")
    (property "ki_description" "Power Inductor (SMT), 6.8 µH, 9.2 A, Shielded, 12.8 A, XAL7070")
    (property "ki_keywords" "SMT, INDUCTOR, PASSIVE")
    (attr smd)
    (fp_text reference "L1" (at -4.026 -4.474) (layer "F.SilkS")
        (effects (font (size 0.7 0.7) (thickness 0.15)) (justify left bottom))
    )
    (fp_text value "L_6u8_12.8A_Coilcraft-XAL7070" (at 0 5.2) (layer "F.Fab")
        (effects (font (size 0.7 0.7) (thickness 0.15)) (justify left bottom))
    )
    (fp_text user "Author: Antmicro" (at -4.09 7.2) (layer "F.Fab") hide
        (effects (font (size 0.7 0.7) (thickness 0.15)) (justify left bottom))
    )
    (fp_text user "${REFERENCE}" (at -4.09 8.4) (layer "F.Fab") hide
        (effects (font (size 0.7 0.7) (thickness 0.15)) (justify left bottom))
    )
    (fp_text user "License: Apache-2.0" (at -4.09 9.6) (layer "F.Fab") hide
        (effects (font (size 0.7 0.7) (thickness 0.15)) (justify left bottom))
    )
    (fp_line (start -3.85 4) (end -3.85 -4)
      (stroke (width 0.15) (type solid)) (layer "F.SilkS"))
    (fp_line (start -3.85 4) (end 3.85 4)
      (stroke (width 0.15) (type solid)) (layer "F.SilkS"))
    (fp_line (start 3.85 -4) (end -3.85 -4)
      (stroke (width 0.15) (type solid)) (layer "F.SilkS"))
    (fp_line (start 3.85 -4) (end 3.85 4)
      (stroke (width 0.15) (type solid)) (layer "F.SilkS"))
    (fp_rect (start -4.09 -4.25) (end 4.09 4.25)
      (stroke (width 0.05) (type solid)) (fill none) (layer "F.CrtYd"))
    (fp_line (start -3.85 -4) (end 3.85 -4)
      (stroke (width 0.15) (type solid)) (layer "F.Fab"))
    (fp_line (start -3.85 4) (end -3.85 -4)
      (stroke (width 0.15) (type solid)) (layer "F.Fab"))
    (fp_line (start 3.85 -4) (end 3.85 4)
      (stroke (width 0.15) (type solid)) (layer "F.Fab"))
    (fp_line (start 3.85 4) (end -3.85 4)
      (stroke (width 0.15) (type solid)) (layer "F.Fab"))
    (pad "1" smd roundrect (at -2.41 0) (size 1.92 6.5) (layers "F.Cu" "F.Paste" "F.Mask") (roundrect_rratio 0.1)
      (net 4 "Net-(C26-Pad2)") (pintype "passive"))
    (pad "2" smd roundrect (at 2.41 0) (size 1.92 6.5) (layers "F.Cu" "F.Paste" "F.Mask") (roundrect_rratio 0.1)
      (net 268 "Net-(C28-Pad2)") (pintype "passive"))
  )

  (footprint "antmicro-footprints:TP_SMD_1mm" (layer "F.Cu")
    (at 108.425 86.4)
    (property "Author" "Antmicro")
    (property "License" "Apache-2.0")
    (property "MPN" "")
    (property "Manufacturer" "")
    (property "Sheetfile" "power.kicad_sch")
    (property "Sheetname" "Power")
    (property "exclude_from_bom" "")
    (property "ki_description" "Test point 1mm SMD")
    (property "ki_keywords" "TESTPOINT")
    (attr exclude_from_pos_files exclude_from_bom)
    (fp_text reference "TP5" (at -4.666 -0.294) (layer "F.SilkS")
        (effects (font (size 0.7 0.7) (thickness 0.15)) (justify left bottom))
    )
    (fp_text value "TP_1mm_SMD" (at 0 1.4) (layer "F.Fab")
        (effects (font (size 0.7 0.7) (thickness 0.15)) (justify left bottom))
    )
    (fp_text user "${REFERENCE}" (at -0.5 2.8) (layer "F.Fab") hide
        (effects (font (size 0.7 0.7) (thickness 0.15)) (justify left bottom))
    )
    (fp_text user "Author: Antmicro" (at -0.5 4) (layer "F.Fab") hide
        (effects (font (size 0.7 0.7) (thickness 0.15)) (justify left bottom))
    )
    (fp_text user "License: Apache-2.0" (at -0.5 5.2) (layer "F.Fab") hide
        (effects (font (size 0.7 0.7) (thickness 0.15)) (justify left bottom))
    )
    (fp_circle (center 0 0) (end 0.6 0)
      (stroke (width 0.05) (type default)) (fill none) (layer "F.CrtYd"))
    (pad "1" smd circle (at 0 0) (size 1 1) (layers "F.Cu" "F.Mask")
      (net 206 "Net-(U1-ISMON)") (pinfunction "1") (pintype "passive"))
  )

  (footprint "antmicro-footprints:C_0603_1608Metric" (layer "F.Cu")
    (at 117.98 59.11)
    (descr "Capacitor SMD 0603")
    (tags "capacitor 0603")
    (property "Author" "Antmicro")
    (property "Dielectric" "")
    (property "License" "Apache-2.0")
    (property "MPN" "GRM188R60J226MEA0D")
    (property "Manufacturer" "Murata")
    (property "Sheetfile" "power.kicad_sch")
    (property "Sheetname" "Power")
    (property "Val" "22u")
    (property "Voltage" "")
    (property "ki_description" "SMD Multilayer Ceramic Capacitor, 22 µF, 6.3 V, 0603 [1608 Metric], ± 20%, X5R, GRM Series")
    (property "ki_keywords" "0603, SMT, CAPACITOR, PASSIVE, CERAMIC, MLCC")
    (attr smd)
    (fp_text reference "C44" (at -3.426 0.479) (layer "F.SilkS")
        (effects (font (size 0.7 0.7) (thickness 0.15)) (justify left bottom))
    )
    (fp_text value "C_22u_0603" (at -1.42757 1.770288) (layer "F.Fab")
        (effects (font (size 0.7 0.7) (thickness 0.15)) (justify left bottom))
    )
    (fp_text user "Author: Antmicro" (at -1.682 4.894) (layer "F.Fab") hide
        (effects (font (size 0.7 0.7) (thickness 0.15)) (justify left bottom))
    )
    (fp_text user "${REFERENCE}" (at -1.682 3.895) (layer "F.Fab") hide
        (effects (font (size 0.7 0.7) (thickness 0.15)) (justify left bottom))
    )
    (fp_text user "License: Apache-2.0" (at -1.682 5.895) (layer "F.Fab") hide
        (effects (font (size 0.7 0.7) (thickness 0.15)) (justify left bottom))
    )
    (fp_line (start -0.15 -0.4) (end 0.15 -0.4)
      (stroke (width 0.15) (type solid)) (layer "F.SilkS"))
    (fp_line (start -0.15 0.4) (end 0.15 0.4)
      (stroke (width 0.15) (type solid)) (layer "F.SilkS"))
    (fp_rect (start -1.25 -0.65) (end 1.25 0.65)
      (stroke (width 0.05) (type solid)) (fill none) (layer "F.CrtYd"))
    (fp_rect (start -0.8 -0.4) (end 0.8 0.4)
      (stroke (width 0.15) (type solid)) (fill none) (layer "F.Fab"))
    (pad "1" smd roundrect (at -0.7 0) (size 0.8 1) (layers "F.Cu" "F.Paste" "F.Mask") (roundrect_rratio 0.2)
      (net 1 "GND") (pintype "passive"))
    (pad "2" smd roundrect (at 0.7 0) (size 0.8 1) (layers "F.Cu" "F.Paste" "F.Mask") (roundrect_rratio 0.2)
      (net 100 "Net-(D2-A)") (pintype "passive"))
  )

  (footprint "antmicro-footprints:QFN-11_2x2mm_P0.5mm" (layer "F.Cu")
    (at 116.411001 64.686)
    (property "Author" "Antmicro")
    (property "License" "Apache-2.0")
    (property "MPN" "MP2386GG-P")
    (property "Manufacturer" "Monolithic Power Systems")
    (property "Sheetfile" "power.kicad_sch")
    (property "Sheetname" "Power")
    (property "ki_description" "DC/DC converter")
    (property "ki_keywords" "IC")
    (attr smd)
    (fp_text reference "U2" (at -0.587001 2.497 unlocked) (layer "F.SilkS")
        (effects (font (size 0.7 0.7) (thickness 0.15)) (justify left bottom))
    )
    (fp_text value "MP2386GG" (at -1.637158 2.644508 unlocked) (layer "F.Fab")
        (effects (font (size 0.7 0.7) (thickness 0.15)) (justify left bottom))
    )
    (fp_text user "License: Apache-2.0" (at -1.401 5.85) (layer "F.Fab") hide
        (effects (font (size 0.7 0.7) (thickness 0.15)) (justify left bottom))
    )
    (fp_text user "Author: Antmicro" (at -1.401 4.65) (layer "F.Fab") hide
        (effects (font (size 0.7 0.7) (thickness 0.15)) (justify left bottom))
    )
    (fp_text user "${REFERENCE}" (at -1.401 3.45) (layer "F.Fab") hide
        (effects (font (size 0.7 0.7) (thickness 0.15)) (justify left bottom))
    )
    (fp_line (start -1.25 -0.951) (end -1.25 -1.25)
      (stroke (width 0.15) (type solid)) (layer "F.SilkS"))
    (fp_line (start -1.25 1.249) (end -1.25 0.949)
      (stroke (width 0.15) (type solid)) (layer "F.SilkS"))
    (fp_line (start -0.951 1.249) (end -1.25 1.249)
      (stroke (width 0.15) (type solid)) (layer "F.SilkS"))
    (fp_line (start 0.949 -1.25) (end 1.249 -1.25)
      (stroke (width 0.15) (type solid)) (layer "F.SilkS"))
    (fp_line (start 1.249 -1.25) (end 1.249 -0.951)
      (stroke (width 0.15) (type solid)) (layer "F.SilkS"))
    (fp_line (start 1.249 0.949) (end 1.249 1.249)
      (stroke (width 0.15) (type solid)) (layer "F.SilkS"))
    (fp_line (start 1.249 1.249) (end 0.949 1.249)
      (stroke (width 0.15) (type solid)) (layer "F.SilkS"))
    (fp_circle (center -1.7 -1.1) (end -1.649 -1.1)
      (stroke (width 0.15) (type solid)) (fill solid) (layer "F.SilkS"))
    (fp_rect (start -1.5 -1.5) (end 1.498 1.498)
      (stroke (width 0.05) (type solid)) (fill none) (layer "F.CrtYd"))
    (fp_line (start -1.101 1.1) (end -1.101 -0.552)
      (stroke (width 0.15) (type solid)) (layer "F.Fab"))
    (fp_line (start -0.552 -1.101) (end -1.101 -0.552)
      (stroke (width 0.15) (type solid)) (layer "F.Fab"))
    (fp_line (start -0.552 -1.101) (end 1.1 -1.101)
      (stroke (width 0.15) (type solid)) (layer "F.Fab"))
    (fp_line (start 1.1 -1.101) (end 1.1 1.1)
      (stroke (width 0.15) (type solid)) (layer "F.Fab"))
    (fp_line (start 1.1 1.1) (end -1.101 1.1)
      (stroke (width 0.15) (type solid)) (layer "F.Fab"))
    (pad "1" smd roundrect (at -0.552 -0.25 180) (size 1.5 0.25) (layers "F.Cu" "F.Paste" "F.Mask") (roundrect_rratio 0.25)
      (net 90 "Net-(U2-VIN)") (pinfunction "VIN") (pintype "power_in"))
    (pad "2" smd roundrect (at -0.75 0.998 90) (size 0.7 0.25) (layers "F.Cu" "F.Paste" "F.Mask") (roundrect_rratio 0.25)
      (net 1 "GND") (pinfunction "PGND") (pintype "power_in"))
    (pad "3" smd roundrect (at -0.25 0.998 90) (size 0.7 0.25) (layers "F.Cu" "F.Paste" "F.Mask") (roundrect_rratio 0.25)
      (net 1 "GND") (pinfunction "PGND") (pintype "passive"))
    (pad "4" smd roundrect (at 0.248 0.998 90) (size 0.7 0.25) (layers "F.Cu" "F.Paste" "F.Mask") (roundrect_rratio 0.25)
      (net 1 "GND") (pinfunction "PGND") (pintype "passive"))
    (pad "5" smd roundrect (at 0.748 0.998 90) (size 0.7 0.25) (layers "F.Cu" "F.Paste" "F.Mask") (roundrect_rratio 0.25)
      (net 158 "Net-(U2-PG)") (pinfunction "PG") (pintype "open_collector"))
    (pad "6" smd roundrect (at 0.55 0.2 180) (size 1.5 0.25) (layers "F.Cu" "F.Paste" "F.Mask") (roundrect_rratio 0.25)
      (net 95 "Net-(U2-SW)") (pinfunction "SW") (pintype "power_out"))
    (pad "7" smd roundrect (at 0.949 -0.25 180) (size 0.7 0.25) (layers "F.Cu" "F.Paste" "F.Mask") (roundrect_rratio 0.25)
      (net 94 "Net-(U2-BST)") (pinfunction "BST") (pintype "input"))
    (pad "8" smd roundrect (at 0.748 -1 90) (size 0.7 0.25) (layers "F.Cu" "F.Paste" "F.Mask") (roundrect_rratio 0.25)
      (net 6 "/Power/SMPS_LDO") (pinfunction "VCC") (pintype "power_out"))
    (pad "9" smd roundrect (at 0.248 -1 90) (size 0.7 0.25) (layers "F.Cu" "F.Paste" "F.Mask") (roundrect_rratio 0.25)
      (net 1 "GND") (pinfunction "AGND") (pintype "power_in"))
    (pad "10" smd roundrect (at -0.25 -1 90) (size 0.7 0.25) (layers "F.Cu" "F.Paste" "F.Mask") (roundrect_rratio 0.25)
      (net 99 "Net-(U2-FB)") (pinfunction "FB") (pintype "input"))
    (pad "11" smd roundrect (at -0.75 -1 90) (size 0.7 0.25) (layers "F.Cu" "F.Paste" "F.Mask") (roundrect_rratio 0.25)
      (net 119 "Net-(D1-C)") (pinfunction "EN") (pintype "input"))
  )

  (footprint "antmicro-footprints:C_0805_2012Metric" (layer "F.Cu")
    (at 105.015 78.0825 -90)
    (descr "Capacitor SMD 0805")
    (tags "capacitor SMD 0805")
    (property "Author" "Antmicro")
    (property "Dielectric" "")
    (property "License" "Apache-2.0")
    (property "MPN" "GRM21BR6YA106KE43L")
    (property "Manufacturer" "Murata")
    (property "Sheetfile" "power.kicad_sch")
    (property "Sheetname" "Power")
    (property "Val" "10u")
    (property "Voltage" "35V")
    (property "ki_description" "SMD Multilayer Ceramic Capacitor, 10 µF, 35 V, 0805 [2012 Metric], ± 10%, X5R, GRM Series")
    (property "ki_keywords" "0805, SMT, CAPACITOR, PASSIVE")
    (attr smd)
    (fp_text reference "C11" (at 1.0385 -1.919 -90) (layer "F.SilkS")
        (effects (font (size 0.7 0.7) (thickness 0.15)) (justify left bottom))
    )
    (fp_text value "C_10u_0805_35V" (at -2.055717 1.963152 -90) (layer "F.Fab")
        (effects (font (size 0.7 0.7) (thickness 0.15)) (justify left bottom))
    )
    (fp_text user "License: Apache-2.0" (at -1.9 4.947 -90) (layer "F.Fab") hide
        (effects (font (size 0.7 0.7) (thickness 0.15)) (justify left bottom))
    )
    (fp_text user "${REFERENCE}" (at -1.9 3.947 -90) (layer "F.Fab") hide
        (effects (font (size 0.7 0.7) (thickness 0.15)) (justify left bottom))
    )
    (fp_text user "Author: Antmicro" (at -1.9 5.947 -90) (layer "F.Fab") hide
        (effects (font (size 0.7 0.7) (thickness 0.15)) (justify left bottom))
    )
    (fp_line (start -0.3 -0.7) (end 0.3 -0.7)
      (stroke (width 0.15) (type solid)) (layer "F.SilkS"))
    (fp_line (start -0.3 0.7) (end 0.3 0.7)
      (stroke (width 0.15) (type solid)) (layer "F.SilkS"))
    (fp_rect (start 1.95 -0.9) (end -1.95 0.9)
      (stroke (width 0.05) (type default)) (fill none) (layer "F.CrtYd"))
    (fp_rect (start -0.95 -0.675) (end 0.95 0.675)
      (stroke (width 0.15) (type solid)) (fill none) (layer "F.Fab"))
    (pad "1" smd roundrect (at -1.1 0 270) (size 1.2 1.3) (layers "F.Cu" "F.Paste" "F.Mask") (roundrect_rratio 0.25)
      (net 1 "GND") (pintype "passive"))
    (pad "2" smd roundrect (at 1.1 0 270) (size 1.2 1.3) (layers "F.Cu" "F.Paste" "F.Mask") (roundrect_rratio 0.25)
      (net 74 "Net-(C10-Pad2)") (pintype "passive"))
  )

  (footprint "antmicro-footprints:L_Vishay-IHLP1616BZ" (layer "F.Cu")
    (at 139.8 70.8 90)
    (property "Author" "Antmicro")
    (property "IMax" "7.6 A")
    (property "ISat" "6.8 A")
    (property "License" "Apache-2.0")
    (property "MPN" "IHLP1616BZERR68M5A")
    (property "Manufacturer" "Vishay")
    (property "Sheetfile" "tb-power.kicad_sch")
    (property "Sheetname" "Thunderbolt Controller - Power")
    (property "Size" "4.06x4.06")
    (property "Val" "680n/7.6A")
    (property "ki_description" "Power Inductor (SMT), 680 nH, 7.6 A, Shielded, 6.8 A, IHLP-1616BZ-5A")
    (property "ki_keywords" "SMT, INDUCTOR, PASSIVE")
    (attr smd)
    (fp_text reference "L3" (at -0.447 -2.597 90) (layer "F.SilkS")
        (effects (font (size 0.7 0.7) (thickness 0.15)) (justify left bottom))
    )
    (fp_text value "L_680n_7.6A_IHLP1616BZ" (at -0.016 3.253 90) (layer "F.Fab")
        (effects (font (size 0.7 0.7) (thickness 0.15)) (justify left bottom))
    )
    (fp_text user "License: Apache-2.0" (at -3.07 6.453 90) (layer "F.Fab") hide
        (effects (font (size 0.7 0.7) (thickness 0.15)) (justify left bottom))
    )
    (fp_text user "${REFERENCE}" (at -3.07 7.653 90) (layer "F.Fab") hide
        (effects (font (size 0.7 0.7) (thickness 0.15)) (justify left bottom))
    )
    (fp_text user "Author: Antmicro" (at -3.07 5.253 90) (layer "F.Fab") hide
        (effects (font (size 0.7 0.7) (thickness 0.15)) (justify left bottom))
    )
    (fp_line (start -2.044 -2.024) (end -2.044 -1.45)
      (stroke (width 0.15) (type solid)) (layer "F.SilkS"))
    (fp_line (start -2.044 2.031) (end -2.044 1.45)
      (stroke (width 0.15) (type solid)) (layer "F.SilkS"))
    (fp_line (start -2.044 2.031) (end 2.012 2.031)
      (stroke (width 0.15) (type solid)) (layer "F.SilkS"))
    (fp_line (start 2.012 -2.024) (end -2.044 -2.024)
      (stroke (width 0.15) (type solid)) (layer "F.SilkS"))
    (fp_line (start 2.012 -2.024) (end 2.012 -1.45)
      (stroke (width 0.15) (type solid)) (layer "F.SilkS"))
    (fp_line (start 2.012 2.031) (end 2.012 1.45)
      (stroke (width 0.15) (type solid)) (layer "F.SilkS"))
    (fp_line (start -3.07 1.4) (end -3.07 -1.4)
      (stroke (width 0.05) (type solid)) (layer "F.CrtYd"))
    (fp_line (start -2.475 -2.31) (end 2.475 -2.31)
      (stroke (width 0.05) (type solid)) (layer "F.CrtYd"))
    (fp_line (start -2.475 -1.4) (end -3.07 -1.4)
      (stroke (width 0.05) (type solid)) (layer "F.CrtYd"))
    (fp_line (start -2.475 -1.4) (end -2.475 -2.31)
      (stroke (width 0.05) (type solid)) (layer "F.CrtYd"))
    (fp_line (start -2.475 1.4) (end -3.07 1.4)
      (stroke (width 0.05) (type solid)) (layer "F.CrtYd"))
    (fp_line (start -2.475 1.4) (end -2.475 2.32)
      (stroke (width 0.05) (type solid)) (layer "F.CrtYd"))
    (fp_line (start -2.475 2.32) (end 2.475 2.32)
      (stroke (width 0.05) (type solid)) (layer "F.CrtYd"))
    (fp_line (start 2.475 -1.4) (end 2.475 -2.31)
      (stroke (width 0.05) (type solid)) (layer "F.CrtYd"))
    (fp_line (start 2.475 -1.4) (end 3.07 -1.4)
      (stroke (width 0.05) (type solid)) (layer "F.CrtYd"))
    (fp_line (start 2.475 1.4) (end 2.475 2.32)
      (stroke (width 0.05) (type solid)) (layer "F.CrtYd"))
    (fp_line (start 2.475 1.4) (end 3.07 1.4)
      (stroke (width 0.05) (type solid)) (layer "F.CrtYd"))
    (fp_line (start 3.07 1.4) (end 3.07 -1.4)
      (stroke (width 0.05) (type solid)) (layer "F.CrtYd"))
    (fp_rect (start -2.217 -2.065) (end 2.217 2.064)
      (stroke (width 0.15) (type solid)) (fill none) (layer "F.Fab"))
    (pad "1" smd roundrect (at -1.89225 0 180) (size 2.286 1.8545) (layers "F.Cu" "F.Paste" "F.Mask") (roundrect_rratio 0.1)
      (net 55 "Net-(L3-Pad1)") (pintype "passive"))
    (pad "2" smd roundrect (at 1.89225 0 180) (size 2.286 1.8545) (layers "F.Cu" "F.Paste" "F.Mask") (roundrect_rratio 0.1)
      (net 112 "Net-(U4A-VCC0P9_SVR_SENSE)") (pintype "passive"))
  )

  (footprint "antmicro-footprints:PCIE_TE_2-2387405-2" (layer "F.Cu")
    (at 128 100.776)
    (property "Author" "Antmicro")
    (property "License" "Apache-2.0")
    (property "MPN" "2-2387405-2")
    (property "Manufacturer" "TE Connectivity")
    (property "Sheetfile" "connectors.kicad_sch")
    (property "Sheetname" "Connectors")
    (property "ki_description" "64 Position Female Connector PCI Express™ Gold 0.039\" (1.00mm) Black")
    (property "ki_keywords" "SMT, PCIE, CONNECTOR")
    (attr smd)
    (fp_text reference "J2" (at 25.543 -1.208 180) (layer "F.SilkS")
        (effects (font (size 0.7 0.7) (thickness 0.15)) (justify left bottom))
    )
    (fp_text value "PCIe_x4_Conn_EdgeMount_Open" (at -5.7 -6.75) (layer "F.Fab")
        (effects (font (size 0.7 0.7) (thickness 0.15)) (justify left bottom))
    )
    (fp_text user "B32" (at 5.985 0.951 90) (layer "B.SilkS") hide
        (effects (font (size 0.7 0.7) (thickness 0.15)) (justify left bottom mirror))
    )
    (fp_text user "B1" (at -3.159 2.983 90) (layer "B.SilkS") hide
        (effects (font (size 0.7 0.7) (thickness 0.15)) (justify left bottom mirror))
    )
    (fp_text user "A32" (at 16.899 -5.8 90) (layer "F.SilkS") hide
        (effects (font (size 0.7 0.7) (thickness 0.15)) (justify left bottom))
    )
    (fp_text user "A1" (at -2.778 -5.78 90) (layer "F.SilkS") hide
        (effects (font (size 0.7 0.7) (thickness 0.15)) (justify left bottom))
    )
    (fp_text user "${REFERENCE}" (at -1.05 -7.95) (layer "F.Fab")
        (effects (font (size 0.7 0.7) (thickness 0.15)) (justify left bottom))
    )
    (fp_text user "License: Apache-2.0" (at -25.401 12.249) (layer "F.Fab") hide
        (effects (font (size 0.7 0.7) (thickness 0.15)) (justify left bottom))
    )
    (fp_text user "Author: Antmicro" (at -25.401 14.649) (layer "F.Fab") hide
        (effects (font (size 0.7 0.7) (thickness 0.15)) (justify left bottom))
    )
    (fp_line (start -24.45 -7.1) (end -24.45 -0.9)
      (stroke (width 0.12) (type solid)) (layer "B.SilkS"))
    (fp_line (start -24.45 -7.1) (end -17.9 -7.1)
      (stroke (width 0.12) (type solid)) (layer "B.SilkS"))
    (fp_line (start 24.44 -7.1) (end 17.89 -7.1)
      (stroke (width 0.12) (type solid)) (layer "B.SilkS"))
    (fp_line (start 24.44 -7.1) (end 24.44 -0.9)
      (stroke (width 0.12) (type solid)) (layer "B.SilkS"))
    (fp_circle (center -16.5 -5.8) (end -16.45 -5.8)
      (stroke (width 0.15) (type solid)) (fill solid) (layer "B.SilkS"))
    (fp_line (start -24.45 -7.1) (end -24.45 -0.9)
      (stroke (width 0.12) (type solid)) (layer "F.SilkS"))
    (fp_line (start -24.45 -7.1) (end -17.9 -7.1)
      (stroke (width 0.12) (type solid)) (layer "F.SilkS"))
    (fp_line (start 24.44 -7.1) (end 17.89 -7.1)
      (stroke (width 0.12) (type solid)) (layer "F.SilkS"))
    (fp_line (start 24.44 -7.1) (end 24.44 -0.9)
      (stroke (width 0.12) (type solid)) (layer "F.SilkS"))
    (fp_circle (center -16.5 -5.8) (end -16.45 -5.8)
      (stroke (width 0.15) (type solid)) (fill solid) (layer "F.SilkS"))
    (fp_rect (start -25.401 -10.25) (end 25.399 10.249)
      (stroke (width 0.05) (type solid)) (fill none) (layer "B.CrtYd"))
    (fp_rect (start -25.401 -10.25) (end 25.399 10.249)
      (stroke (width 0.05) (type solid)) (fill none) (layer "F.CrtYd"))
    (fp_line (start -24.401 -8.35) (end -23.5 -9.25)
      (stroke (width 0.15) (type solid)) (layer "F.Fab"))
    (fp_rect (start -24.401 -9.25) (end 24.399 9.249)
      (stroke (width 0.15) (type solid)) (fill none) (layer "F.Fab"))
    (pad "" np_thru_hole circle (at -21.299 -3.274) (size 2 2) (drill 2) (layers "F&B.Cu" "*.Mask"))
    (pad "" np_thru_hole circle (at 21.301 -3.274) (size 2 2) (drill 2) (layers "F&B.Cu" "*.Mask"))
    (pad "A1" smd rect (at -16.5 -3.326) (size 0.7 4.2) (layers "F.Cu" "F.Paste" "F.Mask")
      (net 124 "unconnected-(J2-PRSNT#1-PadA1)") (pinfunction "PRSNT#1") (pintype "passive+no_connect"))
    (pad "A2" smd rect (at -15.5 -3.326) (size 0.7 4.2) (layers "F.Cu" "F.Paste" "F.Mask")
      (net 8 "12V0_PCIE") (pinfunction "+12V") (pintype "passive"))
    (pad "A3" smd rect (at -14.5 -3.326) (size 0.7 4.2) (layers "F.Cu" "F.Paste" "F.Mask")
      (net 8 "12V0_PCIE") (pinfunction "+12V") (pintype "passive"))
    (pad "A4" smd rect (at -13.5 -3.326) (size 0.7 4.2) (layers "F.Cu" "F.Paste" "F.Mask")
      (net 1 "GND") (pinfunction "GND") (pintype "passive"))
    (pad "A5" smd rect (at -12.5 -3.326) (size 0.7 4.2) (layers "F.Cu" "F.Paste" "F.Mask")
      (net 125 "unconnected-(J2-JTAG2-PadA5)") (pinfunction "JTAG2") (pintype "passive+no_connect"))
    (pad "A6" smd rect (at -11.5 -3.326) (size 0.7 4.2) (layers "F.Cu" "F.Paste" "F.Mask")
      (net 126 "unconnected-(J2-JTAG3-PadA6)") (pinfunction "JTAG3") (pintype "passive+no_connect"))
    (pad "A7" smd rect (at -10.5 -3.326) (size 0.7 4.2) (layers "F.Cu" "F.Paste" "F.Mask")
      (net 127 "unconnected-(J2-JTAG4-PadA7)") (pinfunction "JTAG4") (pintype "passive+no_connect"))
    (pad "A8" smd rect (at -9.5 -3.326) (size 0.7 4.2) (layers "F.Cu" "F.Paste" "F.Mask")
      (net 128 "unconnected-(J2-JTAG5-PadA8)") (pinfunction "JTAG5") (pintype "passive+no_connect"))
    (pad "A9" smd rect (at -8.5 -3.326) (size 0.7 4.2) (layers "F.Cu" "F.Paste" "F.Mask")
      (net 2 "3V3_SYS") (pinfunction "+3V3") (pintype "passive"))
    (pad "A10" smd rect (at -7.5 -3.326) (size 0.7 4.2) (layers "F.Cu" "F.Paste" "F.Mask")
      (net 2 "3V3_SYS") (pinfunction "+3V3") (pintype "passive"))
    (pad "A11" smd rect (at -6.5 -3.326) (size 0.7 4.2) (layers "F.Cu" "F.Paste" "F.Mask")
      (net 43 "PCIE_PWRGD") (pinfunction "PWRGD") (pintype "passive"))
    (pad "A12" smd rect (at -3.5 -3.326) (size 0.7 4.2) (layers "F.Cu" "F.Paste" "F.Mask")
      (net 1 "GND") (pinfunction "GND") (pintype "passive"))
    (pad "A13" smd rect (at -2.5 -3.326) (size 0.7 4.2) (layers "F.Cu" "F.Paste" "F.Mask")
      (net 44 "PCIE_CLK_CON_P") (pinfunction "REFCLK+") (pintype "passive"))
    (pad "A14" smd rect (at -1.5 -3.326) (size 0.7 4.2) (layers "F.Cu" "F.Paste" "F.Mask")
      (net 45 "PCIE_CLK_CON_N") (pinfunction "REFCLK-") (pintype "passive"))
    (pad "A15" smd rect (at -0.5 -3.326) (size 0.7 4.2) (layers "F.Cu" "F.Paste" "F.Mask")
      (net 1 "GND") (pinfunction "GND") (pintype "passive"))
    (pad "A16" smd rect (at 0.496 -3.326) (size 0.7 4.2) (layers "F.Cu" "F.Paste" "F.Mask")
      (net 46 "PCIE_RX0_P") (pinfunction "HSIp(0)") (pintype "passive"))
    (pad "A17" smd rect (at 1.499 -3.326) (size 0.7 4.2) (layers "F.Cu" "F.Paste" "F.Mask")
      (net 47 "PCIE_RX0_N") (pinfunction "HSIn(0)") (pintype "passive"))
    (pad "A18" smd rect (at 2.499 -3.326) (size 0.7 4.2) (layers "F.Cu" "F.Paste" "F.Mask")
      (net 1 "GND") (pinfunction "GND") (pintype "passive"))
    (pad "A19" smd rect (at 3.499 -3.326) (size 0.7 4.2) (layers "F.Cu" "F.Paste" "F.Mask")
      (net 129 "unconnected-(J2-RSVD-PadA19)") (pinfunction "RSVD") (pintype "passive+no_connect"))
    (pad "A20" smd rect (at 4.498 -3.326) (size 0.7 4.2) (layers "F.Cu" "F.Paste" "F.Mask")
      (net 1 "GND") (pinfunction "GND") (pintype "passive"))
    (pad "A21" smd rect (at 5.499 -3.326) (size 0.7 4.2) (layers "F.Cu" "F.Paste" "F.Mask")
      (net 48 "PCIE_RX1_P") (pinfunction "HSIp(1)") (pintype "passive"))
    (pad "A22" smd rect (at 6.499 -3.326) (size 0.7 4.2) (layers "F.Cu" "F.Paste" "F.Mask")
      (net 49 "PCIE_RX1_N") (pinfunction "HSIn(1)") (pintype "passive"))
    (pad "A23" smd rect (at 7.499 -3.326) (size 0.7 4.2) (layers "F.Cu" "F.Paste" "F.Mask")
      (net 1 "GND") (pinfunction "GND") (pintype "passive"))
    (pad "A24" smd rect (at 8.499 -3.326) (size 0.7 4.2) (layers "F.Cu" "F.Paste" "F.Mask")
      (net 1 "GND") (pinfunction "GND") (pintype "passive"))
    (pad "A25" smd rect (at 9.499 -3.326) (size 0.7 4.2) (layers "F.Cu" "F.Paste" "F.Mask")
      (net 50 "PCIE_RX2_P") (pinfunction "HSIp(2)") (pintype "passive"))
    (pad "A26" smd rect (at 10.499 -3.326) (size 0.7 4.2) (layers "F.Cu" "F.Paste" "F.Mask")
      (net 51 "PCIE_RX2_N") (pinfunction "HSIn(2)") (pintype "passive"))
    (pad "A27" smd rect (at 11.499 -3.326) (size 0.7 4.2) (layers "F.Cu" "F.Paste" "F.Mask")
      (net 1 "GND") (pinfunction "GND") (pintype "passive"))
    (pad "A28" smd rect (at 12.499 -3.326) (size 0.7 4.2) (layers "F.Cu" "F.Paste" "F.Mask")
      (net 1 "GND") (pinfunction "GND") (pintype "input"))
    (pad "A29" smd rect (at 13.499 -3.326) (size 0.7 4.2) (layers "F.Cu" "F.Paste" "F.Mask")
      (net 52 "PCIE_RX3_P") (pinfunction "HSIp(3)") (pintype "passive"))
    (pad "A30" smd rect (at 14.499 -3.326) (size 0.7 4.2) (layers "F.Cu" "F.Paste" "F.Mask")
      (net 53 "PCIE_RX3_N") (pinfunction "HSIn(3)") (pintype "passive"))
    (pad "A31" smd rect (at 15.499 -3.326) (size 0.7 4.2) (layers "F.Cu" "F.Paste" "F.Mask")
      (net 1 "GND") (pinfunction "GND") (pintype "passive"))
    (pad "A32" smd rect (at 16.498 -3.326) (size 0.7 4.2) (layers "F.Cu" "F.Paste" "F.Mask")
      (net 130 "unconnected-(J2-RSVD-PadA32)") (pinfunction "RSVD") (pintype "passive+no_connect"))
    (pad "B1" smd rect (at -16.5 -3.331) (size 0.7 4.2) (layers "B.Cu" "B.Paste" "B.Mask")
      (net 8 "12V0_PCIE") (pinfunction "+12V") (pintype "passive"))
    (pad "B2" smd rect (at -15.5 -3.331) (size 0.7 4.2) (layers "B.Cu" "B.Paste" "B.Mask")
      (net 8 "12V0_PCIE") (pinfunction "+12V") (pintype "passive"))
    (pad "B3" smd rect (at -14.5 -3.331) (size 0.7 4.2) (layers "B.Cu" "B.Paste" "B.Mask")
      (net 8 "12V0_PCIE") (pinfunction "+12V") (pintype "passive"))
    (pad "B4" smd rect (at -13.5 -3.331) (size 0.7 4.2) (layers "B.Cu" "B.Paste" "B.Mask")
      (net 1 "GND") (pinfunction "GND") (pintype "passive"))
    (pad "B5" smd rect (at -12.5 -3.331) (size 0.7 4.2) (layers "B.Cu" "B.Paste" "B.Mask")
      (net 131 "unconnected-(J2-SMCLK-PadB5)") (pinfunction "SMCLK") (pintype "passive+no_connect"))
    (pad "B6" smd rect (at -11.5 -3.331) (size 0.7 4.2) (layers "B.Cu" "B.Paste" "B.Mask")
      (net 132 "unconnected-(J2-SMDAT-PadB6)") (pinfunction "SMDAT") (pintype "passive+no_connect"))
    (pad "B7" smd rect (at -10.5 -3.331) (size 0.7 4.2) (layers "B.Cu" "B.Paste" "B.Mask")
      (net 1 "GND") (pinfunction "GND") (pintype "passive"))
    (pad "B8" smd rect (at -9.5 -3.331) (size 0.7 4.2) (layers "B.Cu" "B.Paste" "B.Mask")
      (net 2 "3V3_SYS") (pinfunction "+3V3") (pintype "passive"))
    (pad "B9" smd rect (at -8.5 -3.331) (size 0.7 4.2) (layers "B.Cu" "B.Paste" "B.Mask")
      (net 133 "unconnected-(J2-JTAG1-PadB9)") (pinfunction "JTAG1") (pintype "passive+no_connect"))
    (pad "B10" smd rect (at -7.5 -3.331) (size 0.7 4.2) (layers "B.Cu" "B.Paste" "B.Mask")
      (net 2 "3V3_SYS") (pinfunction "+3V3aux") (pintype "passive"))
    (pad "B11" smd rect (at -6.5 -3.331) (size 0.7 4.2) (layers "B.Cu" "B.Paste" "B.Mask")
      (net 54 "PCIE_WAKE") (pinfunction "WAKE#") (pintype "passive"))
    (pad "B12" smd rect (at -3.5 -3.331) (size 0.7 4.2) (layers "B.Cu" "B.Paste" "B.Mask")
      (net 134 "unconnected-(J2-RSVD-PadB12)") (pinfunction "RSVD") (pintype "passive+no_connect"))
    (pad "B13" smd rect (at -2.5 -3.331) (size 0.7 4.2) (layers "B.Cu" "B.Paste" "B.Mask")
      (net 1 "GND") (pinfunction "GND") (pintype "passive"))
    (pad "B14" smd rect (at -1.5 -3.331) (size 0.7 4.2) (layers "B.Cu" "B.Paste" "B.Mask")
      (net 28 "PCIE_TX0_P") (pinfunction "HSOp(0)") (pintype "passive"))
    (pad "B15" smd rect (at -0.5 -3.331) (size 0.7 4.2) (layers "B.Cu" "B.Paste" "B.Mask")
      (net 24 "PCIE_TX0_N") (pinfunction "HSOn(0)") (pintype "passive"))
    (pad "B16" smd rect (at 0.496 -3.331) (size 0.7 4.2) (layers "B.Cu" "B.Paste" "B.Mask")
      (net 1 "GND") (pinfunction "GND") (pintype "passive"))
    (pad "B17" smd rect (at 1.499 -3.331) (size 0.7 4.2) (layers "B.Cu" "B.Paste" "B.Mask")
      (net 135 "unconnected-(J2-PRSNT#2-PadB17)") (pinfunction "PRSNT#2") (pintype "passive+no_connect"))
    (pad "B18" smd rect (at 2.499 -3.331) (size 0.7 4.2) (layers "B.Cu" "B.Paste" "B.Mask")
      (net 1 "GND") (pinfunction "GND") (pintype "passive"))
    (pad "B19" smd rect (at 3.499 -3.331) (size 0.7 4.2) (layers "B.Cu" "B.Paste" "B.Mask")
      (net 29 "PCIE_TX1_P") (pinfunction "HSOp(1)") (pintype "passive"))
    (pad "B20" smd rect (at 4.498 -3.331) (size 0.7 4.2) (layers "B.Cu" "B.Paste" "B.Mask")
      (net 25 "PCIE_TX1_N") (pinfunction "HSOn(1)") (pintype "passive"))
    (pad "B21" smd rect (at 5.499 -3.331) (size 0.7 4.2) (layers "B.Cu" "B.Paste" "B.Mask")
      (net 1 "GND") (pinfunction "GND") (pintype "passive"))
    (pad "B22" smd rect (at 6.499 -3.331) (size 0.7 4.2) (layers "B.Cu" "B.Paste" "B.Mask")
      (net 1 "GND") (pinfunction "GND") (pintype "passive"))
    (pad "B23" smd rect (at 7.499 -3.331) (size 0.7 4.2) (layers "B.Cu" "B.Paste" "B.Mask")
      (net 30 "PCIE_TX2_P") (pinfunction "HSOp(2)") (pintype "passive"))
    (pad "B24" smd rect (at 8.499 -3.331) (size 0.7 4.2) (layers "B.Cu" "B.Paste" "B.Mask")
      (net 26 "PCIE_TX2_N") (pinfunction "HSOn(2)") (pintype "passive"))
    (pad "B25" smd rect (at 9.499 -3.331) (size 0.7 4.2) (layers "B.Cu" "B.Paste" "B.Mask")
      (net 1 "GND") (pinfunction "GND") (pintype "passive"))
    (pad "B26" smd rect (at 10.499 -3.331) (size 0.7 4.2) (layers "B.Cu" "B.Paste" "B.Mask")
      (net 1 "GND") (pinfunction "GND") (pintype "passive"))
    (pad "B27" smd rect (at 11.499 -3.331) (size 0.7 4.2) (layers "B.Cu" "B.Paste" "B.Mask")
      (net 31 "PCIE_TX3_P") (pinfunction "HSOp(3)") (pintype "passive"))
    (pad "B28" smd rect (at 12.499 -3.331) (size 0.7 4.2) (layers "B.Cu" "B.Paste" "B.Mask")
      (net 27 "PCIE_TX3_N") (pinfunction "HSOn(3)") (pintype "passive"))
    (pad "B29" smd rect (at 13.499 -3.331) (size 0.7 4.2) (layers "B.Cu" "B.Paste" "B.Mask")
      (net 1 "GND") (pinfunction "GND") (pintype "passive"))
    (pad "B30" smd rect (at 14.499 -3.331) (size 0.7 4.2) (layers "B.Cu" "B.Paste" "B.Mask")
      (net 136 "unconnected-(J2-RSVD-PadB30)") (pinfunction "RSVD") (pintype "passive+no_connect"))
    (pad "B31" smd rect (at 15.499 -3.331) (size 0.7 4.2) (layers "B.Cu" "B.Paste" "B.Mask")
      (net 137 "unconnected-(J2-PRSNT#2-PadB31)") (pinfunction "PRSNT#2") (pintype "passive+no_connect"))
    (pad "B32" smd rect (at 16.498 -3.331) (size 0.7 4.2) (layers "B.Cu" "B.Paste" "B.Mask")
      (net 1 "GND") (pinfunction "GND") (pintype "passive"))
  )

  (footprint "antmicro-footprints:C_1206_3216Metric" (layer "F.Cu")
    (at 113.470001 64.255 90)
    (descr "Capacitor SMD 1206")
    (tags "capacitor SMD 1206")
    (property "Author" "Antmicro")
    (property "Dielectric" "")
    (property "License" "Apache-2.0")
    (property "MPN" "3216X5R1V226M160AC")
    (property "Manufacturer" "TDK")
    (property "Sheetfile" "power.kicad_sch")
    (property "Sheetname" "Power")
    (property "Val" "22u")
    (property "Voltage" "35V")
    (property "ki_description" "SMD Multilayer Ceramic Capacitors, 22µF, 35V, X5R, 1206 [2316 Metric], 20% ")
    (property "ki_keywords" "1206, SMT, CAPACITOR, PASSIVE, CERAMIC, MLCC")
    (attr smd)
    (fp_text reference "C17" (at -4.452 0.321999 90) (layer "F.SilkS")
        (effects (font (size 0.7 0.7) (thickness 0.15)) (justify left bottom))
    )
    (fp_text value "C_22u_1206_35V" (at 0 2.101 90) (layer "F.Fab")
        (effects (font (size 0.7 0.7) (thickness 0.15)) (justify left bottom))
    )
    (fp_text user "License: Apache-2.0" (at -2.625 6.501 90) (layer "F.Fab") hide
        (effects (font (size 0.7 0.7) (thickness 0.15)) (justify left bottom))
    )
    (fp_text user "Author: Antmicro" (at -2.625 5.301 90) (layer "F.Fab") hide
        (effects (font (size 0.7 0.7) (thickness 0.15)) (justify left bottom))
    )
    (fp_text user "${REFERENCE}" (at -2.625 4.101 90) (layer "F.Fab") hide
        (effects (font (size 0.7 0.7) (thickness 0.15)) (justify left bottom))
    )
    (fp_line (start 0.8 -0.899) (end -0.8 -0.899)
      (stroke (width 0.15) (type solid)) (layer "F.SilkS"))
    (fp_line (start 0.8 0.901) (end -0.8 0.901)
      (stroke (width 0.15) (type solid)) (layer "F.SilkS"))
    (fp_rect (start -2.325 -1.15) (end 2.325 1.15)
      (stroke (width 0.05) (type default)) (fill none) (layer "F.CrtYd"))
    (fp_rect (start -1.6 -0.799) (end 1.6 0.801)
      (stroke (width 0.15) (type solid)) (fill none) (layer "F.Fab"))
    (pad "1" smd roundrect (at -1.5 0.001 90) (size 1.15 1.8) (layers "F.Cu" "F.Paste" "F.Mask") (roundrect_rratio 0.25)
      (net 1 "GND") (pintype "passive"))
    (pad "2" smd roundrect (at 1.5 0.001 90) (size 1.15 1.8) (layers "F.Cu" "F.Paste" "F.Mask") (roundrect_rratio 0.25)
      (net 90 "Net-(U2-VIN)") (pintype "passive"))
  )

  (footprint "antmicro-footprints:Resonator_SMD_Abracon_ABM8G_3.2x2.5mm" (layer "F.Cu")
    (at 122.998 76.12 180)
    (property "Author" "Antmicro")
    (property "License" "Apache-2.0")
    (property "MPN" "ABM8G-25.000MHZ-18-D2Y-T3")
    (property "Manufacturer" "Abracon")
    (property "Sheetfile" "tb.kicad_sch")
    (property "Sheetname" "TB Controller")
    (property "Val" "25 MHz")
    (property "ki_description" "Crystal, 25 MHz, SMD, 3.2mm x 2.5mm, 30 ppm, 18 pF, 20 ppm, ABM8G")
    (property "ki_keywords" "SMT, CERAMIC, OSCILLATOR")
    (attr smd)
    (fp_text reference "Y1" (at 0.824 1.825) (layer "F.SilkS")
        (effects (font (size 0.7 0.7) (thickness 0.15)) (justify left bottom))
    )
    (fp_text value "Resonator_25MHz_ABM8G" (at -1.75 2.548 180) (layer "F.Fab")
        (effects (font (size 0.7 0.7) (thickness 0.15)) (justify left bottom))
    )
    (fp_text user "License: Apache-2.0" (at -1.75 6.5 180) (layer "F.Fab") hide
        (effects (font (size 0.7 0.7) (thickness 0.15)) (justify left bottom))
    )
    (fp_text user "${REFERENCE}" (at -1.75 3.75 180) (layer "F.Fab") hide
        (effects (font (size 0.7 0.7) (thickness 0.15)) (justify left bottom))
    )
    (fp_text user "Author: Antmicro" (at -1.75 5 180) (layer "F.Fab") hide
        (effects (font (size 0.7 0.7) (thickness 0.15)) (justify left bottom))
    )
    (fp_line (start -1.6 0.3) (end -1.6 -0.2)
      (stroke (width 0.15) (type solid)) (layer "F.SilkS"))
    (fp_line (start -0.35 -1.25) (end 0.45 -1.25)
      (stroke (width 0.15) (type solid)) (layer "F.SilkS"))
    (fp_line (start -0.35 1.25) (end 0.45 1.25)
      (stroke (width 0.15) (type solid)) (layer "F.SilkS"))
    (fp_line (start 1.6 0.3) (end 1.6 -0.2)
      (stroke (width 0.15) (type solid)) (layer "F.SilkS"))
    (fp_circle (center -1.75 1.5) (end -1.7 1.5)
      (stroke (width 0.15) (type solid)) (fill none) (layer "F.SilkS"))
    (fp_rect (start -1.907 -1.55) (end 2.006 1.649)
      (stroke (width 0.05) (type solid)) (fill none) (layer "F.CrtYd"))
    (pad "1" smd roundrect (at -1.101 0.949 180) (size 1.3 1.1) (layers "F.Cu" "F.Paste" "F.Mask") (roundrect_rratio 0)
      (chamfer_ratio 0.2) (chamfer bottom_left)
      (net 115 "Net-(U6-XOUT)") (pintype "passive"))
    (pad "2" smd rect (at 1.199 0.949 180) (size 1.3 1.1) (layers "F.Cu" "F.Paste" "F.Mask")
      (net 1 "GND") (pinfunction "SH") (pintype "passive"))
    (pad "3" smd rect (at 1.199 -0.85 180) (size 1.3 1.1) (layers "F.Cu" "F.Paste" "F.Mask")
      (net 116 "Net-(U6-XIN{slash}CLKIN)") (pintype "passive"))
    (pad "4" smd rect (at -1.101 -0.85 180) (size 1.3 1.1) (layers "F.Cu" "F.Paste" "F.Mask")
      (net 1 "GND") (pinfunction "SH") (pintype "passive"))
  )

  (footprint "antmicro-footprints:C_1206_3216Metric" (layer "F.Cu")
    (at 111.110001 64.255 90)
    (descr "Capacitor SMD 1206")
    (tags "capacitor SMD 1206")
    (property "Author" "Antmicro")
    (property "Dielectric" "")
    (property "License" "Apache-2.0")
    (property "MPN" "3216X5R1V226M160AC")
    (property "Manufacturer" "TDK")
    (property "Sheetfile" "power.kicad_sch")
    (property "Sheetname" "Power")
    (property "Val" "22u")
    (property "Voltage" "35V")
    (property "ki_description" "SMD Multilayer Ceramic Capacitors, 22µF, 35V, X5R, 1206 [2316 Metric], 20% ")
    (property "ki_keywords" "1206, SMT, CAPACITOR, PASSIVE, CERAMIC, MLCC")
    (attr smd)
    (fp_text reference "C15" (at -4.325 0.395999 90) (layer "F.SilkS")
        (effects (font (size 0.7 0.7) (thickness 0.15)) (justify left bottom))
    )
    (fp_text value "C_22u_1206_35V" (at 0 2.101 90) (layer "F.Fab")
        (effects (font (size 0.7 0.7) (thickness 0.15)) (justify left bottom))
    )
    (fp_text user "Author: Antmicro" (at -2.625 5.301 90) (layer "F.Fab") hide
        (effects (font (size 0.7 0.7) (thickness 0.15)) (justify left bottom))
    )
    (fp_text user "${REFERENCE}" (at -2.625 4.101 90) (layer "F.Fab") hide
        (effects (font (size 0.7 0.7) (thickness 0.15)) (justify left bottom))
    )
    (fp_text user "License: Apache-2.0" (at -2.625 6.501 90) (layer "F.Fab") hide
        (effects (font (size 0.7 0.7) (thickness 0.15)) (justify left bottom))
    )
    (fp_line (start 0.8 -0.899) (end -0.8 -0.899)
      (stroke (width 0.15) (type solid)) (layer "F.SilkS"))
    (fp_line (start 0.8 0.901) (end -0.8 0.901)
      (stroke (width 0.15) (type solid)) (layer "F.SilkS"))
    (fp_rect (start -2.325 -1.15) (end 2.325 1.15)
      (stroke (width 0.05) (type default)) (fill none) (layer "F.CrtYd"))
    (fp_rect (start -1.6 -0.799) (end 1.6 0.801)
      (stroke (width 0.15) (type solid)) (fill none) (layer "F.Fab"))
    (pad "1" smd roundrect (at -1.5 0.001 90) (size 1.15 1.8) (layers "F.Cu" "F.Paste" "F.Mask") (roundrect_rratio 0.25)
      (net 1 "GND") (pintype "passive"))
    (pad "2" smd roundrect (at 1.5 0.001 90) (size 1.15 1.8) (layers "F.Cu" "F.Paste" "F.Mask") (roundrect_rratio 0.25)
      (net 90 "Net-(U2-VIN)") (pintype "passive"))
  )

  (footprint "antmicro-footprints:C_0805_2012Metric" (layer "F.Cu")
    (at 114.35 93.95 180)
    (descr "Capacitor SMD 0805")
    (tags "capacitor SMD 0805")
    (property "Author" "Antmicro")
    (property "Dielectric" "")
    (property "License" "Apache-2.0")
    (property "MPN" "GRM21BR6YA106KE43L")
    (property "Manufacturer" "Murata")
    (property "Sheetfile" "connectors.kicad_sch")
    (property "Sheetname" "Connectors")
    (property "Val" "10u")
    (property "Voltage" "35V")
    (property "ki_description" "SMD Multilayer Ceramic Capacitor, 10 µF, 35 V, 0805 [2012 Metric], ± 10%, X5R, GRM Series")
    (property "ki_keywords" "0805, SMT, CAPACITOR, PASSIVE")
    (attr smd)
    (fp_text reference "C1" (at -1.982 -0.538 180) (layer "F.SilkS")
        (effects (font (size 0.7 0.7) (thickness 0.15)) (justify left bottom))
    )
    (fp_text value "C_10u_0805_35V" (at -2.055717 1.963152 180) (layer "F.Fab")
        (effects (font (size 0.7 0.7) (thickness 0.15)) (justify left bottom))
    )
    (fp_text user "${REFERENCE}" (at -1.9 3.947 180) (layer "F.Fab") hide
        (effects (font (size 0.7 0.7) (thickness 0.15)) (justify left bottom))
    )
    (fp_text user "Author: Antmicro" (at -1.9 5.947 180) (layer "F.Fab") hide
        (effects (font (size 0.7 0.7) (thickness 0.15)) (justify left bottom))
    )
    (fp_text user "License: Apache-2.0" (at -1.9 4.947 180) (layer "F.Fab") hide
        (effects (font (size 0.7 0.7) (thickness 0.15)) (justify left bottom))
    )
    (fp_line (start -0.3 -0.7) (end 0.3 -0.7)
      (stroke (width 0.15) (type solid)) (layer "F.SilkS"))
    (fp_line (start -0.3 0.7) (end 0.3 0.7)
      (stroke (width 0.15) (type solid)) (layer "F.SilkS"))
    (fp_rect (start 1.95 -0.9) (end -1.95 0.9)
      (stroke (width 0.05) (type default)) (fill none) (layer "F.CrtYd"))
    (fp_rect (start -0.95 -0.675) (end 0.95 0.675)
      (stroke (width 0.15) (type solid)) (fill none) (layer "F.Fab"))
    (pad "1" smd roundrect (at -1.1 0 180) (size 1.2 1.3) (layers "F.Cu" "F.Paste" "F.Mask") (roundrect_rratio 0.25)
      (net 1 "GND") (pintype "passive"))
    (pad "2" smd roundrect (at 1.1 0 180) (size 1.2 1.3) (layers "F.Cu" "F.Paste" "F.Mask") (roundrect_rratio 0.25)
      (net 8 "12V0_PCIE") (pintype "passive"))
  )

  (footprint "antmicro-footprints:SOIC-8_3.9x4.9x1.75mm_P1.27mm" (layer "F.Cu")
    (at 137.147856 62.3)
    (property "Author" "Antmicro")
    (property "License" "Apache-2.0")
    (property "MPN" "MX25L8006EM1I-12G")
    (property "Manufacturer" "Macronix")
    (property "Sheetfile" "tb.kicad_sch")
    (property "Sheetname" "TB Controller")
    (property "ki_description" "FLASH - NOR Memory IC 8Mbit SPI 86 MHz 8-SOP")
    (property "ki_keywords" "SMT, MEMORY, IC, FLASH")
    (attr smd)
    (fp_text reference "U5" (at -1.892856 -3.245) (layer "F.SilkS")
        (effects (font (size 0.7 0.7) (thickness 0.15)) (justify left bottom))
    )
    (fp_text value "MX25L8006EM1I-12G" (at 0 3.65) (layer "F.Fab")
        (effects (font (size 0.7 0.7) (thickness 0.15)) (justify left bottom))
    )
    (fp_text user "${REFERENCE}" (at -3.476 7.099) (layer "F.Fab") hide
        (effects (font (size 0.7 0.7) (thickness 0.15)) (justify left bottom))
    )
    (fp_text user "Author: Antmicro" (at -3.476 6.099) (layer "F.Fab") hide
        (effects (font (size 0.7 0.7) (thickness 0.15)) (justify left bottom))
    )
    (fp_text user "License: Apache-2.0" (at -3.476 5.099) (layer "F.Fab") hide
        (effects (font (size 0.7 0.7) (thickness 0.15)) (justify left bottom))
    )
    (fp_line (start -1.95 -2.452) (end 1.95 -2.45)
      (stroke (width 0.15) (type solid)) (layer "F.SilkS"))
    (fp_line (start -1.95 2.45) (end 1.95 2.45)
      (stroke (width 0.15) (type solid)) (layer "F.SilkS"))
    (fp_circle (center -2.4 -2.45) (end -2.35 -2.4)
      (stroke (width 0.15) (type solid)) (fill solid) (layer "F.SilkS"))
    (fp_rect (start -3.625 -2.7) (end 3.625 2.7)
      (stroke (width 0.05) (type solid)) (fill none) (layer "F.CrtYd"))
    (fp_line (start -1.95 -1.18) (end -0.683 -2.452)
      (stroke (width 0.15) (type solid)) (layer "F.Fab"))
    (fp_line (start -1.95 2.45) (end -1.95 -1.18)
      (stroke (width 0.15) (type solid)) (layer "F.Fab"))
    (fp_line (start -0.683 -2.452) (end 1.949 -2.452)
      (stroke (width 0.15) (type solid)) (layer "F.Fab"))
    (fp_line (start 1.949 -2.452) (end 1.949 2.45)
      (stroke (width 0.15) (type solid)) (layer "F.Fab"))
    (fp_line (start 1.949 2.45) (end -1.95 2.45)
      (stroke (width 0.15) (type solid)) (layer "F.Fab"))
    (pad "1" smd roundrect (at -2.714 -1.905 90) (size 0.65 1.525) (layers "F.Cu" "F.Paste" "F.Mask") (roundrect_rratio 0.25)
      (net 65 "SPI_CS") (pinfunction "~{CS}") (pintype "input"))
    (pad "2" smd roundrect (at -2.714 -0.635 90) (size 0.65 1.525) (layers "F.Cu" "F.Paste" "F.Mask") (roundrect_rratio 0.25)
      (net 63 "SPI_MISO") (pinfunction "SO/IO1") (pintype "input"))
    (pad "3" smd roundrect (at -2.714 0.632 90) (size 0.65 1.525) (layers "F.Cu" "F.Paste" "F.Mask") (roundrect_rratio 0.25)
      (net 64 "/TB Controller/FLASH_WP") (pinfunction "~{WP}") (pintype "input"))
    (pad "4" smd roundrect (at -2.714 1.902 90) (size 0.65 1.525) (layers "F.Cu" "F.Paste" "F.Mask") (roundrect_rratio 0.25)
      (net 1 "GND") (pinfunction "GND") (pintype "power_in"))
    (pad "5" smd roundrect (at 2.712 1.902 90) (size 0.65 1.525) (layers "F.Cu" "F.Paste" "F.Mask") (roundrect_rratio 0.25)
      (net 69 "SPI_MOSI") (pinfunction "SI/IO0") (pintype "input"))
    (pad "6" smd roundrect (at 2.712 0.632 90) (size 0.65 1.525) (layers "F.Cu" "F.Paste" "F.Mask") (roundrect_rratio 0.25)
      (net 68 "SPI_SCLK") (pinfunction "SCLK") (pintype "input"))
    (pad "7" smd roundrect (at 2.712 -0.635 90) (size 0.65 1.525) (layers "F.Cu" "F.Paste" "F.Mask") (roundrect_rratio 0.25)
      (net 89 "/TB Controller/FLASH_HOLD") (pinfunction "~{HOLD}") (pintype "input"))
    (pad "8" smd roundrect (at 2.712 -1.905 90) (size 0.65 1.525) (layers "F.Cu" "F.Paste" "F.Mask") (roundrect_rratio 0.25)
      (net 2 "3V3_SYS") (pinfunction "VCC") (pintype "power_in"))
  )

  (footprint "antmicro-footprints:IC_TPS65983BAZBHR" (layer "F.Cu")
    (at 156.89 62.85)
    (property "Author" "Antmicro")
    (property "License" "Apache-2.0")
    (property "MPN" "TPS65983BAZBHR")
    (property "Manufacturer" "Texas Instruments")
    (property "Sheetfile" "power.kicad_sch")
    (property "Sheetname" "Power")
    (property "ki_description" "USB Interface IC Universal USB Type-C and Power Delivery (PD) 3.0 controller 96-NFBGA -10°C to 85")
    (property "ki_keywords" "IC")
    (attr smd)
    (fp_text reference "U3" (at 0 -3.8 unlocked) (layer "F.SilkS")
        (effects (font (size 0.7 0.7) (thickness 0.15)))
    )
    (fp_text value "TPS65983BAZBHR" (at 0 4.1 unlocked) (layer "F.Fab")
        (effects (font (size 0.7 0.7) (thickness 0.15)))
    )
    (fp_text user "${REFERENCE}" (at 0 5.2 unlocked) (layer "F.Fab") hide
        (effects (font (size 0.7 0.7) (thickness 0.15)))
    )
    (fp_text user "License: Apache-2.0" (at 0 7.2) (layer "F.Fab") hide
        (effects (font (size 0.7 0.7) (thickness 0.15)))
    )
    (fp_text user "Author: Antmicro" (at 0 6.2) (layer "F.Fab") hide
        (effects (font (size 0.7 0.7) (thickness 0.15)))
    )
    (fp_poly
      (pts
        (xy -2.6 2.6)
        (xy -2.6 2.4)
        (xy -2.4 2.4)
        (xy -2.4 2.6)
      )

      (stroke (width 0.05) (type solid)) (fill solid) (layer "F.Paste"))
    (fp_poly
      (pts
        (xy -2.4 -2.4)
        (xy -2.6 -2.4)
        (xy -2.6 -2.6)
        (xy -2.4 -2.6)
      )

      (stroke (width 0.05) (type solid)) (fill solid) (layer "F.Paste"))
    (fp_poly
      (pts
        (xy -2.1 -1.9)
        (xy -2.1 -2.1)
        (xy -1.9 -2.1)
        (xy -1.9 -1.9)
      )

      (stroke (width 0.05) (type solid)) (fill solid) (layer "F.Paste"))
    (fp_poly
      (pts
        (xy -2.1 -1.4)
        (xy -2.1 -1.6)
        (xy -1.9 -1.6)
        (xy -1.9 -1.4)
      )

      (stroke (width 0.05) (type solid)) (fill solid) (layer "F.Paste"))
    (fp_poly
      (pts
        (xy -2.1 -0.9)
        (xy -2.1 -1.1)
        (xy -1.9 -1.1)
        (xy -1.9 -0.9)
      )

      (stroke (width 0.05) (type solid)) (fill solid) (layer "F.Paste"))
    (fp_poly
      (pts
        (xy -2.1 0.6)
        (xy -2.1 0.4)
        (xy -1.9 0.4)
        (xy -1.9 0.6)
      )

      (stroke (width 0.05) (type solid)) (fill solid) (layer "F.Paste"))
    (fp_poly
      (pts
        (xy -2.1 1.1)
        (xy -2.1 0.9)
        (xy -1.9 0.9)
        (xy -1.9 1.1)
      )

      (stroke (width 0.05) (type solid)) (fill solid) (layer "F.Paste"))
    (fp_poly
      (pts
        (xy -2.1 1.6)
        (xy -2.1 1.4)
        (xy -1.9 1.4)
        (xy -1.9 1.6)
      )

      (stroke (width 0.05) (type solid)) (fill solid) (layer "F.Paste"))
    (fp_poly
      (pts
        (xy -2.1 1.9)
        (xy -1.9 1.9)
        (xy -1.9 2.1)
        (xy -2.1 2.1)
      )

      (stroke (width 0.05) (type solid)) (fill solid) (layer "F.Paste"))
    (fp_poly
      (pts
        (xy -1.9 -0.4)
        (xy -2.1 -0.4)
        (xy -2.1 -0.6)
        (xy -1.9 -0.6)
      )

      (stroke (width 0.05) (type solid)) (fill solid) (layer "F.Paste"))
    (fp_poly
      (pts
        (xy -1.9 0.1)
        (xy -2.1 0.1)
        (xy -2.1 -0.1)
        (xy -1.9 -0.1)
      )

      (stroke (width 0.05) (type solid)) (fill solid) (layer "F.Paste"))
    (fp_poly
      (pts
        (xy -1.6 1.9)
        (xy -1.4 1.9)
        (xy -1.4 2.1)
        (xy -1.6 2.1)
      )

      (stroke (width 0.05) (type solid)) (fill solid) (layer "F.Paste"))
    (fp_poly
      (pts
        (xy -1.4 -1.9)
        (xy -1.6 -1.9)
        (xy -1.6 -2.1)
        (xy -1.4 -2.1)
      )

      (stroke (width 0.05) (type solid)) (fill solid) (layer "F.Paste"))
    (fp_poly
      (pts
        (xy -1.1 0.1)
        (xy -1.1 -0.1)
        (xy -0.9 -0.1)
        (xy -0.9 0.1)
      )

      (stroke (width 0.05) (type solid)) (fill solid) (layer "F.Paste"))
    (fp_poly
      (pts
        (xy -1.1 0.6)
        (xy -1.1 0.4)
        (xy -0.9 0.4)
        (xy -0.9 0.6)
      )

      (stroke (width 0.05) (type solid)) (fill solid) (layer "F.Paste"))
    (fp_poly
      (pts
        (xy -1.1 1.1)
        (xy -1.1 0.9)
        (xy -0.9 0.9)
        (xy -0.9 1.1)
      )

      (stroke (width 0.05) (type solid)) (fill solid) (layer "F.Paste"))
    (fp_poly
      (pts
        (xy -1.1 2.1)
        (xy -1.1 1.9)
        (xy -0.9 1.9)
        (xy -0.9 2.1)
      )

      (stroke (width 0.05) (type solid)) (fill solid) (layer "F.Paste"))
    (fp_poly
      (pts
        (xy -0.9 -1.9)
        (xy -1.1 -1.9)
        (xy -1.1 -2.1)
        (xy -0.9 -2.1)
      )

      (stroke (width 0.05) (type solid)) (fill solid) (layer "F.Paste"))
    (fp_poly
      (pts
        (xy -0.9 -0.4)
        (xy -1.1 -0.4)
        (xy -1.1 -0.6)
        (xy -0.9 -0.6)
      )

      (stroke (width 0.05) (type solid)) (fill solid) (layer "F.Paste"))
    (fp_poly
      (pts
        (xy -0.6 -1.1)
        (xy -0.4 -1.1)
        (xy -0.4 -0.9)
        (xy -0.6 -0.9)
      )

      (stroke (width 0.05) (type solid)) (fill solid) (layer "F.Paste"))
    (fp_poly
      (pts
        (xy -0.6 0.1)
        (xy -0.6 -0.1)
        (xy -0.4 -0.1)
        (xy -0.4 0.1)
      )

      (stroke (width 0.05) (type solid)) (fill solid) (layer "F.Paste"))
    (fp_poly
      (pts
        (xy -0.6 0.6)
        (xy -0.6 0.4)
        (xy -0.4 0.4)
        (xy -0.4 0.6)
      )

      (stroke (width 0.05) (type solid)) (fill solid) (layer "F.Paste"))
    (fp_poly
      (pts
        (xy -0.6 1.1)
        (xy -0.6 0.9)
        (xy -0.4 0.9)
        (xy -0.4 1.1)
      )

      (stroke (width 0.05) (type solid)) (fill solid) (layer "F.Paste"))
    (fp_poly
      (pts
        (xy -0.6 2.1)
        (xy -0.6 1.9)
        (xy -0.4 1.9)
        (xy -0.4 2.1)
      )

      (stroke (width 0.05) (type solid)) (fill solid) (layer "F.Paste"))
    (fp_poly
      (pts
        (xy -0.4 -2.1)
        (xy -0.4 -1.9)
        (xy -0.6 -1.9)
        (xy -0.6 -2.1)
      )

      (stroke (width 0.05) (type solid)) (fill solid) (layer "F.Paste"))
    (fp_poly
      (pts
        (xy -0.4 -0.4)
        (xy -0.6 -0.4)
        (xy -0.6 -0.6)
        (xy -0.4 -0.6)
      )

      (stroke (width 0.05) (type solid)) (fill solid) (layer "F.Paste"))
    (fp_poly
      (pts
        (xy -0.1 -1.1)
        (xy 0.1 -1.1)
        (xy 0.1 -0.9)
        (xy -0.1 -0.9)
      )

      (stroke (width 0.05) (type solid)) (fill solid) (layer "F.Paste"))
    (fp_poly
      (pts
        (xy -0.1 -0.6)
        (xy 0.1 -0.6)
        (xy 0.1 -0.4)
        (xy -0.1 -0.4)
      )

      (stroke (width 0.05) (type solid)) (fill solid) (layer "F.Paste"))
    (fp_poly
      (pts
        (xy -0.1 -0.1)
        (xy 0.1 -0.1)
        (xy 0.1 0.1)
        (xy -0.1 0.1)
      )

      (stroke (width 0.05) (type solid)) (fill solid) (layer "F.Paste"))
    (fp_poly
      (pts
        (xy -0.1 0.4)
        (xy 0.1 0.4)
        (xy 0.1 0.6)
        (xy -0.1 0.6)
      )

      (stroke (width 0.05) (type solid)) (fill solid) (layer "F.Paste"))
    (fp_poly
      (pts
        (xy -0.1 0.9)
        (xy 0.1 0.9)
        (xy 0.1 1.1)
        (xy -0.1 1.1)
      )

      (stroke (width 0.05) (type solid)) (fill solid) (layer "F.Paste"))
    (fp_poly
      (pts
        (xy -0.1 1.9)
        (xy 0.1 1.9)
        (xy 0.1 2.1)
        (xy -0.1 2.1)
      )

      (stroke (width 0.05) (type solid)) (fill solid) (layer "F.Paste"))
    (fp_poly
      (pts
        (xy 0.1 -2.1)
        (xy 0.1 -1.9)
        (xy -0.1 -1.9)
        (xy -0.1 -2.1)
      )

      (stroke (width 0.05) (type solid)) (fill solid) (layer "F.Paste"))
    (fp_poly
      (pts
        (xy 0.4 -1.1)
        (xy 0.6 -1.1)
        (xy 0.6 -0.9)
        (xy 0.4 -0.9)
      )

      (stroke (width 0.05) (type solid)) (fill solid) (layer "F.Paste"))
    (fp_poly
      (pts
        (xy 0.4 -0.6)
        (xy 0.6 -0.6)
        (xy 0.6 -0.4)
        (xy 0.4 -0.4)
      )

      (stroke (width 0.05) (type solid)) (fill solid) (layer "F.Paste"))
    (fp_poly
      (pts
        (xy 0.4 0.6)
        (xy 0.4 0.4)
        (xy 0.6 0.4)
        (xy 0.6 0.6)
      )

      (stroke (width 0.05) (type solid)) (fill solid) (layer "F.Paste"))
    (fp_poly
      (pts
        (xy 0.4 0.9)
        (xy 0.6 0.9)
        (xy 0.6 1.1)
        (xy 0.4 1.1)
      )

      (stroke (width 0.05) (type solid)) (fill solid) (layer "F.Paste"))
    (fp_poly
      (pts
        (xy 0.4 1.9)
        (xy 0.6 1.9)
        (xy 0.6 2.1)
        (xy 0.4 2.1)
      )

      (stroke (width 0.05) (type solid)) (fill solid) (layer "F.Paste"))
    (fp_poly
      (pts
        (xy 0.6 -1.9)
        (xy 0.4 -1.9)
        (xy 0.4 -2.1)
        (xy 0.6 -2.1)
      )

      (stroke (width 0.05) (type solid)) (fill solid) (layer "F.Paste"))
    (fp_poly
      (pts
        (xy 0.6 0.1)
        (xy 0.4 0.1)
        (xy 0.4 -0.1)
        (xy 0.6 -0.1)
      )

      (stroke (width 0.05) (type solid)) (fill solid) (layer "F.Paste"))
    (fp_poly
      (pts
        (xy 0.9 -1.1)
        (xy 1.1 -1.1)
        (xy 1.1 -0.9)
        (xy 0.9 -0.9)
      )

      (stroke (width 0.05) (type solid)) (fill solid) (layer "F.Paste"))
    (fp_poly
      (pts
        (xy 0.9 -0.6)
        (xy 1.1 -0.6)
        (xy 1.1 -0.4)
        (xy 0.9 -0.4)
      )

      (stroke (width 0.05) (type solid)) (fill solid) (layer "F.Paste"))
    (fp_poly
      (pts
        (xy 0.9 1.1)
        (xy 0.9 0.9)
        (xy 1.1 0.9)
        (xy 1.1 1.1)
      )

      (stroke (width 0.05) (type solid)) (fill solid) (layer "F.Paste"))
    (fp_poly
      (pts
        (xy 0.9 1.9)
        (xy 1.1 1.9)
        (xy 1.1 2.1)
        (xy 0.9 2.1)
      )

      (stroke (width 0.05) (type solid)) (fill solid) (layer "F.Paste"))
    (fp_poly
      (pts
        (xy 1.1 -1.9)
        (xy 0.9 -1.9)
        (xy 0.9 -2.1)
        (xy 1.1 -2.1)
      )

      (stroke (width 0.05) (type solid)) (fill solid) (layer "F.Paste"))
    (fp_poly
      (pts
        (xy 1.1 0.1)
        (xy 0.9 0.1)
        (xy 0.9 -0.1)
        (xy 1.1 -0.1)
      )

      (stroke (width 0.05) (type solid)) (fill solid) (layer "F.Paste"))
    (fp_poly
      (pts
        (xy 1.1 0.6)
        (xy 0.9 0.6)
        (xy 0.9 0.4)
        (xy 1.1 0.4)
      )

      (stroke (width 0.05) (type solid)) (fill solid) (layer "F.Paste"))
    (fp_poly
      (pts
        (xy 1.4 1.9)
        (xy 1.6 1.9)
        (xy 1.6 2.1)
        (xy 1.4 2.1)
      )

      (stroke (width 0.05) (type solid)) (fill solid) (layer "F.Paste"))
    (fp_poly
      (pts
        (xy 1.6 -1.9)
        (xy 1.4 -1.9)
        (xy 1.4 -2.1)
        (xy 1.6 -2.1)
      )

      (stroke (width 0.05) (type solid)) (fill solid) (layer "F.Paste"))
    (fp_poly
      (pts
        (xy 1.9 -0.1)
        (xy 2.1 -0.1)
        (xy 2.1 0.1)
        (xy 1.9 0.1)
      )

      (stroke (width 0.05) (type solid)) (fill solid) (layer "F.Paste"))
    (fp_poly
      (pts
        (xy 1.9 2.1)
        (xy 1.9 1.9)
        (xy 2.1 1.9)
        (xy 2.1 2.1)
      )

      (stroke (width 0.05) (type solid)) (fill solid) (layer "F.Paste"))
    (fp_poly
      (pts
        (xy 2.1 -1.9)
        (xy 1.9 -1.9)
        (xy 1.9 -2.1)
        (xy 2.1 -2.1)
      )

      (stroke (width 0.05) (type solid)) (fill solid) (layer "F.Paste"))
    (fp_poly
      (pts
        (xy 2.1 -1.6)
        (xy 2.1 -1.4)
        (xy 1.9 -1.4)
        (xy 1.9 -1.6)
      )

      (stroke (width 0.05) (type solid)) (fill solid) (layer "F.Paste"))
    (fp_poly
      (pts
        (xy 2.1 -1.1)
        (xy 2.1 -0.9)
        (xy 1.9 -0.9)
        (xy 1.9 -1.1)
      )

      (stroke (width 0.05) (type solid)) (fill solid) (layer "F.Paste"))
    (fp_poly
      (pts
        (xy 2.1 -0.6)
        (xy 2.1 -0.4)
        (xy 1.9 -0.4)
        (xy 1.9 -0.6)
      )

      (stroke (width 0.05) (type solid)) (fill solid) (layer "F.Paste"))
    (fp_poly
      (pts
        (xy 2.1 0.4)
        (xy 2.1 0.6)
        (xy 1.9 0.6)
        (xy 1.9 0.4)
      )

      (stroke (width 0.05) (type solid)) (fill solid) (layer "F.Paste"))
    (fp_poly
      (pts
        (xy 2.1 0.9)
        (xy 2.1 1.1)
        (xy 1.9 1.1)
        (xy 1.9 0.9)
      )

      (stroke (width 0.05) (type solid)) (fill solid) (layer "F.Paste"))
    (fp_poly
      (pts
        (xy 2.1 1.4)
        (xy 2.1 1.6)
        (xy 1.9 1.6)
        (xy 1.9 1.4)
      )

      (stroke (width 0.05) (type solid)) (fill solid) (layer "F.Paste"))
    (fp_poly
      (pts
        (xy 2.6 -2.4)
        (xy 2.4 -2.4)
        (xy 2.4 -2.6)
        (xy 2.6 -2.6)
      )

      (stroke (width 0.05) (type solid)) (fill solid) (layer "F.Paste"))
    (fp_poly
      (pts
        (xy 2.6 2.6)
        (xy 2.4 2.6)
        (xy 2.4 2.4)
        (xy 2.6 2.4)
      )

      (stroke (width 0.05) (type solid)) (fill solid) (layer "F.Paste"))
    (fp_line (start -3 -3) (end 3 -3)
      (stroke (width 0.1) (type solid)) (layer "F.SilkS"))
    (fp_line (start -3 -2.9) (end -2.9 -3)
      (stroke (width 0.1) (type solid)) (layer "F.SilkS"))
    (fp_line (start -3 -2.8) (end -2.8 -3)
      (stroke (width 0.1) (type solid)) (layer "F.SilkS"))
    (fp_line (start -3 -2.7) (end -2.7 -3)
      (stroke (width 0.1) (type solid)) (layer "F.SilkS"))
    (fp_line (start -3 3) (end -3 -3)
      (stroke (width 0.1) (type solid)) (layer "F.SilkS"))
    (fp_line (start 3 -3) (end 3 3)
      (stroke (width 0.1) (type solid)) (layer "F.SilkS"))
    (fp_line (start 3 3) (end -3 3)
      (stroke (width 0.1) (type solid)) (layer "F.SilkS"))
    (fp_circle (center -3.4 -2.9) (end -3.35 -2.9)
      (stroke (width 0.15) (type solid)) (fill none) (layer "F.SilkS"))
    (fp_line (start -3.25 -3.25) (end -3.25 3.25)
      (stroke (width 0.05) (type solid)) (layer "F.CrtYd"))
    (fp_line (start -3.25 3.25) (end 3.25 3.25)
      (stroke (width 0.05) (type solid)) (layer "F.CrtYd"))
    (fp_line (start 3.25 -3.25) (end -3.25 -3.25)
      (stroke (width 0.05) (type solid)) (layer "F.CrtYd"))
    (fp_line (start 3.25 -3.25) (end 3.25 3.25)
      (stroke (width 0.05) (type solid)) (layer "F.CrtYd"))
    (fp_line (start -3 -2) (end -2 -3)
      (stroke (width 0.15) (type solid)) (layer "F.Fab"))
    (fp_line (start -3 3) (end -3 -2)
      (stroke (width 0.15) (type solid)) (layer "F.Fab"))
    (fp_line (start -2 -3) (end 3 -3)
      (stroke (width 0.15) (type solid)) (layer "F.Fab"))
    (fp_line (start 3 -3) (end 3 3)
      (stroke (width 0.15) (type solid)) (layer "F.Fab"))
    (fp_line (start 3 3) (end -3 3)
      (stroke (width 0.15) (type solid)) (layer "F.Fab"))
    (pad "A1" smd circle (at -2.5 -2.5) (size 0.25 0.25) (layers "F.Cu" "F.Paste" "F.Mask")
      (net 1 "GND") (pinfunction "GND") (pintype "power_in") (solder_paste_margin_ratio -1))
    (pad "A2" smd oval (at -2 -2.5) (size 0.17 0.25) (layers "F.Cu" "F.Paste" "F.Mask")
      (net 103 "Net-(U3-LDO_1V8D)") (pinfunction "LDO_1V8D") (pintype "power_out"))
    (pad "A3" smd oval (at -1.5 -2.5) (size 0.17 0.25) (layers "F.Cu" "F.Paste" "F.Mask")
      (net 68 "SPI_SCLK") (pinfunction "SPI_CLK") (pintype "output"))
    (pad "A4" smd oval (at -1 -2.5) (size 0.17 0.25) (layers "F.Cu" "F.Paste" "F.Mask")
      (net 63 "SPI_MISO") (pinfunction "SPI_POCI") (pintype "input"))
    (pad "A5" smd oval (at -0.5 -2.5) (size 0.17 0.25) (layers "F.Cu" "F.Paste" "F.Mask")
      (net 149 "Net-(U3-I2C_SDA2)") (pinfunction "I2C_SDA2") (pintype "bidirectional"))
    (pad "A6" smd oval (at 0 -2.5) (size 0.17 0.25) (layers "F.Cu" "F.Paste" "F.Mask")
      (net 19 "PP_HV") (pinfunction "PP_HV") (pintype "power_in"))
    (pad "A7" smd oval (at 0.5 -2.5) (size 0.17 0.25) (layers "F.Cu" "F.Paste" "F.Mask")
      (net 19 "PP_HV") (pinfunction "PP_HV") (pintype "power_in"))
    (pad "A8" smd oval (at 1 -2.5) (size 0.17 0.25) (layers "F.Cu" "F.Paste" "F.Mask")
      (net 19 "PP_HV") (pinfunction "PP_HV") (pintype "power_in"))
    (pad "A9" smd oval (at 1.5 -2.5) (size 0.17 0.25) (layers "F.Cu" "F.Paste" "F.Mask")
      (net 208 "unconnected-(U3-HV_GATE2-PadA9)") (pinfunction "HV_GATE2") (pintype "output+no_connect"))
    (pad "A10" smd oval (at 2 -2.5) (size 0.17 0.25) (layers "F.Cu" "F.Paste" "F.Mask")
      (net 209 "unconnected-(U3-SENSEN-PadA10)") (pinfunction "SENSEN") (pintype "input+no_connect"))
    (pad "A11" smd circle (at 2.5 -2.5) (size 0.25 0.25) (layers "F.Cu" "F.Paste" "F.Mask")
      (net 20 "PP_5V0") (pinfunction "PP_5V0") (pintype "power_in") (solder_paste_margin_ratio -1))
    (pad "B1" smd oval (at -2.5 -2) (size 0.25 0.17) (layers "F.Cu" "F.Paste" "F.Mask")
      (net 2 "3V3_SYS") (pinfunction "VDDIO") (pintype "power_in"))
    (pad "B2" smd circle (at -2 -2 270) (size 0.25 0.25) (layers "F.Cu" "F.Paste" "F.Mask")
      (net 152 "Net-(U3-GPIO0(HD3_AMSEL))") (pinfunction "GPIO0(HD3_AMSEL)") (pintype "bidirectional") (solder_paste_margin_ratio -1))
    (pad "B3" smd circle (at -1.5 -2) (size 0.25 0.25) (layers "F.Cu" "F.Paste" "F.Mask")
      (net 65 "SPI_CS") (pinfunction "SPI_CSZ") (pintype "output") (solder_paste_margin_ratio -1))
    (pad "B4" smd circle (at -1 -2) (size 0.25 0.25) (layers "F.Cu" "F.Paste" "F.Mask")
      (net 69 "SPI_MOSI") (pinfunction "SPI_PICO") (pintype "output") (solder_paste_margin_ratio -1))
    (pad "B5" smd circle (at -0.5 -2 90) (size 0.25 0.25) (layers "F.Cu" "F.Paste" "F.Mask")
      (net 150 "Net-(U3-I2C_SCL2)") (pinfunction "I2C_SCL2") (pintype "bidirectional") (solder_paste_margin_ratio -1))
    (pad "B6" smd circle (at 0 -2 90) (size 0.25 0.25) (layers "F.Cu" "F.Paste" "F.Mask")
      (net 151 "Net-(U3-I2C_IRQ2Z)") (pinfunction "I2C_IRQ2Z") (pintype "output") (solder_paste_margin_ratio -1))
    (pad "B7" smd circle (at 0.5 -2) (size 0.25 0.25) (layers "F.Cu" "F.Paste" "F.Mask")
      (net 19 "PP_HV") (pinfunction "PP_HV") (pintype "power_in") (solder_paste_margin_ratio -1))
    (pad "B8" smd circle (at 1 -2) (size 0.25 0.25) (layers "F.Cu" "F.Paste" "F.Mask")
      (net 1 "GND") (pinfunction "GND") (pintype "power_in") (solder_paste_margin_ratio -1))
    (pad "B9" smd circle (at 1.5 -2) (size 0.25 0.25) (layers "F.Cu" "F.Paste" "F.Mask")
      (net 210 "unconnected-(U3-HV_GATE1-PadB9)") (pinfunction "HV_GATE1") (pintype "output+no_connect") (solder_paste_margin_ratio -1))
    (pad "B10" smd circle (at 2 -2) (size 0.25 0.25) (layers "F.Cu" "F.Paste" "F.Mask")
      (net 211 "unconnected-(U3-SENSEP-PadB10)") (pinfunction "SENSEP") (pintype "input+no_connect") (solder_paste_margin_ratio -1))
    (pad "B11" smd oval (at 2.5 -2) (size 0.25 0.17) (layers "F.Cu" "F.Paste" "F.Mask")
      (net 20 "PP_5V0") (pinfunction "PP_5V0") (pintype "power_in"))
    (pad "C1" smd oval (at -2.5 -1.5) (size 0.25 0.17) (layers "F.Cu" "F.Paste" "F.Mask")
      (net 56 "I2C1_IRQ") (pinfunction "I2C_IRQ1Z") (pintype "output"))
    (pad "C2" smd circle (at -2 -1.5 270) (size 0.25 0.25) (layers "F.Cu" "F.Paste" "F.Mask")
      (net 212 "unconnected-(U3-GPIO1(CONFIG0)-PadC2)") (pinfunction "GPIO1(CONFIG0)") (pintype "bidirectional+no_connect") (solder_paste_margin_ratio -1))
    (pad "C10" smd circle (at 2 -1.5 90) (size 0.25 0.25) (layers "F.Cu" "F.Paste" "F.Mask")
      (net 153 "Net-(U3-GPIO4(HPD_TXRX))") (pinfunction "GPIO4(HPD_TXRX)") (pintype "bidirectional") (solder_paste_margin_ratio -1))
    (pad "C11" smd oval (at 2.5 -1.5) (size 0.25 0.17) (layers "F.Cu" "F.Paste" "F.Mask")
      (net 20 "PP_5V0") (pinfunction "PP_5V0") (pintype "power_in"))
    (pad "D1" smd oval (at -2.5 -1) (size 0.25 0.17) (layers "F.Cu" "F.Paste" "F.Mask")
      (net 59 "I2C1_SDA") (pinfunction "I2C_SDA1") (pintype "bidirectional"))
    (pad "D2" smd circle (at -2 -1 270) (size 0.25 0.25) (layers "F.Cu" "F.Paste" "F.Mask")
      (net 57 "I2C1_SCL") (pinfunction "I2C_SCL1") (pintype "bidirectional") (solder_paste_margin_ratio -1))
    (pad "D5" smd circle (at -0.5 -1 180) (size 0.25 0.25) (layers "F.Cu" "F.Paste" "F.Mask")
      (net 162 "Net-(U3-DEBUG_CTL2(GPIO17,_I2CADDR_B5))") (pinfunction "DEBUG_CTL2(GPIO17,_I2CADDR_B5)") (pintype "bidirectional") (solder_paste_margin_ratio -1))
    (pad "D6" smd circle (at 0 -1 180) (size 0.25 0.25) (layers "F.Cu" "F.Paste" "F.Mask")
      (net 166 "Net-(U3-HRESET)") (pinfunction "HRESET") (pintype "input") (solder_paste_margin_ratio -1))
    (pad "D7" smd circle (at 0.5 -1 180) (size 0.25 0.25) (layers "F.Cu" "F.Paste" "F.Mask")
      (net 155 "Net-(U3-GPIO7)") (pinfunction "GPIO7") (pintype "bidirectional") (solder_paste_margin_ratio -1))
    (pad "D8" smd circle (at 1 -1 180) (size 0.25 0.25) (layers "F.Cu" "F.Paste" "F.Mask")
      (net 1 "GND") (pinfunction "GND") (pintype "power_in") (solder_paste_margin_ratio -1))
    (pad "D10" smd circle (at 2 -1 90) (size 0.25 0.25) (layers "F.Cu" "F.Paste" "F.Mask")
      (net 213 "unconnected-(U3-GPIO2-PadD10)") (pinfunction "GPIO2") (pintype "bidirectional+no_connect") (solder_paste_margin_ratio -1))
    (pad "D11" smd oval (at 2.5 -1) (size 0.25 0.17) (layers "F.Cu" "F.Paste" "F.Mask")
      (net 20 "PP_5V0") (pinfunction "PP_5V0") (pintype "power_in"))
    (pad "E1" smd oval (at -2.5 -0.5) (size 0.25 0.17) (layers "F.Cu" "F.Paste" "F.Mask")
      (net 104 "Net-(U3-LDO_BMC)") (pinfunction "LDO_BMC") (pintype "power_out"))
    (pad "E2" smd circle (at -2 -0.5) (size 0.25 0.25) (layers "F.Cu" "F.Paste" "F.Mask")
      (net 156 "Net-(U3-UART_RX)") (pinfunction "UART_TX") (pintype "output") (solder_paste_margin_ratio -1))
    (pad "E4" smd circle (at -1 -0.5) (size 0.25 0.25) (layers "F.Cu" "F.Paste" "F.Mask")
      (net 163 "Net-(U3-DEBUG_CTL1(GPIO16,_I2CADDR_B4))") (pinfunction "DEBUG_CTL1(GPIO16,_I2CADDR_B4)") (pintype "bidirectional") (solder_paste_margin_ratio -1))
    (pad "E5" smd circle (at -0.5 -0.5) (size 0.25 0.25) (layers "F.Cu" "F.Paste" "F.Mask")
      (net 1 "GND") (pinfunction "GND") (pintype "power_in") (solder_paste_margin_ratio -1))
    (pad "E6" smd circle (at 0 -0.5 180) (size 0.25 0.25) (layers "F.Cu" "F.Paste" "F.Mask")
      (net 1 "GND") (pinfunction "GND") (pintype "power_in") (solder_paste_margin_ratio -1))
    (pad "E7" smd circle (at 0.5 -0.5 180) (size 0.25 0.25) (layers "F.Cu" "F.Paste" "F.Mask")
      (net 1 "GND") (pinfunction "GND") (pintype "power_in") (solder_paste_margin_ratio -1))
    (pad "E8" smd circle (at 1 -0.5 180) (size 0.25 0.25) (layers "F.Cu" "F.Paste" "F.Mask")
      (net 1 "GND") (pinfunction "GND") (pintype "power_in") (solder_paste_margin_ratio -1))
    (pad "E10" smd circle (at 2 -0.5 90) (size 0.25 0.25) (layers "F.Cu" "F.Paste" "F.Mask")
      (net 214 "unconnected-(U3-GPIO5(HPD_RX)-PadE10)") (pinfunction "GPIO5(HPD_RX)") (pintype "bidirectional+no_connect") (solder_paste_margin_ratio -1))
    (pad "E11" smd oval (at 2.5 -0.5) (size 0.25 0.17) (layers "F.Cu" "F.Paste" "F.Mask")
      (net 165 "Net-(U3-MRESET(GPIO11))") (pinfunction "MRESET(GPIO11)") (pintype "bidirectional"))
    (pad "F1" smd oval (at -2.5 0) (size 0.25 0.17) (layers "F.Cu" "F.Paste" "F.Mask")
      (net 164 "Net-(U3-I2C_ADDR)") (pinfunction "I2C_ADDR") (pintype "bidirectional"))
    (pad "F2" smd circle (at -2 0) (size 0.25 0.25) (layers "F.Cu" "F.Paste" "F.Mask")
      (net 156 "Net-(U3-UART_RX)") (pinfunction "UART_RX") (pintype "input") (solder_paste_margin_ratio -1))
    (pad "F4" smd circle (at -1 0 270) (size 0.25 0.25) (layers "F.Cu" "F.Paste" "F.Mask")
      (net 215 "unconnected-(U3-SWD_DATA-PadF4)") (pinfunction "SWD_DATA") (pintype "bidirectional+no_connect") (solder_paste_margin_ratio -1))
    (pad "F5" smd circle (at -0.5 0 270) (size 0.25 0.25) (layers "F.Cu" "F.Paste" "F.Mask")
      (net 1 "GND") (pinfunction "GND") (pintype "power_in") (solder_paste_margin_ratio -1))
    (pad "F6" smd circle (at 0 0 180) (size 0.25 0.25) (layers "F.Cu" "F.Paste" "F.Mask")
      (net 1 "GND") (pinfunction "GND") (pintype "power_in") (solder_paste_margin_ratio -1))
    (pad "F7" smd circle (at 0.5 0) (size 0.25 0.25) (layers "F.Cu" "F.Paste" "F.Mask")
      (net 1 "GND") (pinfunction "GND") (pintype "power_in") (solder_paste_margin_ratio -1))
    (pad "F8" smd circle (at 1 0) (size 0.25 0.25) (layers "F.Cu" "F.Paste" "F.Mask")
      (net 1 "GND") (pinfunction "GND") (pintype "power_in") (solder_paste_margin_ratio -1))
    (pad "F10" smd circle (at 2 0 180) (size 0.25 0.25) (layers "F.Cu" "F.Paste" "F.Mask")
      (net 167 "Net-(U3-BUSPOWERZ(GPIO10))") (pinfunction "BUSPOWERZ(GPIO10)") (pintype "bidirectional") (solder_paste_margin_ratio -1))
    (pad "F11" smd oval (at 2.5 0) (size 0.25 0.17) (layers "F.Cu" "F.Paste" "F.Mask")
      (net 62 "RESET_N") (pinfunction "RESETZ(GPIO9)") (pintype "bidirectional"))
    (pad "G1" smd oval (at -2.5 0.5) (size 0.25 0.17) (layers "F.Cu" "F.Paste" "F.Mask")
      (net 9 "/Power/TPS_3V3") (pinfunction "LDO_3V3") (pintype "power_out"))
    (pad "G2" smd circle (at -2 0.5 270) (size 0.25 0.25) (layers "F.Cu" "F.Paste" "F.Mask")
      (net 168 "Net-(U3-R_OSC)") (pinfunction "R_OSC") (pintype "bidirectional") (solder_paste_margin_ratio -1))
    (pad "G4" smd circle (at -1 0.5 270) (size 0.25 0.25) (layers "F.Cu" "F.Paste" "F.Mask")
      (net 216 "unconnected-(U3-SWD_CLK-PadG4)") (pinfunction "SWD_CLK") (pintype "input+no_connect") (solder_paste_margin_ratio -1))
    (pad "G5" smd circle (at -0.5 0.5 270) (size 0.25 0.25) (layers "F.Cu" "F.Paste" "F.Mask")
      (net 1 "GND") (pinfunction "GND") (pintype "power_in") (solder_paste_margin_ratio -1))
    (pad "G6" smd circle (at 0 0.5 180) (size 0.25 0.25) (layers "F.Cu" "F.Paste" "F.Mask")
      (net 1 "GND") (pinfunction "GND") (pintype "power_in") (solder_paste_margin_ratio -1))
    (pad "G7" smd circle (at 0.5 0.5 270) (size 0.25 0.25) (layers "F.Cu" "F.Paste" "F.Mask")
      (net 1 "GND") (pinfunction "GND") (pintype "power_in") (solder_paste_margin_ratio -1))
    (pad "G8" smd circle (at 1 0.5) (size 0.25 0.25) (layers "F.Cu" "F.Paste" "F.Mask")
      (net 1 "GND") (pinfunction "GND") (pintype "power_in") (solder_paste_margin_ratio -1))
    (pad "G10" smd circle (at 2 0.5 90) (size 0.25 0.25) (layers "F.Cu" "F.Paste" "F.Mask")
      (net 154 "Net-(U3-GPIO6)") (pinfunction "GPIO6") (pintype "bidirectional") (solder_paste_margin_ratio -1))
    (pad "G11" smd oval (at 2.5 0.5) (size 0.25 0.17) (layers "F.Cu" "F.Paste" "F.Mask")
      (net 217 "unconnected-(U3-GPIO3(HD3_EN)-PadG11)") (pinfunction "GPIO3(HD3_EN)") (pintype "bidirectional+no_connect"))
    (pad "H1" smd oval (at -2.5 1) (size 0.25 0.17) (layers "F.Cu" "F.Paste" "F.Mask")
      (net 2 "3V3_SYS") (pinfunction "VIN_3V3") (pintype "power_in"))
    (pad "H2" smd circle (at -2 1 270) (size 0.25 0.25) (layers "F.Cu" "F.Paste" "F.Mask")
      (net 101 "Net-(U3-VOUT_3V3)") (pinfunction "VOUT_3V3") (pintype "power_out") (solder_paste_margin_ratio -1))
    (pad "H4" smd circle (at -1 1 270) (size 0.25 0.25) (layers "F.Cu" "F.Paste" "F.Mask")
      (net 1 "GND") (pinfunction "GND") (pintype "power_in") (solder_paste_margin_ratio -1))
    (pad "H5" smd circle (at -0.5 1 270) (size 0.25 0.25) (layers "F.Cu" "F.Paste" "F.Mask")
      (net 1 "GND") (pinfunction "GND") (pintype "power_in") (solder_paste_margin_ratio -1))
    (pad "H6" smd circle (at 0 1 180) (size 0.25 0.25) (layers "F.Cu" "F.Paste" "F.Mask")
      (net 218 "unconnected-(U3-GPIO8-PadH6)") (pinfunction "GPIO8") (pintype "bidirectional+no_connect") (solder_paste_margin_ratio -1))
    (pad "H7" smd circle (at 0.5 1 180) (size 0.25 0.25) (layers "F.Cu" "F.Paste" "F.Mask")
      (net 98 "Net-(U3-SS)") (pinfunction "SS") (pintype "output") (solder_paste_margin_ratio -1))
    (pad "H8" smd circle (at 1 1 270) (size 0.25 0.25) (layers "F.Cu" "F.Paste" "F.Mask")
      (net 1 "GND") (pinfunction "GND") (pintype "power_in") (solder_paste_margin_ratio -1))
    (pad "H10" smd circle (at 2 1 90) (size 0.25 0.25) (layers "F.Cu" "F.Paste" "F.Mask")
      (net 20 "PP_5V0") (pinfunction "PP_CABLE") (pintype "power_in") (solder_paste_margin_ratio -1))
    (pad "H11" smd oval (at 2.5 1) (size 0.25 0.17) (layers "F.Cu" "F.Paste" "F.Mask")
      (net 32 "VBUS") (pinfunction "VBUS") (pintype "power_in"))
    (pad "J1" smd oval (at -2.5 1.5) (size 0.25 0.17) (layers "F.Cu" "F.Paste" "F.Mask")
      (net 16 "AUX_P") (pinfunction "AUX_P") (pintype "bidirectional"))
    (pad "J2" smd circle (at -2 1.5 270) (size 0.25 0.25) (layers "F.Cu" "F.Paste" "F.Mask")
      (net 23 "AUX_N") (pinfunction "AUX_N") (pintype "bidirectional") (solder_paste_margin_ratio -1))
    (pad "J10" smd circle (at 2 1.5 90) (size 0.25 0.25) (layers "F.Cu" "F.Paste" "F.Mask")
      (net 32 "VBUS") (pinfunction "VBUS") (pintype "power_in") (solder_paste_margin_ratio -1))
    (pad "J11" smd oval (at 2.5 1.5) (size 0.25 0.17) (layers "F.Cu" "F.Paste" "F.Mask")
      (net 32 "VBUS") (pinfunction "VBUS") (pintype "power_in"))
    (pad "K1" smd oval (at -2.5 2) (size 0.25 0.17) (layers "F.Cu" "F.Paste" "F.Mask")
      (net 102 "Net-(U3-LDO_1V8A)") (pinfunction "LDO_1V8A") (pintype "power_out"))
    (pad "K2" smd circle (at -2 2 180) (size 0.25 0.25) (layers "F.Cu" "F.Paste" "F.Mask")
      (net 1 "GND") (pinfunction "DEBUG2(GPIO14,HD3POL)") (pintype "bidirectional") (solder_paste_margin_ratio -1))
    (pad "K3" smd circle (at -1.5 2 180) (size 0.25 0.25) (layers "F.Cu" "F.Paste" "F.Mask")
      (net 1 "GND") (pinfunction "DEBUG4(GPIO12,CONFIG2)") (pintype "bidirectional") (solder_paste_margin_ratio -1))
    (pad "K4" smd circle (at -1 2 270) (size 0.25 0.25) (layers "F.Cu" "F.Paste" "F.Mask")
      (net 66 "LSX_P2R") (pinfunction "LSX_P2R") (pintype "output") (solder_paste_margin_ratio -1))
    (pad "K5" smd circle (at -0.5 2 270) (size 0.25 0.25) (layers "F.Cu" "F.Paste" "F.Mask")
      (net 70 "USB_RP_N") (pinfunction "USB_RP_N") (pintype "bidirectional") (solder_paste_margin_ratio -1))
    (pad "K6" smd circle (at 0 2 180) (size 0.25 0.25) (layers "F.Cu" "F.Paste" "F.Mask")
      (net 33 "USB_T_P") (pinfunction "C_USB_TP") (pintype "bidirectional") (solder_paste_margin_ratio -1))
    (pad "K7" smd circle (at 0.5 2 180) (size 0.25 0.25) (layers "F.Cu" "F.Paste" "F.Mask")
      (net 38 "USB_B_P") (pinfunction "C_USB_BP") (pintype "bidirectional") (solder_paste_margin_ratio -1))
    (pad "K8" smd circle (at 1 2 180) (size 0.25 0.25) (layers "F.Cu" "F.Paste" "F.Mask")
      (net 35 "SBU1") (pinfunction "C_SBU1") (pintype "bidirectional") (solder_paste_margin_ratio -1))
    (pad "K9" smd circle (at 1.5 2 180) (size 0.25 0.25) (layers "F.Cu" "F.Paste" "F.Mask")
      (net 1 "GND") (pinfunction "RPD_G1") (pintype "bidirectional") (solder_paste_margin_ratio -1))
    (pad "K10" smd circle (at 2 2 270) (size 0.25 0.25) (layers "F.Cu" "F.Paste" "F.Mask")
      (net 1 "GND") (pinfunction "RPD_G2") (pintype "bidirectional") (solder_paste_margin_ratio -1))
    (pad "K11" smd oval (at 2.5 2) (size 0.25 0.17) (layers "F.Cu" "F.Paste" "F.Mask")
      (net 32 "VBUS") (pinfunction "VBUS") (pintype "power_in"))
    (pad "L1" smd circle (at -2.5 2.5 270) (size 0.25 0.25) (layers "F.Cu" "F.Paste" "F.Mask")
      (net 1 "GND") (pinfunction "GND") (pintype "power_in") (solder_paste_margin_ratio -1))
    (pad "L2" smd oval (at -2 2.5) (size 0.17 0.25) (layers "F.Cu" "F.Paste" "F.Mask")
      (net 1 "GND") (pinfunction "DEBUG1(GPIO15)") (pintype "bidirectional"))
    (pad "L3" smd oval (at -1.5 2.5) (size 0.17 0.25) (layers "F.Cu" "F.Paste" "F.Mask")
      (net 1 "GND") (pinfunction "DEBUG3(GPIO13,CONFIG1)") (pintype "bidirectional"))
    (pad "L4" smd oval (at -1 2.5) (size 0.17 0.25) (layers "F.Cu" "F.Paste" "F.Mask")
      (net 67 "LSX_R2P") (pinfunction "LSX_R2P") (pintype "input"))
    (pad "L5" smd oval (at -0.5 2.5) (size 0.17 0.25) (layers "F.Cu" "F.Paste" "F.Mask")
      (net 71 "USB_RP_P") (pinfunction "USB_RP_P") (pintype "bidirectional"))
    (pad "L6" smd oval (at 0 2.5) (size 0.17 0.25) (layers "F.Cu" "F.Paste" "F.Mask")
      (net 34 "USB_T_N") (pinfunction "C_USB_TN") (pintype "bidirectional"))
    (pad "L7" smd oval (at 0.5 2.5) (size 0.17 0.25) (layers "F.Cu" "F.Paste" "F.Mask")
      (net 39 "USB_B_N") (pinfunction "C_USB_BN") (pintype "bidirectional"))
    (pad "L8" smd oval (at 1 2.5) (size 0.17 0.25) (layers "F.Cu" "F.Paste" "F.Mask")
      (net 40 "SBU2") (pinfunction "C_SBU2") (pintype "bidirectional"))
    (pad "L9" smd oval (at 1.5 2.5) (size 0.17 0.25) (layers "F.Cu" "F.Paste" "F.Mask")
      (net 11 "CC1") (pinfunction "C_CC1") (pintype "bidirectional"))
    (pad "L10" smd oval (at 2 2.5) (size 0.17 0.25) (layers "F.Cu" "F.Paste" "F.Mask")
      (net 10 "CC2") (pinfunction "C_CC2") (pintype "bidirectional"))
    (pad "L11" smd circle (at 2.5 2.5) (size 0.25 0.25) (layers "F.Cu" "F.Paste" "F.Mask")
      (net 219 "unconnected-(U3-NC-PadL11)") (pinfunction "NC") (pintype "no_connect") (solder_paste_margin_ratio -1))
  )

  (footprint "antmicro-footprints:C_0603_1608Metric" (layer "F.Cu")
    (at 117.979999 60.5875)
    (descr "Capacitor SMD 0603")
    (tags "capacitor 0603")
    (property "Author" "Antmicro")
    (property "Dielectric" "")
    (property "License" "Apache-2.0")
    (property "MPN" "GRM188R60J226MEA0D")
    (property "Manufacturer" "Murata")
    (property "Sheetfile" "power.kicad_sch")
    (property "Sheetname" "Power")
    (property "Val" "22u")
    (property "Voltage" "")
    (property "ki_description" "SMD Multilayer Ceramic Capacitor, 22 µF, 6.3 V, 0603 [1608 Metric], ± 20%, X5R, GRM Series")
    (property "ki_keywords" "0603, SMT, CAPACITOR, PASSIVE, CERAMIC, MLCC")
    (attr smd)
    (fp_text reference "C47" (at -3.426 0.479) (layer "F.SilkS")
        (effects (font (size 0.7 0.7) (thickness 0.15)) (justify left bottom))
    )
    (fp_text value "C_22u_0603" (at -1.42757 1.770288) (layer "F.Fab")
        (effects (font (size 0.7 0.7) (thickness 0.15)) (justify left bottom))
    )
    (fp_text user "License: Apache-2.0" (at -1.682 5.895) (layer "F.Fab") hide
        (effects (font (size 0.7 0.7) (thickness 0.15)) (justify left bottom))
    )
    (fp_text user "Author: Antmicro" (at -1.682 4.894) (layer "F.Fab") hide
        (effects (font (size 0.7 0.7) (thickness 0.15)) (justify left bottom))
    )
    (fp_text user "${REFERENCE}" (at -1.682 3.895) (layer "F.Fab") hide
        (effects (font (size 0.7 0.7) (thickness 0.15)) (justify left bottom))
    )
    (fp_line (start -0.15 -0.4) (end 0.15 -0.4)
      (stroke (width 0.15) (type solid)) (layer "F.SilkS"))
    (fp_line (start -0.15 0.4) (end 0.15 0.4)
      (stroke (width 0.15) (type solid)) (layer "F.SilkS"))
    (fp_rect (start -1.25 -0.65) (end 1.25 0.65)
      (stroke (width 0.05) (type solid)) (fill none) (layer "F.CrtYd"))
    (fp_rect (start -0.8 -0.4) (end 0.8 0.4)
      (stroke (width 0.15) (type solid)) (fill none) (layer "F.Fab"))
    (pad "1" smd roundrect (at -0.7 0) (size 0.8 1) (layers "F.Cu" "F.Paste" "F.Mask") (roundrect_rratio 0.2)
      (net 1 "GND") (pintype "passive"))
    (pad "2" smd roundrect (at 0.7 0) (size 0.8 1) (layers "F.Cu" "F.Paste" "F.Mask") (roundrect_rratio 0.2)
      (net 100 "Net-(D2-A)") (pintype "passive"))
  )

  (footprint "antmicro-footprints:C_1206_3216Metric" (layer "F.Cu")
    (at 108.750001 64.255 90)
    (descr "Capacitor SMD 1206")
    (tags "capacitor SMD 1206")
    (property "Author" "Antmicro")
    (property "Dielectric" "")
    (property "License" "Apache-2.0")
    (property "MPN" "3216X5R1V226M160AC")
    (property "Manufacturer" "TDK")
    (property "Sheetfile" "power.kicad_sch")
    (property "Sheetname" "Power")
    (property "Val" "22u")
    (property "Voltage" "35V")
    (property "ki_description" "SMD Multilayer Ceramic Capacitors, 22µF, 35V, X5R, 1206 [2316 Metric], 20% ")
    (property "ki_keywords" "1206, SMT, CAPACITOR, PASSIVE, CERAMIC, MLCC")
    (attr smd)
    (fp_text reference "C13" (at -4.325 0.342999 90) (layer "F.SilkS")
        (effects (font (size 0.7 0.7) (thickness 0.15)) (justify left bottom))
    )
    (fp_text value "C_22u_1206_35V" (at 0 2.101 90) (layer "F.Fab")
        (effects (font (size 0.7 0.7) (thickness 0.15)) (justify left bottom))
    )
    (fp_text user "Author: Antmicro" (at -2.625 5.301 90) (layer "F.Fab") hide
        (effects (font (size 0.7 0.7) (thickness 0.15)) (justify left bottom))
    )
    (fp_text user "License: Apache-2.0" (at -2.625 6.501 90) (layer "F.Fab") hide
        (effects (font (size 0.7 0.7) (thickness 0.15)) (justify left bottom))
    )
    (fp_text user "${REFERENCE}" (at -2.625 4.101 90) (layer "F.Fab") hide
        (effects (font (size 0.7 0.7) (thickness 0.15)) (justify left bottom))
    )
    (fp_line (start 0.8 -0.899) (end -0.8 -0.899)
      (stroke (width 0.15) (type solid)) (layer "F.SilkS"))
    (fp_line (start 0.8 0.901) (end -0.8 0.901)
      (stroke (width 0.15) (type solid)) (layer "F.SilkS"))
    (fp_rect (start -2.325 -1.15) (end 2.325 1.15)
      (stroke (width 0.05) (type default)) (fill none) (layer "F.CrtYd"))
    (fp_rect (start -1.6 -0.799) (end 1.6 0.801)
      (stroke (width 0.15) (type solid)) (fill none) (layer "F.Fab"))
    (pad "1" smd roundrect (at -1.5 0.001 90) (size 1.15 1.8) (layers "F.Cu" "F.Paste" "F.Mask") (roundrect_rratio 0.25)
      (net 1 "GND") (pintype "passive"))
    (pad "2" smd roundrect (at 1.5 0.001 90) (size 1.15 1.8) (layers "F.Cu" "F.Paste" "F.Mask") (roundrect_rratio 0.25)
      (net 90 "Net-(U2-VIN)") (pintype "passive"))
  )

  (footprint "antmicro-footprints:Vishay_PowerPAK_1212-8_Single" (layer "F.Cu")
    (at 110.625 90.8 180)
    (descr "PowerPAK 1212-8 Single")
    (tags "Vishay PowerPAK 1212-8 Single")
    (property "Author" "Antmicro")
    (property "License" "Apache-2.0")
    (property "MPN" "SI7613DN-T1-GE3")
    (property "Manufacturer" "Vishay")
    (property "Sheetfile" "power.kicad_sch")
    (property "Sheetname" "Power")
    (property "ki_description" "Power MOSFET, P Channel, 20 V, 35 A, 0.0072 ohm, PowerPAK 1212, Surface Mount")
    (property "ki_keywords" "SMT, TRANSISTOR, SEMICONDUCTOR, MOSFET, PMOS")
    (attr smd)
    (fp_text reference "Q5" (at 0.643 -2.799 180) (layer "F.SilkS")
        (effects (font (size 0.7 0.7) (thickness 0.15)) (justify left bottom))
    )
    (fp_text value "SI7613DN-T1-GE3" (at 0 2.7 180) (layer "F.Fab")
        (effects (font (size 0.7 0.7) (thickness 0.15)) (justify left bottom))
    )
    (fp_text user "License: Apache-2.0" (at -8 7.1 180) (layer "F.Fab") hide
        (effects (font (size 0.7 0.7) (thickness 0.15)) (justify left bottom))
    )
    (fp_text user "${REFERENCE}" (at -8 4.7 180) (layer "F.Fab") hide
        (effects (font (size 0.7 0.7) (thickness 0.15)) (justify left bottom))
    )
    (fp_text user "Author: Antmicro" (at -8 5.9 180) (layer "F.Fab") hide
        (effects (font (size 0.7 0.7) (thickness 0.15)) (justify left bottom))
    )
    (fp_line (start -1.651 -1.651) (end -1.651 -1.317)
      (stroke (width 0.15) (type solid)) (layer "F.SilkS"))
    (fp_line (start -1.651 -1.651) (end 1.648 -1.651)
      (stroke (width 0.15) (type solid)) (layer "F.SilkS"))
    (fp_line (start -1.635 1.3) (end -1.635 1.634)
      (stroke (width 0.15) (type solid)) (layer "F.SilkS"))
    (fp_line (start -1.635 1.634) (end 1.634 1.634)
      (stroke (width 0.15) (type solid)) (layer "F.SilkS"))
    (fp_line (start 1.634 1.3) (end 1.634 1.634)
      (stroke (width 0.15) (type solid)) (layer "F.SilkS"))
    (fp_line (start 1.648 -1.651) (end 1.648 -1.317)
      (stroke (width 0.15) (type solid)) (layer "F.SilkS"))
    (fp_circle (center -1.9 -1.4) (end -1.85 -1.4)
      (stroke (width 0.15) (type solid)) (fill solid) (layer "F.SilkS"))
    (fp_rect (start -2 -1.8) (end 2 1.798)
      (stroke (width 0.05) (type solid)) (fill none) (layer "F.CrtYd"))
    (fp_line (start -1.6425 -1.4175) (end -1.4175 -1.6425)
      (stroke (width 0.15) (type solid)) (layer "F.Fab"))
    (fp_rect (start -1.651 -1.651) (end 1.648 1.648)
      (stroke (width 0.15) (type solid)) (fill none) (layer "F.Fab"))
    (pad "1" smd rect (at -1.436 -0.99 180) (size 0.99 0.405) (layers "F.Cu" "F.Paste" "F.Mask")
      (net 143 "Net-(Q3-S)") (pinfunction "S") (pintype "passive"))
    (pad "2" smd rect (at -1.436 -0.332 180) (size 0.99 0.405) (layers "F.Cu" "F.Paste" "F.Mask")
      (net 143 "Net-(Q3-S)") (pinfunction "S") (pintype "passive"))
    (pad "3" smd rect (at -1.436 0.33 180) (size 0.99 0.405) (layers "F.Cu" "F.Paste" "F.Mask")
      (net 143 "Net-(Q3-S)") (pinfunction "S") (pintype "passive"))
    (pad "4" smd rect (at -1.436 0.988 180) (size 0.99 0.405) (layers "F.Cu" "F.Paste" "F.Mask")
      (net 142 "Net-(Q3-BIAS)") (pinfunction "G") (pintype "passive"))
    (pad "5" smd custom (at 0.557 0 180) (size 1.725 2.235) (layers "F.Cu" "F.Paste" "F.Mask")
      (net 61 "12V0_MOLEX") (pinfunction "D") (pintype "passive") (zone_connect 2)
      (options (clearance outline) (anchor rect))
      (primitives
        (gr_poly
          (pts
            (xy 0.8625 0.1275)
            (xy 0.8625 -0.1275)
            (xy 1.3725 -0.1275)
            (xy 1.3725 -0.5325)
            (xy 0.8625 -0.5325)
            (xy 0.8625 -0.7875)
            (xy 1.3725 -0.7875)
            (xy 1.3725 -1.195)
            (xy 0.6125 -1.195)
            (xy 0.6125 1.195)
            (xy 1.3725 1.195)
            (xy 1.3725 0.7875)
            (xy 0.8625 0.7875)
            (xy 0.8625 0.5325)
            (xy 1.3725 0.5325)
            (xy 1.3725 0.1275)
          )
          (width 0) (fill yes))
      ))
  )

  (footprint "antmicro-footprints:R_1206_3216Metric" (layer "F.Cu")
    (at 116.16 86.35 -90)
    (property "Author" "Antmicro")
    (property "License" "Apache-2.0")
    (property "MPN" "WSLP1206R0200FEA")
    (property "Manufacturer" "Vishay")
    (property "Sheetfile" "power.kicad_sch")
    (property "Sheetname" "Power")
    (property "Tolerance" "1%")
    (property "Val" "0R02")
    (property "ki_description" "Wirewound resistor, 0.02 ohm, 1W, ±1%")
    (property "ki_keywords" "1206, SMT, RESISTOR, PASSIVE")
    (attr smd)
    (fp_text reference "R45" (at -2.022 -2.204 -90) (layer "F.SilkS")
        (effects (font (size 0.7 0.7) (thickness 0.15)) (justify left bottom))
    )
    (fp_text value "R_0R02_1206" (at -2.422356 2.103591 -90) (layer "F.Fab")
        (effects (font (size 0.7 0.7) (thickness 0.15)) (justify left bottom))
    )
    (fp_text user "${REFERENCE}" (at -2.401 3.5 -90) (layer "F.Fab") hide
        (effects (font (size 0.7 0.7) (thickness 0.15)) (justify left bottom))
    )
    (fp_text user "Author: Antmicro" (at -2.401 4.899 -90) (layer "F.Fab") hide
        (effects (font (size 0.7 0.7) (thickness 0.15)) (justify left bottom))
    )
    (fp_text user "License: Apache-2.0" (at -2.401 6.3 -90) (layer "F.Fab") hide
        (effects (font (size 0.7 0.7) (thickness 0.15)) (justify left bottom))
    )
    (fp_line (start 0.8 -0.899) (end -0.8 -0.899)
      (stroke (width 0.15) (type solid)) (layer "F.SilkS"))
    (fp_line (start 0.8 0.901) (end -0.8 0.901)
      (stroke (width 0.15) (type solid)) (layer "F.SilkS"))
    (fp_rect (start -2.325 -1.15) (end 2.325 1.15)
      (stroke (width 0.05) (type default)) (fill none) (layer "F.CrtYd"))
    (fp_line (start -1.601 -0.802) (end -1.601 0.8)
      (stroke (width 0.15) (type solid)) (layer "F.Fab"))
    (fp_line (start -1.601 -0.802) (end 1.6 -0.802)
      (stroke (width 0.15) (type solid)) (layer "F.Fab"))
    (fp_line (start -1.601 0.8) (end 1.6 0.8)
      (stroke (width 0.15) (type solid)) (layer "F.Fab"))
    (fp_line (start 1.6 -0.802) (end 1.6 0.8)
      (stroke (width 0.15) (type solid)) (layer "F.Fab"))
    (pad "1" smd roundrect (at -1.5 0.001 270) (size 1.15 1.8) (layers "F.Cu" "F.Paste" "F.Mask") (roundrect_rratio 0.25)
      (net 75 "Net-(C32-Pad2)") (pintype "passive"))
    (pad "2" smd roundrect (at 1.5 0.001 270) (size 1.15 1.8) (layers "F.Cu" "F.Paste" "F.Mask") (roundrect_rratio 0.25)
      (net 60 "12V0_DCDC") (pintype "passive"))
  )

  (footprint "antmicro-footprints:C_0603_1608Metric" (layer "F.Cu")
    (at 117.98 57.56)
    (descr "Capacitor SMD 0603")
    (tags "capacitor 0603")
    (property "Author" "Antmicro")
    (property "Dielectric" "")
    (property "License" "Apache-2.0")
    (property "MPN" "GRM188R60J226MEA0D")
    (property "Manufacturer" "Murata")
    (property "Sheetfile" "power.kicad_sch")
    (property "Sheetname" "Power")
    (property "Val" "22u")
    (property "Voltage" "")
    (property "ki_description" "SMD Multilayer Ceramic Capacitor, 22 µF, 6.3 V, 0603 [1608 Metric], ± 20%, X5R, GRM Series")
    (property "ki_keywords" "0603, SMT, CAPACITOR, PASSIVE, CERAMIC, MLCC")
    (attr smd)
    (fp_text reference "C41" (at -3.426 0.479) (layer "F.SilkS")
        (effects (font (size 0.7 0.7) (thickness 0.15)) (justify left bottom))
    )
    (fp_text value "C_22u_0603" (at -1.42757 1.770288) (layer "F.Fab")
        (effects (font (size 0.7 0.7) (thickness 0.15)) (justify left bottom))
    )
    (fp_text user "${REFERENCE}" (at -1.682 3.895) (layer "F.Fab") hide
        (effects (font (size 0.7 0.7) (thickness 0.15)) (justify left bottom))
    )
    (fp_text user "License: Apache-2.0" (at -1.682 5.895) (layer "F.Fab") hide
        (effects (font (size 0.7 0.7) (thickness 0.15)) (justify left bottom))
    )
    (fp_text user "Author: Antmicro" (at -1.682 4.894) (layer "F.Fab") hide
        (effects (font (size 0.7 0.7) (thickness 0.15)) (justify left bottom))
    )
    (fp_line (start -0.15 -0.4) (end 0.15 -0.4)
      (stroke (width 0.15) (type solid)) (layer "F.SilkS"))
    (fp_line (start -0.15 0.4) (end 0.15 0.4)
      (stroke (width 0.15) (type solid)) (layer "F.SilkS"))
    (fp_rect (start -1.25 -0.65) (end 1.25 0.65)
      (stroke (width 0.05) (type solid)) (fill none) (layer "F.CrtYd"))
    (fp_rect (start -0.8 -0.4) (end 0.8 0.4)
      (stroke (width 0.15) (type solid)) (fill none) (layer "F.Fab"))
    (pad "1" smd roundrect (at -0.7 0) (size 0.8 1) (layers "F.Cu" "F.Paste" "F.Mask") (roundrect_rratio 0.2)
      (net 1 "GND") (pintype "passive"))
    (pad "2" smd roundrect (at 0.7 0) (size 0.8 1) (layers "F.Cu" "F.Paste" "F.Mask") (roundrect_rratio 0.2)
      (net 100 "Net-(D2-A)") (pintype "passive"))
  )

  (footprint "antmicro-footprints:TP_SMD_1mm" (layer "F.Cu")
    (at 111.7 88.3)
    (property "Author" "Antmicro")
    (property "License" "Apache-2.0")
    (property "MPN" "")
    (property "Manufacturer" "")
    (property "Sheetfile" "power.kicad_sch")
    (property "Sheetname" "Power")
    (property "exclude_from_bom" "")
    (property "ki_description" "Test point 1mm SMD")
    (property "ki_keywords" "TESTPOINT")
    (attr exclude_from_pos_files exclude_from_bom)
    (fp_text reference "TP3" (at -1.21 -0.797) (layer "F.SilkS")
        (effects (font (size 0.7 0.7) (thickness 0.15)) (justify left bottom))
    )
    (fp_text value "TP_1mm_SMD" (at 0 1.4) (layer "F.Fab")
        (effects (font (size 0.7 0.7) (thickness 0.15)) (justify left bottom))
    )
    (fp_text user "${REFERENCE}" (at -0.5 2.8) (layer "F.Fab") hide
        (effects (font (size 0.7 0.7) (thickness 0.15)) (justify left bottom))
    )
    (fp_text user "License: Apache-2.0" (at -0.5 5.2) (layer "F.Fab") hide
        (effects (font (size 0.7 0.7) (thickness 0.15)) (justify left bottom))
    )
    (fp_text user "Author: Antmicro" (at -0.5 4) (layer "F.Fab") hide
        (effects (font (size 0.7 0.7) (thickness 0.15)) (justify left bottom))
    )
    (fp_circle (center 0 0) (end 0.6 0)
      (stroke (width 0.05) (type default)) (fill none) (layer "F.CrtYd"))
    (pad "1" smd circle (at 0 0) (size 1 1) (layers "F.Cu" "F.Mask")
      (net 157 "Net-(U1-~{PGOOD})") (pinfunction "1") (pintype "passive"))
  )

  (footprint "antmicro-footprints:MP_Pad6mm_Drill3mm" (layer "F.Cu")
    (at 104 54)
    (property "Author" "Antmicro")
    (property "License" "Apache-2.0")
    (property "Sheetfile" "connectors.kicad_sch")
    (property "Sheetname" "Connectors")
    (property "exclude_from_bom" "")
    (property "ki_description" "Mechanical part")
    (property "ki_keywords" "MECHANICAL")
    (attr exclude_from_pos_files exclude_from_bom)
    (fp_text reference "MP1" (at 0 -3.2) (layer "F.SilkS") hide
        (effects (font (size 0.7 0.7) (thickness 0.15)) (justify left bottom))
    )
    (fp_text value "MP_Pad6mm_Drill3mm" (at 0 3.9) (layer "F.Fab")
        (effects (font (size 0.7 0.7) (thickness 0.15)) (justify left bottom))
    )
    (fp_text user "License: Apache-2.0" (at -0.178 8.425) (layer "F.Fab") hide
        (effects (font (size 0.7 0.7) (thickness 0.15)) (justify left bottom))
    )
    (fp_text user "${REFERENCE}" (at -0.178 6.025) (layer "F.Fab") hide
        (effects (font (size 0.7 0.7) (thickness 0.15)) (justify left bottom))
    )
    (fp_text user "Author: Antmicro" (at -0.178 7.225) (layer "F.Fab") hide
        (effects (font (size 0.7 0.7) (thickness 0.15)) (justify left bottom))
    )
    (fp_circle (center 0 0) (end 3.25 0)
      (stroke (width 0.05) (type default)) (fill none) (layer "F.CrtYd"))
    (pad "1" thru_hole circle (at 0 0) (size 6 6) (drill 3) (layers "*.Cu" "*.Mask")
      (net 1 "GND") (pintype "passive"))
  )

  (footprint "antmicro-footprints:SOIC-8_5.3x5.3x2mm_P1.27mm" (layer "F.Cu")
    (at 137.147856 62.3)
    (descr "8-Pin SOIC 208-mil")
    (property "Author" "Antmicro")
    (property "License" "Apache-2.0")
    (property "MPN" "MX25L8006EM2I-12G")
    (property "Manufacturer" "Macronix")
    (property "Sheetfile" "tb.kicad_sch")
    (property "Sheetname" "TB Controller")
    (property "dnp" "")
    (property "ki_description" "FLASH - NOR Memory IC 8Mbit SPI 86 MHz 8-SOP")
    (property "ki_keywords" "SMT, MEMORY, IC, FLASH, SPI")
    (attr smd)
    (fp_text reference "U7" (at 0.520144 -3.245) (layer "F.SilkS")
        (effects (font (size 0.7 0.7) (thickness 0.15)) (justify left bottom))
    )
    (fp_text value "MX25L8006EM2I-12G" (at 0 3.8) (layer "F.Fab")
        (effects (font (size 0.7 0.7) (thickness 0.15)) (justify left bottom))
    )
    (fp_text user "License: Apache-2.0" (at -4.675 6.938) (layer "F.Fab") hide
        (effects (font (size 0.7 0.7) (thickness 0.15)) (justify left bottom))
    )
    (fp_text user "Author: Antmicro" (at -4.675 5.938) (layer "F.Fab") hide
        (effects (font (size 0.7 0.7) (thickness 0.15)) (justify left bottom))
    )
    (fp_text user "${REFERENCE}" (at -4.675 4.938) (layer "F.Fab") hide
        (effects (font (size 0.7 0.7) (thickness 0.15)) (justify left bottom))
    )
    (fp_line (start -2.8 -2.641) (end -4.4 -2.641)
      (stroke (width 0.15) (type solid)) (layer "F.SilkS"))
    (fp_circle (center -4.85 -1.905) (end -4.8 -1.855)
      (stroke (width 0.15) (type solid)) (fill solid) (layer "F.SilkS"))
    (fp_rect (start 4.675 -3) (end -4.675 3)
      (stroke (width 0.05) (type solid)) (fill none) (layer "F.CrtYd"))
    (fp_line (start -2.641 -2.641) (end 2.64 -2.641)
      (stroke (width 0.15) (type solid)) (layer "F.Fab"))
    (fp_line (start -2.641 -1.371) (end -1.371 -2.641)
      (stroke (width 0.15) (type solid)) (layer "F.Fab"))
    (fp_line (start -2.641 2.64) (end -2.641 -2.641)
      (stroke (width 0.15) (type solid)) (layer "F.Fab"))
    (fp_line (start 2.64 -2.641) (end 2.64 2.64)
      (stroke (width 0.15) (type solid)) (layer "F.Fab"))
    (fp_line (start 2.64 2.64) (end -2.641 2.64)
      (stroke (width 0.15) (type solid)) (layer "F.Fab"))
    (pad "1" smd roundrect (at -3.601 -1.905 90) (size 0.65 1.65) (layers "F.Cu" "F.Paste" "F.Mask") (roundrect_rratio 0.25)
      (net 65 "SPI_CS") (pinfunction "~{CS}") (pintype "input"))
    (pad "2" smd roundrect (at -3.601 -0.635 90) (size 0.65 1.65) (layers "F.Cu" "F.Paste" "F.Mask") (roundrect_rratio 0.25)
      (net 63 "SPI_MISO") (pinfunction "SO/IO1") (pintype "input"))
    (pad "3" smd roundrect (at -3.601 0.633 90) (size 0.65 1.65) (layers "F.Cu" "F.Paste" "F.Mask") (roundrect_rratio 0.25)
      (net 64 "/TB Controller/FLASH_WP") (pinfunction "~{WP}") (pintype "input"))
    (pad "4" smd roundrect (at -3.601 1.904 90) (size 0.65 1.65) (layers "F.Cu" "F.Paste" "F.Mask") (roundrect_rratio 0.25)
      (net 1 "GND") (pinfunction "GND") (pintype "power_in"))
    (pad "5" smd roundrect (at 3.6 1.904 90) (size 0.65 1.65) (layers "F.Cu" "F.Paste" "F.Mask") (roundrect_rratio 0.25)
      (net 69 "SPI_MOSI") (pinfunction "SI/IO0") (pintype "input"))
    (pad "6" smd roundrect (at 3.6 0.633 90) (size 0.65 1.65) (layers "F.Cu" "F.Paste" "F.Mask") (roundrect_rratio 0.25)
      (net 68 "SPI_SCLK") (pinfunction "SCLK") (pintype "input"))
    (pad "7" smd roundrect (at 3.6 -0.635 90) (size 0.65 1.65) (layers "F.Cu" "F.Paste" "F.Mask") (roundrect_rratio 0.25)
      (net 89 "/TB Controller/FLASH_HOLD") (pinfunction "~{HOLD}") (pintype "input"))
    (pad "8" smd roundrect (at 3.6 -1.905 90) (size 0.65 1.65) (layers "F.Cu" "F.Paste" "F.Mask") (roundrect_rratio 0.25)
      (net 2 "3V3_SYS") (pinfunction "VCC") (pintype "power_in"))
  )

  (footprint "antmicro-footprints:QFN-32-4EP_4x6mm_P0.5mm" (layer "F.Cu")
    (at 110.325 82.15)
    (property "Author" "Antmicro")
    (property "License" "Apache-2.0")
    (property "MPN" "LT8350RV#PBF")
    (property "Manufacturer" "Analog Devices")
    (property "Sheetfile" "power.kicad_sch")
    (property "Sheetname" "Power")
    (property "ki_description" "DC/DC converter")
    (property "ki_keywords" "SMT, PMIC, IC, POWER, MANAGEMENT, VOLTAGE, REGULATOR")
    (attr smd)
    (fp_text reference "U1" (at 0 -3.5 unlocked) (layer "F.SilkS")
        (effects (font (size 0.7 0.7) (thickness 0.15)) (justify left bottom))
    )
    (fp_text value "LT8350RV" (at 0 4.25 unlocked) (layer "F.Fab")
        (effects (font (size 0.7 0.7) (thickness 0.15)) (justify left bottom))
    )
    (fp_text user "Author: Antmicro" (at -2.54 8.65) (layer "F.Fab") hide
        (effects (font (size 0.7 0.7) (thickness 0.15)) (justify left bottom))
    )
    (fp_text user "${REFERENCE}" (at -2.54 7.45 unlocked) (layer "F.Fab") hide
        (effects (font (size 0.7 0.7) (thickness 0.15)) (justify left bottom))
    )
    (fp_text user "License: Apache-2.0" (at -2.54 6.25) (layer "F.Fab") hide
        (effects (font (size 0.7 0.7) (thickness 0.15)) (justify left bottom))
    )
    (fp_line (start -2 -1) (end -2 -0.5)
      (stroke (width 0.15) (type solid)) (layer "F.SilkS"))
    (fp_line (start 2 -2.5) (end 2 -2)
      (stroke (width 0.15) (type solid)) (layer "F.SilkS"))
    (fp_line (start 2 -1) (end 2 -0.5)
      (stroke (width 0.15) (type solid)) (layer "F.SilkS"))
    (fp_circle (center -2.15 -2.05) (end -2.1 -2.05)
      (stroke (width 0.15) (type solid)) (fill none) (layer "F.SilkS"))
    (fp_rect (start -2.3 -3.3) (end 2.3 3.3)
      (stroke (width 0.05) (type solid)) (fill none) (layer "F.CrtYd"))
    (fp_line (start -2 -2) (end -2 3)
      (stroke (width 0.15) (type solid)) (layer "F.Fab"))
    (fp_line (start -2 3) (end -2 3)
      (stroke (width 0.15) (type solid)) (layer "F.Fab"))
    (fp_line (start -2 3) (end 2 3)
      (stroke (width 0.15) (type solid)) (layer "F.Fab"))
    (fp_line (start -1 -3) (end -2 -2)
      (stroke (width 0.15) (type solid)) (layer "F.Fab"))
    (fp_line (start 2 -3) (end -1 -3)
      (stroke (width 0.15) (type solid)) (layer "F.Fab"))
    (fp_line (start 2 3) (end 2 -3)
      (stroke (width 0.15) (type solid)) (layer "F.Fab"))
    (pad "2" smd rect (at -1.899 -1.75) (size 0.7 0.25) (layers "F.Cu" "F.Paste" "F.Mask")
      (net 74 "Net-(C10-Pad2)") (pinfunction "VIN") (pintype "power_in"))
    (pad "3" smd rect (at -1.899 -1.25) (size 0.7 0.25) (layers "F.Cu" "F.Paste" "F.Mask")
      (net 74 "Net-(C10-Pad2)") (pinfunction "VIN") (pintype "passive"))
    (pad "5" smd rect (at -1.899 -0.25) (size 0.7 0.25) (layers "F.Cu" "F.Paste" "F.Mask")
      (net 88 "/Power/DCDC_EN") (pinfunction "EN/UVLO") (pintype "input"))
    (pad "6" smd rect (at -1.899 0.25) (size 0.7 0.25) (layers "F.Cu" "F.Paste" "F.Mask")
      (net 91 "Net-(U1-INTVCC)") (pinfunction "INTVCC") (pintype "power_out"))
    (pad "7" smd rect (at -1.899 0.75) (size 0.7 0.25) (layers "F.Cu" "F.Paste" "F.Mask")
      (net 91 "Net-(U1-INTVCC)") (pinfunction "RP") (pintype "unspecified"))
    (pad "8" smd rect (at -1.899 1.25) (size 0.7 0.25) (layers "F.Cu" "F.Paste" "F.Mask")
      (net 148 "Net-(U1-LOADEN)") (pinfunction "LOADEN") (pintype "input"))
    (pad "9" smd rect (at -1.899 1.75) (size 0.7 0.25) (layers "F.Cu" "F.Paste" "F.Mask")
      (net 5 "Net-(U1-VREF)") (pinfunction "VREF") (pintype "power_out"))
    (pad "10" smd rect (at -1.899 2.25) (size 0.7 0.25) (layers "F.Cu" "F.Paste" "F.Mask")
      (net 206 "Net-(U1-ISMON)") (pinfunction "ISMON") (pintype "output"))
    (pad "11" smd rect (at -1.25 2.9 90) (size 0.7 0.25) (layers "F.Cu" "F.Paste" "F.Mask")
      (net 84 "/Power/I_SENSE_P") (pinfunction "ISP") (pintype "input"))
    (pad "12" smd rect (at -0.75 2.9 90) (size 0.7 0.25) (layers "F.Cu" "F.Paste" "F.Mask")
      (net 85 "/Power/I_SENSE_N") (pinfunction "ISN") (pintype "input"))
    (pad "13" smd rect (at -0.25 2.9 90) (size 0.7 0.25) (layers "F.Cu" "F.Paste" "F.Mask")
      (net 147 "Net-(U1-CTRL)") (pinfunction "CTRL") (pintype "input"))
    (pad "14" smd rect (at 0.25 2.9 90) (size 0.7 0.25) (layers "F.Cu" "F.Paste" "F.Mask")
      (net 169 "Net-(U1-FB)") (pinfunction "FB") (pintype "input"))
    (pad "15" smd rect (at 0.75 2.9 90) (size 0.7 0.25) (layers "F.Cu" "F.Paste" "F.Mask")
      (net 160 "Net-(U1-VC)") (pinfunction "VC") (pintype "output"))
    (pad "16" smd rect (at 1.25 2.9 90) (size 0.7 0.25) (layers "F.Cu" "F.Paste" "F.Mask")
      (net 157 "Net-(U1-~{PGOOD})") (pinfunction "~{PGOOD}") (pintype "open_collector"))
    (pad "17" smd rect (at 1.899 2.25) (size 0.7 0.25) (layers "F.Cu" "F.Paste" "F.Mask")
      (net 92 "Net-(U1-SS)") (pinfunction "SS") (pintype "input"))
    (pad "18" smd rect (at 1.899 1.75) (size 0.7 0.25) (layers "F.Cu" "F.Paste" "F.Mask")
      (net 161 "Net-(U1-RT)") (pinfunction "RT") (pintype "input"))
    (pad "19" smd rect (at 1.899 1.25) (size 0.7 0.25) (layers "F.Cu" "F.Paste" "F.Mask")
      (net 159 "Net-(U1-SYNC{slash}MODE)") (pinfunction "SYNC/MODE") (pintype "input"))
    (pad "20" smd rect (at 1.899 0.75) (size 0.7 0.25) (layers "F.Cu" "F.Paste" "F.Mask")
      (net 207 "Net-(U1-CLKOUT)") (pinfunction "CLKOUT") (pintype "output"))
    (pad "21" smd rect (at 1.899 0.25) (size 0.7 0.25) (layers "F.Cu" "F.Paste" "F.Mask")
      (net 97 "Net-(U1-EXTVCC)") (pinfunction "EXTVCC") (pintype "power_in"))
    (pad "22" smd rect (at 1.899 -0.25) (size 0.7 0.25) (layers "F.Cu" "F.Paste" "F.Mask")
      (net 205 "Net-(U1-LOADTG)") (pinfunction "LOADTG") (pintype "output"))
    (pad "24" smd rect (at 1.899 -1.25) (size 0.7 0.25) (layers "F.Cu" "F.Paste" "F.Mask")
      (net 75 "Net-(C32-Pad2)") (pinfunction "VOUT") (pintype "power_out"))
    (pad "25" smd rect (at 1.899 -1.75) (size 0.7 0.25) (layers "F.Cu" "F.Paste" "F.Mask")
      (net 75 "Net-(C32-Pad2)") (pinfunction "VOUT") (pintype "passive"))
    (pad "27" smd rect (at 1.25 -2.9 90) (size 0.7 0.25) (layers "F.Cu" "F.Paste" "F.Mask")
      (net 268 "Net-(C28-Pad2)") (pinfunction "SW2") (pintype "output"))
    (pad "28" smd rect (at 0.75 -2.9 90) (size 0.7 0.25) (layers "F.Cu" "F.Paste" "F.Mask")
      (net 268 "Net-(C28-Pad2)") (pinfunction "SW2") (pintype "passive"))
    (pad "29" smd rect (at 0.25 -2.9 90) (size 0.7 0.25) (layers "F.Cu" "F.Paste" "F.Mask")
      (net 96 "Net-(U1-BST2)") (pinfunction "BST2") (pintype "input"))
    (pad "30" smd rect (at -0.25 -2.9 90) (size 0.7 0.25) (layers "F.Cu" "F.Paste" "F.Mask")
      (net 93 "Net-(U1-BST1)") (pinfunction "BST1") (pintype "input"))
    (pad "31" smd rect (at -0.75 -2.9 90) (size 0.7 0.25) (layers "F.Cu" "F.Paste" "F.Mask")
      (net 4 "Net-(C26-Pad2)") (pinfunction "SW1") (pintype "output"))
    (pad "32" smd rect (at -1.25 -2.9 90) (size 0.7 0.25) (layers "F.Cu" "F.Paste" "F.Mask")
      (net 4 "Net-(C26-Pad2)") (pinfunction "SW1") (pintype "passive"))
    (pad "33" smd rect (at -0.696 -1.055 90) (size 1.91 1.2) (layers "F.Cu" "F.Paste" "F.Mask")
      (net 1 "GND") (pinfunction "GND") (pintype "power_in"))
    (pad "34" smd rect (at 0.696 -1.055 90) (size 1.91 1.2) (layers "F.Cu" "F.Paste" "F.Mask")
      (net 1 "GND") (pinfunction "GND") (pintype "passive"))
    (pad "35" smd rect (at -0.696 1.055 90) (size 1.91 1.2) (layers "F.Cu" "F.Paste" "F.Mask")
      (net 1 "GND") (pinfunction "GND") (pintype "passive"))
    (pad "36" smd rect (at 0.696 1.055 90) (size 1.91 1.2) (layers "F.Cu" "F.Paste" "F.Mask")
      (net 1 "GND") (pinfunction "GND") (pintype "passive"))
    (pad "MP" smd rect (at -1.812 -2.812 90) (size 0.375 0.375) (layers "F.Cu" "F.Paste" "F.Mask")
      (net 1 "GND") (pinfunction "MP") (pintype "passive"))
    (pad "MP" smd rect (at -1.812 2.812 90) (size 0.375 0.375) (layers "F.Cu" "F.Paste" "F.Mask")
      (net 1 "GND") (pinfunction "MP") (pintype "passive"))
    (pad "MP" smd rect (at 1.812 -2.812 90) (size 0.375 0.375) (layers "F.Cu" "F.Paste" "F.Mask")
      (net 1 "GND") (pinfunction "MP") (pintype "passive"))
    (pad "MP" smd rect (at 1.812 2.812 90) (size 0.375 0.375) (layers "F.Cu" "F.Paste" "F.Mask")
      (net 1 "GND") (pinfunction "MP") (pintype "passive"))
  )

  (footprint "antmicro-footprints:MP_Pad6mm_Drill3mm" (layer "F.Cu")
    (at 166 96)
    (property "Author" "Antmicro")
    (property "License" "Apache-2.0")
    (property "Sheetfile" "connectors.kicad_sch")
    (property "Sheetname" "Connectors")
    (property "exclude_from_bom" "")
    (property "ki_description" "Mechanical part")
    (property "ki_keywords" "MECHANICAL")
    (attr exclude_from_pos_files exclude_from_bom)
    (fp_text reference "MP3" (at 0 -3.2) (layer "F.SilkS") hide
        (effects (font (size 0.7 0.7) (thickness 0.15)) (justify left bottom))
    )
    (fp_text value "MP_Pad6mm_Drill3mm" (at 0 3.9) (layer "F.Fab")
        (effects (font (size 0.7 0.7) (thickness 0.15)) (justify left bottom))
    )
    (fp_text user "${REFERENCE}" (at -0.178 6.025) (layer "F.Fab") hide
        (effects (font (size 0.7 0.7) (thickness 0.15)) (justify left bottom))
    )
    (fp_text user "License: Apache-2.0" (at -0.178 8.425) (layer "F.Fab") hide
        (effects (font (size 0.7 0.7) (thickness 0.15)) (justify left bottom))
    )
    (fp_text user "Author: Antmicro" (at -0.178 7.225) (layer "F.Fab") hide
        (effects (font (size 0.7 0.7) (thickness 0.15)) (justify left bottom))
    )
    (fp_circle (center 0 0) (end 3.25 0)
      (stroke (width 0.05) (type default)) (fill none) (layer "F.CrtYd"))
    (pad "1" thru_hole circle (at 0 0) (size 6 6) (drill 3) (layers "*.Cu" "*.Mask")
      (net 1 "GND") (pintype "passive"))
  )

  (footprint "antmicro-footprints:C_0603_1608Metric" (layer "F.Cu")
    (at 117.085001 79.9 -90)
    (descr "Capacitor SMD 0603")
    (tags "capacitor 0603")
    (property "Author" "Antmicro")
    (property "Dielectric" "")
    (property "License" "Apache-2.0")
    (property "MPN" "CL10A226MO7JZNC")
    (property "Manufacturer" "Samsung Electro-Mechanics")
    (property "Sheetfile" "power.kicad_sch")
    (property "Sheetname" "Power")
    (property "Val" "22u")
    (property "Voltage" "16V")
    (property "ki_description" "SMD Multilayer Ceramic Capacitor")
    (property "ki_keywords" "0603, SMT, CAPACITOR, PASSIVE, CERAMIC")
    (attr smd)
    (fp_text reference "C46" (at -1.16 -0.340998 -90) (layer "F.SilkS")
        (effects (font (size 0.7 0.7) (thickness 0.15)) (justify left bottom))
    )
    (fp_text value "C_22u_16V_0603" (at -1.42757 1.770288 -90) (layer "F.Fab")
        (effects (font (size 0.7 0.7) (thickness 0.15)) (justify left bottom))
    )
    (fp_text user "License: Apache-2.0" (at -1.682 5.895 -90) (layer "F.Fab") hide
        (effects (font (size 0.7 0.7) (thickness 0.15)) (justify left bottom))
    )
    (fp_text user "${REFERENCE}" (at -1.682 3.895 -90) (layer "F.Fab") hide
        (effects (font (size 0.7 0.7) (thickness 0.15)) (justify left bottom))
    )
    (fp_text user "Author: Antmicro" (at -1.682 4.894 -90) (layer "F.Fab") hide
        (effects (font (size 0.7 0.7) (thickness 0.15)) (justify left bottom))
    )
    (fp_line (start -0.15 -0.4) (end 0.15 -0.4)
      (stroke (width 0.15) (type solid)) (layer "F.SilkS"))
    (fp_line (start -0.15 0.4) (end 0.15 0.4)
      (stroke (width 0.15) (type solid)) (layer "F.SilkS"))
    (fp_rect (start -1.25 -0.65) (end 1.25 0.65)
      (stroke (width 0.05) (type solid)) (fill none) (layer "F.CrtYd"))
    (fp_rect (start -0.8 -0.4) (end 0.8 0.4)
      (stroke (width 0.15) (type solid)) (fill none) (layer "F.Fab"))
    (pad "1" smd roundrect (at -0.7 0 270) (size 0.8 1) (layers "F.Cu" "F.Paste" "F.Mask") (roundrect_rratio 0.2)
      (net 1 "GND") (pintype "passive"))
    (pad "2" smd roundrect (at 0.7 0 270) (size 0.8 1) (layers "F.Cu" "F.Paste" "F.Mask") (roundrect_rratio 0.2)
      (net 75 "Net-(C32-Pad2)") (pintype "passive"))
  )

  (footprint "antmicro-footprints:SOT-323" (layer "F.Cu")
    (at 147.5 70.94)
    (property "Author" "Antmicro")
    (property "License" "Apache-2.0")
    (property "MPN" "BC817-25W,115")
    (property "Manufacturer" "Nexperia")
    (property "Sheetfile" "tb-power.kicad_sch")
    (property "Sheetname" "Thunderbolt Controller - Power")
    (property "ki_description" "Bipolar (BJT) Single Transistor, NPN, 45 V, 500 mA, 200 mW, SOT-323, Surface Mount")
    (property "ki_keywords" "SMT, TRANSISTOR, SEMICONDUCTOR, BIPOLAR")
    (attr smd)
    (fp_text reference "Q1" (at 1.471 0.434) (layer "F.SilkS")
        (effects (font (size 0.7 0.7) (thickness 0.15)) (justify left bottom))
    )
    (fp_text value "BC817-25W" (at 0 2.749) (layer "F.Fab")
        (effects (font (size 0.7 0.7) (thickness 0.15)) (justify left bottom))
    )
    (fp_text user "${REFERENCE}" (at -1.35 4.749) (layer "F.Fab") hide
        (effects (font (size 0.7 0.7) (thickness 0.15)) (justify left bottom))
    )
    (fp_text user "License: Apache-2.0" (at -1.35 5.949) (layer "F.Fab") hide
        (effects (font (size 0.7 0.7) (thickness 0.15)) (justify left bottom))
    )
    (fp_text user "Author: Antmicro" (at -1.35 7.149) (layer "F.Fab") hide
        (effects (font (size 0.7 0.7) (thickness 0.15)) (justify left bottom))
    )
    (fp_line (start -0.802 -1.2) (end -0.802 -1.05)
      (stroke (width 0.15) (type solid)) (layer "F.SilkS"))
    (fp_line (start -0.802 1.05) (end -0.802 1.199)
      (stroke (width 0.15) (type solid)) (layer "F.SilkS"))
    (fp_line (start -0.802 1.199) (end -0.5 1.199)
      (stroke (width 0.15) (type solid)) (layer "F.SilkS"))
    (fp_line (start -0.402 -1.2) (end -0.802 -1.2)
      (stroke (width 0.15) (type solid)) (layer "F.SilkS"))
    (fp_line (start 0.498 -1.2) (end 0.8 -1.2)
      (stroke (width 0.15) (type solid)) (layer "F.SilkS"))
    (fp_line (start 0.498 1.199) (end 0.8 1.199)
      (stroke (width 0.15) (type solid)) (layer "F.SilkS"))
    (fp_line (start 0.8 -1.2) (end 0.8 -0.902)
      (stroke (width 0.15) (type solid)) (layer "F.SilkS"))
    (fp_line (start 0.8 1.199) (end 0.8 0.9)
      (stroke (width 0.15) (type solid)) (layer "F.SilkS"))
    (fp_circle (center -1.05 -1.156824) (end -1 -1.129824)
      (stroke (width 0.15) (type solid)) (fill none) (layer "F.SilkS"))
    (fp_rect (start -1.35 -1.35) (end 1.35 1.35)
      (stroke (width 0.05) (type solid)) (fill none) (layer "F.CrtYd"))
    (fp_line (start -0.677 -1.101) (end -0.677 1.1)
      (stroke (width 0.15) (type solid)) (layer "F.Fab"))
    (fp_line (start -0.677 -1.101) (end 0.675 -1.101)
      (stroke (width 0.15) (type solid)) (layer "F.Fab"))
    (fp_line (start -0.677 1.1) (end 0.675 1.1)
      (stroke (width 0.15) (type solid)) (layer "F.Fab"))
    (fp_line (start 0.675 -1.101) (end 0.675 1.1)
      (stroke (width 0.15) (type solid)) (layer "F.Fab"))
    (pad "1" smd rect (at -0.927 -0.652) (size 0.55 0.6) (layers "F.Cu" "F.Paste" "F.Mask")
      (net 138 "Net-(Q1-B)") (pinfunction "B") (pintype "input"))
    (pad "2" smd rect (at -0.927 0.65) (size 0.55 0.6) (layers "F.Cu" "F.Paste" "F.Mask")
      (net 1 "GND") (pinfunction "E") (pintype "passive"))
    (pad "3" smd rect (at 0.925 0) (size 0.55 0.6) (layers "F.Cu" "F.Paste" "F.Mask")
      (net 139 "Net-(Q1-C)") (pinfunction "C") (pintype "passive"))
  )

  (footprint "antmicro-footprints:C_0603_1608Metric" (layer "F.Cu")
    (at 142.9 72.3 90)
    (descr "Capacitor SMD 0603")
    (tags "capacitor 0603")
    (property "Author" "Antmicro")
    (property "Dielectric" "")
    (property "License" "Apache-2.0")
    (property "MPN" "GRM188R60J226MEA0D")
    (property "Manufacturer" "Murata")
    (property "Sheetfile" "tb-power.kicad_sch")
    (property "Sheetname" "Thunderbolt Controller - Power")
    (property "Val" "22u")
    (property "Voltage" "")
    (property "ki_description" "SMD Multilayer Ceramic Capacitor, 22 µF, 6.3 V, 0603 [1608 Metric], ± 20%, X5R, GRM Series")
    (property "ki_keywords" "0603, SMT, CAPACITOR, PASSIVE, CERAMIC, MLCC")
    (attr smd)
    (fp_text reference "C82" (at -3.519 0.483 90) (layer "F.SilkS")
        (effects (font (size 0.7 0.7) (thickness 0.15)) (justify left bottom))
    )
    (fp_text value "C_22u_0603" (at -1.42757 1.770288 90) (layer "F.Fab")
        (effects (font (size 0.7 0.7) (thickness 0.15)) (justify left bottom))
    )
    (fp_text user "License: Apache-2.0" (at -1.682 5.895 90) (layer "F.Fab") hide
        (effects (font (size 0.7 0.7) (thickness 0.15)) (justify left bottom))
    )
    (fp_text user "Author: Antmicro" (at -1.682 4.894 90) (layer "F.Fab") hide
        (effects (font (size 0.7 0.7) (thickness 0.15)) (justify left bottom))
    )
    (fp_text user "${REFERENCE}" (at -1.682 3.895 90) (layer "F.Fab") hide
        (effects (font (size 0.7 0.7) (thickness 0.15)) (justify left bottom))
    )
    (fp_line (start -0.15 -0.4) (end 0.15 -0.4)
      (stroke (width 0.15) (type solid)) (layer "F.SilkS"))
    (fp_line (start -0.15 0.4) (end 0.15 0.4)
      (stroke (width 0.15) (type solid)) (layer "F.SilkS"))
    (fp_rect (start -1.25 -0.65) (end 1.25 0.65)
      (stroke (width 0.05) (type solid)) (fill none) (layer "F.CrtYd"))
    (fp_rect (start -0.8 -0.4) (end 0.8 0.4)
      (stroke (width 0.15) (type solid)) (fill none) (layer "F.Fab"))
    (pad "1" smd roundrect (at -0.7 0 90) (size 0.8 1) (layers "F.Cu" "F.Paste" "F.Mask") (roundrect_rratio 0.2)
      (net 1 "GND") (pintype "passive"))
    (pad "2" smd roundrect (at 0.7 0 90) (size 0.8 1) (layers "F.Cu" "F.Paste" "F.Mask") (roundrect_rratio 0.2)
      (net 112 "Net-(U4A-VCC0P9_SVR_SENSE)") (pintype "passive"))
  )

  (footprint "antmicro-footprints:SOT-363" (layer "F.Cu")
    (at 106.9475 91.3 90)
    (property "Author" "Antmicro")
    (property "License" "Apache-2.0")
    (property "MPN" "DZDH0401DW")
    (property "Manufacturer" "Diodes Incorporated")
    (property "Sheetfile" "power.kicad_sch")
    (property "Sheetname" "Power")
    (property "ki_description" "OR Controller N+1 ORing Controller P-Channel 1:1 SOT-363")
    (property "ki_keywords" "SMT, CONTROLLER, SEMICONDUCTOR, DIODE, PMOS")
    (attr smd)
    (fp_text reference "Q3" (at -0.775 -1.5 90) (layer "F.SilkS")
        (effects (font (size 0.7 0.7) (thickness 0.15)) (justify left bottom))
    )
    (fp_text value "DZDH0401DW" (at 0 2.2 90) (layer "F.Fab")
        (effects (font (size 0.7 0.7) (thickness 0.15)) (justify left bottom))
    )
    (fp_text user "${REFERENCE}" (at -1.3 4 90) (layer "F.Fab") hide
        (effects (font (size 0.7 0.7) (thickness 0.15)) (justify left bottom))
    )
    (fp_text user "Author: Antmicro" (at -1.3 6.4 90) (layer "F.Fab") hide
        (effects (font (size 0.7 0.7) (thickness 0.15)) (justify left bottom))
    )
    (fp_text user "License: Apache-2.0" (at -1.3 5.2 90) (layer "F.Fab") hide
        (effects (font (size 0.7 0.7) (thickness 0.15)) (justify left bottom))
    )
    (fp_line (start -0.8 1.146) (end -0.8 1.223)
      (stroke (width 0.15) (type solid)) (layer "F.SilkS"))
    (fp_line (start -0.8 1.223) (end 0.803 1.223)
      (stroke (width 0.15) (type solid)) (layer "F.SilkS"))
    (fp_line (start -0.72 -1.153) (end -0.72 -1.228)
      (stroke (width 0.15) (type solid)) (layer "F.SilkS"))
    (fp_line (start 0.803 -1.228) (end -0.72 -1.228)
      (stroke (width 0.15) (type solid)) (layer "F.SilkS"))
    (fp_line (start 0.803 -1.153) (end 0.803 -1.228)
      (stroke (width 0.15) (type solid)) (layer "F.SilkS"))
    (fp_line (start 0.803 1.146) (end 0.803 1.223)
      (stroke (width 0.15) (type solid)) (layer "F.SilkS"))
    (fp_circle (center -0.978102 -1.2) (end -0.928102 -1.2)
      (stroke (width 0.15) (type solid)) (fill solid) (layer "F.SilkS"))
    (fp_rect (start 1.3 -1.3) (end -1.3 1.3)
      (stroke (width 0.05) (type solid)) (fill none) (layer "F.CrtYd"))
    (fp_line (start -0.1 -1.1) (end -0.68 -0.52)
      (stroke (width 0.15) (type solid)) (layer "F.Fab"))
    (fp_rect (start 0.68 1.1) (end -0.68 -1.1)
      (stroke (width 0.15) (type solid)) (fill none) (layer "F.Fab"))
    (pad "1" smd custom (at -0.948 -0.752) (size 0.6 0.6) (layers "F.Cu" "F.Paste" "F.Mask")
      (options (clearance outline) (anchor rect))
      (primitives
      ))
    (pad "2" smd rect (at -0.948 -0.002) (size 0.4 0.6) (layers "F.Cu" "F.Paste" "F.Mask")
      (net 141 "Net-(Q3-REF)") (pinfunction "REF") (pintype "input"))
    (pad "3" smd custom (at -0.948 0.745) (size 0.6 0.6) (layers "F.Cu" "F.Paste" "F.Mask")
      (net 142 "Net-(Q3-BIAS)") (pinfunction "BIAS") (pintype "output")
      (options (clearance outline) (anchor rect))
      (primitives
      ))
    (pad "4" smd custom (at 0.951 0.745) (size 0.6 0.6) (layers "F.Cu" "F.Paste" "F.Mask")
      (net 143 "Net-(Q3-S)") (pinfunction "S") (pintype "power_in")
      (options (clearance outline) (anchor rect))
      (primitives
      ))
    (pad "5" smd rect (at 0.951 -0.002) (size 0.4 0.6) (layers "F.Cu" "F.Paste" "F.Mask"))
    (pad "6" smd custom (at 0.951 -0.752) (size 0.6 0.6) (layers "F.Cu" "F.Paste" "F.Mask")
      (net 61 "12V0_MOLEX") (pinfunction "D") (pintype "power_in")
      (options (clearance outline) (anchor rect))
      (primitives
      ))
  )

  (footprint "antmicro-footprints:C_0402_1005Metric" (layer "B.Cu")
    (at 144.15 76.432 90)
    (descr "Capacitor SMD 0402")
    (tags "capacitor SMD 0402")
    (property "Author" "Antmicro")
    (property "Dielectric" "")
    (property "License" "Apache-2.0")
    (property "MPN" "CC0402MRX5R5BB106")
    (property "Manufacturer" "YAGEO")
    (property "Sheetfile" "tb-power.kicad_sch")
    (property "Sheetname" "Thunderbolt Controller - Power")
    (property "Val" "10u")
    (property "Voltage" "")
    (property "ki_description" "SMD Multilayer Ceramic Capacitor, 10 µF, 6.3 V, 0402 [1005 Metric], ± 20%, X5R, CC Series")
    (property "ki_keywords" "0402, SMT, CAPACITOR, PASSIVE, MLCC, CERAMIC")
    (attr smd)
    (fp_text reference "C83" (at 5.439 1.519 270) (layer "B.SilkS")
        (effects (font (size 0.7 0.7) (thickness 0.15)) (justify left bottom mirror))
    )
    (fp_text value "C_10u_0402" (at -1.022927 -2.155213 270) (layer "B.Fab")
        (effects (font (size 0.7 0.7) (thickness 0.15)) (justify left bottom mirror))
    )
    (fp_text user "License: Apache-2.0" (at -0.939 -5.799 270) (layer "B.Fab") hide
        (effects (font (size 0.7 0.7) (thickness 0.15)) (justify left bottom mirror))
    )
    (fp_text user "Author: Antmicro" (at -0.939 -3.399 270) (layer "B.Fab") hide
        (effects (font (size 0.7 0.7) (thickness 0.15)) (justify left bottom mirror))
    )
    (fp_text user "${REFERENCE}" (at -0.939 -4.599 270) (layer "B.Fab") hide
        (effects (font (size 0.7 0.7) (thickness 0.15)) (justify left bottom mirror))
    )
    (fp_rect (start -0.925 0.47) (end 0.925 -0.47)
      (stroke (width 0.05) (type default)) (fill none) (layer "B.CrtYd"))
    (fp_line (start -0.494 -0.248) (end -0.494 0.25)
      (stroke (width 0.15) (type solid)) (layer "B.Fab"))
    (fp_line (start -0.494 0.25) (end 0.504 0.25)
      (stroke (width 0.15) (type solid)) (layer "B.Fab"))
    (fp_line (start 0.504 -0.248) (end -0.494 -0.248)
      (stroke (width 0.15) (type solid)) (layer "B.Fab"))
    (fp_line (start 0.504 0.25) (end 0.504 -0.248)
      (stroke (width 0.15) (type solid)) (layer "B.Fab"))
    (pad "1" smd roundrect (at -0.48 0 90) (size 0.59 0.64) (layers "B.Cu" "B.Paste" "B.Mask") (roundrect_rratio 0.25)
      (net 1 "GND") (pintype "passive"))
    (pad "2" smd roundrect (at 0.48 0 90) (size 0.59 0.64) (layers "B.Cu" "B.Paste" "B.Mask") (roundrect_rratio 0.25)
      (net 2 "3V3_SYS") (pintype "passive"))
  )

  (footprint "antmicro-footprints:R_0402_1005Metric" (layer "B.Cu")
    (at 107.85 91.765 -90)
    (descr "Resistor SMD 0402")
    (tags "resistor SMD 0402")
    (property "Author" "Antmicro")
    (property "License" "Apache-2.0")
    (property "MPN" "CR0402-FX-1003GLF")
    (property "Manufacturer" "Bourns")
    (property "Sheetfile" "power.kicad_sch")
    (property "Sheetname" "Power")
    (property "Tolerance" "1%")
    (property "Val" "100k")
    (property "ki_description" "SMD Chip Resistor, 100 kohm, ± 1%, 62.5 mW, 0402 [1005 Metric], Thick Film, General Purpose")
    (property "ki_keywords" "0402, SMT, RESISTOR, PASSIVE")
    (attr smd)
    (fp_text reference "R95" (at -1.087 -1.497 90) (layer "B.SilkS")
        (effects (font (size 0.7 0.7) (thickness 0.15)) (justify left bottom mirror))
    )
    (fp_text value "R_100k_0402" (at -1.011843 -1.772047 90) (layer "B.Fab")
        (effects (font (size 0.7 0.7) (thickness 0.15)) (justify left bottom mirror))
    )
    (fp_text user "${REFERENCE}" (at -0.95 -3.168 90) (layer "B.Fab") hide
        (effects (font (size 0.7 0.7) (thickness 0.15)) (justify left bottom mirror))
    )
    (fp_text user "License: Apache-2.0" (at -0.95 -5.169 90) (layer "B.Fab") hide
        (effects (font (size 0.7 0.7) (thickness 0.15)) (justify left bottom mirror))
    )
    (fp_text user "Author: Antmicro" (at -0.95 -4.169 90) (layer "B.Fab") hide
        (effects (font (size 0.7 0.7) (thickness 0.15)) (justify left bottom mirror))
    )
    (fp_rect (start -0.925 0.47) (end 0.925 -0.47)
      (stroke (width 0.05) (type default)) (fill none) (layer "B.CrtYd"))
    (fp_rect (start -0.5 0.25) (end 0.5 -0.25)
      (stroke (width 0.15) (type solid)) (fill none) (layer "B.Fab"))
    (pad "1" smd roundrect (at -0.48 0 270) (size 0.59 0.64) (layers "B.Cu" "B.Paste" "B.Mask") (roundrect_rratio 0.25)
      (net 1 "GND") (pintype "passive"))
    (pad "2" smd roundrect (at 0.48 0 270) (size 0.59 0.64) (layers "B.Cu" "B.Paste" "B.Mask") (roundrect_rratio 0.25)
      (net 142 "Net-(Q3-BIAS)") (pintype "passive"))
  )

  (footprint "antmicro-footprints:R_0402_1005Metric" (layer "B.Cu")
    (at 138.25 70.72 90)
    (descr "Resistor SMD 0402")
    (tags "resistor SMD 0402")
    (property "Author" "Antmicro")
    (property "License" "Apache-2.0")
    (property "MPN" "CR0402-FX-1003GLF")
    (property "Manufacturer" "Bourns")
    (property "Sheetfile" "tb.kicad_sch")
    (property "Sheetname" "TB Controller")
    (property "Tolerance" "1%")
    (property "Val" "100k")
    (property "ki_description" "SMD Chip Resistor, 100 kohm, ± 1%, 62.5 mW, 0402 [1005 Metric], Thick Film, General Purpose")
    (property "ki_keywords" "0402, SMT, RESISTOR, PASSIVE")
    (attr smd)
    (fp_text reference "R86" (at -1.035 0.434 270) (layer "B.SilkS")
        (effects (font (size 0.7 0.7) (thickness 0.15)) (justify left bottom mirror))
    )
    (fp_text value "R_100k_0402" (at -1.011843 -1.772047 270) (layer "B.Fab")
        (effects (font (size 0.7 0.7) (thickness 0.15)) (justify left bottom mirror))
    )
    (fp_text user "Author: Antmicro" (at -0.95 -4.169 270) (layer "B.Fab") hide
        (effects (font (size 0.7 0.7) (thickness 0.15)) (justify left bottom mirror))
    )
    (fp_text user "${REFERENCE}" (at -0.95 -3.168 270) (layer "B.Fab") hide
        (effects (font (size 0.7 0.7) (thickness 0.15)) (justify left bottom mirror))
    )
    (fp_text user "License: Apache-2.0" (at -0.95 -5.169 270) (layer "B.Fab") hide
        (effects (font (size 0.7 0.7) (thickness 0.15)) (justify left bottom mirror))
    )
    (fp_rect (start -0.925 0.47) (end 0.925 -0.47)
      (stroke (width 0.05) (type default)) (fill none) (layer "B.CrtYd"))
    (fp_rect (start -0.5 0.25) (end 0.5 -0.25)
      (stroke (width 0.15) (type solid)) (fill none) (layer "B.Fab"))
    (pad "1" smd roundrect (at -0.48 0 90) (size 0.59 0.64) (layers "B.Cu" "B.Paste" "B.Mask") (roundrect_rratio 0.25)
      (net 201 "Net-(U4C-POC_GPIO_5)") (pintype "passive"))
    (pad "2" smd roundrect (at 0.48 0 90) (size 0.59 0.64) (layers "B.Cu" "B.Paste" "B.Mask") (roundrect_rratio 0.25)
      (net 1 "GND") (pintype "passive"))
  )

  (footprint "antmicro-footprints:R_0402_1005Metric" (layer "B.Cu")
    (at 106.9455 89.2 180)
    (descr "Resistor SMD 0402")
    (tags "resistor SMD 0402")
    (property "Author" "Antmicro")
    (property "License" "Apache-2.0")
    (property "MPN" "CR0402-FX-2201GLF")
    (property "Manufacturer" "Bourns")
    (property "Sheetfile" "power.kicad_sch")
    (property "Sheetname" "Power")
    (property "Tolerance" "1%")
    (property "Val" "2k2")
    (property "ki_description" "SMD Chip Resistor, 2.2 kohm, ± 1%, 62.5 mW, 0402 [1005 Metric], Thick Film, General Purpose")
    (property "ki_keywords" "0402, SMT, RESISTOR, PASSIVE")
    (attr smd)
    (fp_text reference "R97" (at -1.122484 0.772697) (layer "B.SilkS")
        (effects (font (size 0.7 0.7) (thickness 0.15)) (justify left bottom mirror))
    )
    (fp_text value "R_2k2_0402" (at -1.011843 -1.772047) (layer "B.Fab")
        (effects (font (size 0.7 0.7) (thickness 0.15)) (justify left bottom mirror))
    )
    (fp_text user "Author: Antmicro" (at -0.95 -4.169) (layer "B.Fab") hide
        (effects (font (size 0.7 0.7) (thickness 0.15)) (justify left bottom mirror))
    )
    (fp_text user "${REFERENCE}" (at -0.95 -3.168) (layer "B.Fab") hide
        (effects (font (size 0.7 0.7) (thickness 0.15)) (justify left bottom mirror))
    )
    (fp_text user "License: Apache-2.0" (at -0.95 -5.169) (layer "B.Fab") hide
        (effects (font (size 0.7 0.7) (thickness 0.15)) (justify left bottom mirror))
    )
    (fp_rect (start -0.925 0.47) (end 0.925 -0.47)
      (stroke (width 0.05) (type default)) (fill none) (layer "B.CrtYd"))
    (fp_rect (start -0.5 0.25) (end 0.5 -0.25)
      (stroke (width 0.15) (type solid)) (fill none) (layer "B.Fab"))
    (pad "1" smd roundrect (at -0.48 0 180) (size 0.59 0.64) (layers "B.Cu" "B.Paste" "B.Mask") (roundrect_rratio 0.25)
      (net 1 "GND") (pintype "passive"))
    (pad "2" smd roundrect (at 0.48 0 180) (size 0.59 0.64) (layers "B.Cu" "B.Paste" "B.Mask") (roundrect_rratio 0.25)
      (net 123 "Net-(D5-C)") (pintype "passive"))
  )

  (footprint "antmicro-footprints:R_0402_1005Metric" (layer "B.Cu")
    (at 151.41 63.97 180)
    (descr "Resistor SMD 0402")
    (tags "resistor SMD 0402")
    (property "Author" "Antmicro")
    (property "License" "Apache-2.0")
    (property "MPN" "CR0402-FX-1003GLF")
    (property "Manufacturer" "Bourns")
    (property "Sheetfile" "power.kicad_sch")
    (property "Sheetname" "Power")
    (property "Tolerance" "1%")
    (property "Val" "100k")
    (property "ki_description" "SMD Chip Resistor, 100 kohm, ± 1%, 62.5 mW, 0402 [1005 Metric], Thick Film, General Purpose")
    (property "ki_keywords" "0402, SMT, RESISTOR, PASSIVE")
    (attr smd)
    (fp_text reference "R9" (at 0.961516 -0.382303) (layer "B.SilkS")
        (effects (font (size 0.7 0.7) (thickness 0.15)) (justify left bottom mirror))
    )
    (fp_text value "R_100k_0402" (at -1.011843 -1.772047) (layer "B.Fab")
        (effects (font (size 0.7 0.7) (thickness 0.15)) (justify left bottom mirror))
    )
    (fp_text user "License: Apache-2.0" (at -0.95 -5.169) (layer "B.Fab") hide
        (effects (font (size 0.7 0.7) (thickness 0.15)) (justify left bottom mirror))
    )
    (fp_text user "Author: Antmicro" (at -0.95 -4.169) (layer "B.Fab") hide
        (effects (font (size 0.7 0.7) (thickness 0.15)) (justify left bottom mirror))
    )
    (fp_text user "${REFERENCE}" (at -0.95 -3.168) (layer "B.Fab") hide
        (effects (font (size 0.7 0.7) (thickness 0.15)) (justify left bottom mirror))
    )
    (fp_rect (start -0.925 0.47) (end 0.925 -0.47)
      (stroke (width 0.05) (type default)) (fill none) (layer "B.CrtYd"))
    (fp_rect (start -0.5 0.25) (end 0.5 -0.25)
      (stroke (width 0.15) (type solid)) (fill none) (layer "B.Fab"))
    (pad "1" smd roundrect (at -0.48 0 180) (size 0.59 0.64) (layers "B.Cu" "B.Paste" "B.Mask") (roundrect_rratio 0.25)
      (net 1 "GND") (pintype "passive"))
    (pad "2" smd roundrect (at 0.48 0 180) (size 0.59 0.64) (layers "B.Cu" "B.Paste" "B.Mask") (roundrect_rratio 0.25)
      (net 16 "AUX_P") (pintype "passive"))
  )

  (footprint "antmicro-footprints:R_0402_1005Metric" (layer "B.Cu")
    (at 130.7 83.12)
    (descr "Resistor SMD 0402")
    (tags "resistor SMD 0402")
    (property "Author" "Antmicro")
    (property "License" "Apache-2.0")
    (property "MPN" "CR0402-FX-1402GLF")
    (property "Manufacturer" "Bourns")
    (property "Sheetfile" "tb.kicad_sch")
    (property "Sheetname" "TB Controller")
    (property "Tolerance" "1%")
    (property "Val" "14k")
    (property "dnp" "")
    (property "ki_description" "SMD Chip Resistor, 14 kohm, ± 1%, 100 mW, 0402 [1005 Metric], Thick Film, Precision")
    (property "ki_keywords" "0402, SMT, RESISTOR, PASSIVE")
    (attr smd)
    (fp_text reference "R63" (at 17.509 7.431 180) (layer "B.SilkS")
        (effects (font (size 0.7 0.7) (thickness 0.15)) (justify left bottom mirror))
    )
    (fp_text value "R_14k_0402" (at -1.011843 -1.772047 180) (layer "B.Fab")
        (effects (font (size 0.7 0.7) (thickness 0.15)) (justify left bottom mirror))
    )
    (fp_text user "Author: Antmicro" (at -0.95 -4.169 180) (layer "B.Fab") hide
        (effects (font (size 0.7 0.7) (thickness 0.15)) (justify left bottom mirror))
    )
    (fp_text user "${REFERENCE}" (at -0.95 -3.168 180) (layer "B.Fab") hide
        (effects (font (size 0.7 0.7) (thickness 0.15)) (justify left bottom mirror))
    )
    (fp_text user "License: Apache-2.0" (at -0.95 -5.169 180) (layer "B.Fab") hide
        (effects (font (size 0.7 0.7) (thickness 0.15)) (justify left bottom mirror))
    )
    (fp_rect (start -0.925 0.47) (end 0.925 -0.47)
      (stroke (width 0.05) (type default)) (fill none) (layer "B.CrtYd"))
    (fp_rect (start -0.5 0.25) (end 0.5 -0.25)
      (stroke (width 0.15) (type solid)) (fill none) (layer "B.Fab"))
    (pad "1" smd roundrect (at -0.48 0) (size 0.59 0.64) (layers "B.Cu" "B.Paste" "B.Mask") (roundrect_rratio 0.25)
      (net 1 "GND") (pintype "passive"))
    (pad "2" smd roundrect (at 0.48 0) (size 0.59 0.64) (layers "B.Cu" "B.Paste" "B.Mask") (roundrect_rratio 0.25)
      (net 177 "Net-(U4C-DPSNK_RBIAS)") (pintype "passive"))
  )

  (footprint "antmicro-footprints:C_0402_1005Metric" (layer "B.Cu")
    (at 161 76.928922)
    (descr "Capacitor SMD 0402")
    (tags "capacitor SMD 0402")
    (property "Author" "Antmicro")
    (property "Dielectric" "X5R")
    (property "License" "Apache-2.0")
    (property "MPN" "GRM155R61H104KE14D")
    (property "Manufacturer" "Murata")
    (property "Sheetfile" "connectors.kicad_sch")
    (property "Sheetname" "Connectors")
    (property "Val" "100n")
    (property "Voltage" "50V")
    (property "ki_description" "SMD Multilayer Ceramic Capacitor, 0.1 µF, 50 V, 0402 [1005 Metric], ± 10%, X5R, GRM Series")
    (property "ki_keywords" "0402, SMT, CAPACITOR, PASSIVE, CERAMIC, MLCC")
    (attr smd)
    (fp_text reference "C3" (at -0.98 0.509078 180) (layer "B.SilkS")
        (effects (font (size 0.7 0.7) (thickness 0.15)) (justify left bottom mirror))
    )
    (fp_text value "C_100n_0402" (at -1.022927 -2.155213 180) (layer "B.Fab")
        (effects (font (size 0.7 0.7) (thickness 0.15)) (justify left bottom mirror))
    )
    (fp_text user "${REFERENCE}" (at -0.939 -4.599 180) (layer "B.Fab") hide
        (effects (font (size 0.7 0.7) (thickness 0.15)) (justify left bottom mirror))
    )
    (fp_text user "Author: Antmicro" (at -0.939 -3.399 180) (layer "B.Fab") hide
        (effects (font (size 0.7 0.7) (thickness 0.15)) (justify left bottom mirror))
    )
    (fp_text user "License: Apache-2.0" (at -0.939 -5.799 180) (layer "B.Fab") hide
        (effects (font (size 0.7 0.7) (thickness 0.15)) (justify left bottom mirror))
    )
    (fp_rect (start -0.925 0.47) (end 0.925 -0.47)
      (stroke (width 0.05) (type default)) (fill none) (layer "B.CrtYd"))
    (fp_line (start -0.494 -0.248) (end -0.494 0.25)
      (stroke (width 0.15) (type solid)) (layer "B.Fab"))
    (fp_line (start -0.494 0.25) (end 0.504 0.25)
      (stroke (width 0.15) (type solid)) (layer "B.Fab"))
    (fp_line (start 0.504 -0.248) (end -0.494 -0.248)
      (stroke (width 0.15) (type solid)) (layer "B.Fab"))
    (fp_line (start 0.504 0.25) (end 0.504 -0.248)
      (stroke (width 0.15) (type solid)) (layer "B.Fab"))
    (pad "1" smd roundrect (at -0.48 0) (size 0.59 0.64) (layers "B.Cu" "B.Paste" "B.Mask") (roundrect_rratio 0.25)
      (net 1 "GND") (pintype "passive"))
    (pad "2" smd roundrect (at 0.48 0) (size 0.59 0.64) (layers "B.Cu" "B.Paste" "B.Mask") (roundrect_rratio 0.25)
      (net 3 "5V0_USB") (pintype "passive"))
  )

  (footprint "antmicro-footprints:C_0402_1005Metric" (layer "B.Cu")
    (at 144.30859 90.885531 -135)
    (descr "Capacitor SMD 0402")
    (tags "capacitor SMD 0402")
    (property "Author" "Antmicro")
    (property "Dielectric" "C0G")
    (property "License" "Apache-2.0")
    (property "MPN" "GCM1555C1H100GA16D")
    (property "Manufacturer" "Murata")
    (property "Sheetfile" "tb.kicad_sch")
    (property "Sheetname" "TB Controller")
    (property "Val" "10p")
    (property "Voltage" "50V")
    (property "ki_description" "SMD Multilayer Ceramic Capacitor, 10 pF, 50 V, 0402 [1005 Metric], ± 2%, C0G / NP0, GCM")
    (property "ki_keywords" "0402, SMT, CAPACITOR, PASSIVE")
    (attr smd)
    (fp_text reference "C116" (at -1.018899 -1.443826 45) (layer "B.SilkS")
        (effects (font (size 0.7 0.7) (thickness 0.15)) (justify left bottom mirror))
    )
    (fp_text value "C_10p_0402" (at -1.022927 -2.155213 45) (layer "B.Fab")
        (effects (font (size 0.7 0.7) (thickness 0.15)) (justify left bottom mirror))
    )
    (fp_text user "${REFERENCE}" (at -0.939 -4.599 45) (layer "B.Fab") hide
        (effects (font (size 0.7 0.7) (thickness 0.15)) (justify left bottom mirror))
    )
    (fp_text user "Author: Antmicro" (at -0.939 -3.399 45) (layer "B.Fab") hide
        (effects (font (size 0.7 0.7) (thickness 0.15)) (justify left bottom mirror))
    )
    (fp_text user "License: Apache-2.0" (at -0.939 -5.799 45) (layer "B.Fab") hide
        (effects (font (size 0.7 0.7) (thickness 0.15)) (justify left bottom mirror))
    )
    (fp_rect (start -0.925 0.47) (end 0.925 -0.47)
      (stroke (width 0.05) (type default)) (fill none) (layer "B.CrtYd"))
    (fp_line (start -0.494 -0.248) (end -0.494 0.25)
      (stroke (width 0.15) (type solid)) (layer "B.Fab"))
    (fp_line (start -0.494 0.25) (end 0.504 0.25)
      (stroke (width 0.15) (type solid)) (layer "B.Fab"))
    (fp_line (start 0.504 -0.248) (end -0.494 -0.248)
      (stroke (width 0.15) (type solid)) (layer "B.Fab"))
    (fp_line (start 0.504 0.25) (end 0.504 -0.248)
      (stroke (width 0.15) (type solid)) (layer "B.Fab"))
    (pad "1" smd roundrect (at -0.48 0 225) (size 0.59 0.64) (layers "B.Cu" "B.Paste" "B.Mask") (roundrect_rratio 0.25)
      (net 117 "Net-(U4D-XTAL_25_IN)") (pintype "passive"))
    (pad "2" smd roundrect (at 0.48 0 225) (size 0.59 0.64) (layers "B.Cu" "B.Paste" "B.Mask") (roundrect_rratio 0.25)
      (net 1 "GND") (pintype "passive"))
  )

  (footprint "antmicro-footprints:C_0402_1005Metric" (layer "B.Cu")
    (at 134.925 81.8 180)
    (descr "Capacitor SMD 0402")
    (tags "capacitor SMD 0402")
    (property "Author" "Antmicro")
    (property "Dielectric" "")
    (property "License" "Apache-2.0")
    (property "MPN" "C1005X6S1A105K050BC")
    (property "Manufacturer" "TDK")
    (property "Sheetfile" "tb-power.kicad_sch")
    (property "Sheetname" "Thunderbolt Controller - Power")
    (property "Val" "1u")
    (property "Voltage" "")
    (property "ki_description" "SMD Multilayer Ceramic Capacitor, 1 µF, 10 V, 0402 [1005 Metric], ± 10%, X6S, C")
    (property "ki_keywords" "0402, SMT, CAPACITOR, PASSIVE, CERAMIC, MLCC")
    (attr smd)
    (fp_text reference "C59" (at -17.475 -7.735) (layer "B.SilkS")
        (effects (font (size 0.7 0.7) (thickness 0.15)) (justify left bottom mirror))
    )
    (fp_text value "C_1u_0402" (at -1.022927 -2.155213) (layer "B.Fab")
        (effects (font (size 0.7 0.7) (thickness 0.15)) (justify left bottom mirror))
    )
    (fp_text user "Author: Antmicro" (at -0.939 -3.399) (layer "B.Fab") hide
        (effects (font (size 0.7 0.7) (thickness 0.15)) (justify left bottom mirror))
    )
    (fp_text user "License: Apache-2.0" (at -0.939 -5.799) (layer "B.Fab") hide
        (effects (font (size 0.7 0.7) (thickness 0.15)) (justify left bottom mirror))
    )
    (fp_text user "${REFERENCE}" (at -0.939 -4.599) (layer "B.Fab") hide
        (effects (font (size 0.7 0.7) (thickness 0.15)) (justify left bottom mirror))
    )
    (fp_rect (start -0.925 0.47) (end 0.925 -0.47)
      (stroke (width 0.05) (type default)) (fill none) (layer "B.CrtYd"))
    (fp_line (start -0.494 -0.248) (end -0.494 0.25)
      (stroke (width 0.15) (type solid)) (layer "B.Fab"))
    (fp_line (start -0.494 0.25) (end 0.504 0.25)
      (stroke (width 0.15) (type solid)) (layer "B.Fab"))
    (fp_line (start 0.504 -0.248) (end -0.494 -0.248)
      (stroke (width 0.15) (type solid)) (layer "B.Fab"))
    (fp_line (start 0.504 0.25) (end 0.504 -0.248)
      (stroke (width 0.15) (type solid)) (layer "B.Fab"))
    (pad "1" smd roundrect (at -0.48 0 180) (size 0.59 0.64) (layers "B.Cu" "B.Paste" "B.Mask") (roundrect_rratio 0.25)
      (net 1 "GND") (pintype "passive"))
    (pad "2" smd roundrect (at 0.48 0 180) (size 0.59 0.64) (layers "B.Cu" "B.Paste" "B.Mask") (roundrect_rratio 0.25)
      (net 108 "Net-(C56-Pad2)") (pintype "passive"))
  )

  (footprint "antmicro-footprints:C_0402_1005Metric" (layer "B.Cu")
    (at 135.115 59.1 180)
    (descr "Capacitor SMD 0402")
    (tags "capacitor SMD 0402")
    (property "Author" "Antmicro")
    (property "Dielectric" "X5R")
    (property "License" "Apache-2.0")
    (property "MPN" "GRM155R61H104KE14D")
    (property "Manufacturer" "Murata")
    (property "Sheetfile" "tb.kicad_sch")
    (property "Sheetname" "TB Controller")
    (property "Val" "100n")
    (property "Voltage" "50V")
    (property "ki_description" "SMD Multilayer Ceramic Capacitor, 0.1 µF, 50 V, 0402 [1005 Metric], ± 10%, X5R, GRM Series")
    (property "ki_keywords" "0402, SMT, CAPACITOR, PASSIVE, CERAMIC, MLCC")
    (attr smd)
    (fp_text reference "C104" (at 1.003 -0.463) (layer "B.SilkS")
        (effects (font (size 0.7 0.7) (thickness 0.15)) (justify left bottom mirror))
    )
    (fp_text value "C_100n_0402" (at -1.022927 -2.155213) (layer "B.Fab")
        (effects (font (size 0.7 0.7) (thickness 0.15)) (justify left bottom mirror))
    )
    (fp_text user "${REFERENCE}" (at -0.939 -4.599) (layer "B.Fab") hide
        (effects (font (size 0.7 0.7) (thickness 0.15)) (justify left bottom mirror))
    )
    (fp_text user "License: Apache-2.0" (at -0.939 -5.799) (layer "B.Fab") hide
        (effects (font (size 0.7 0.7) (thickness 0.15)) (justify left bottom mirror))
    )
    (fp_text user "Author: Antmicro" (at -0.939 -3.399) (layer "B.Fab") hide
        (effects (font (size 0.7 0.7) (thickness 0.15)) (justify left bottom mirror))
    )
    (fp_rect (start -0.925 0.47) (end 0.925 -0.47)
      (stroke (width 0.05) (type default)) (fill none) (layer "B.CrtYd"))
    (fp_line (start -0.494 -0.248) (end -0.494 0.25)
      (stroke (width 0.15) (type solid)) (layer "B.Fab"))
    (fp_line (start -0.494 0.25) (end 0.504 0.25)
      (stroke (width 0.15) (type solid)) (layer "B.Fab"))
    (fp_line (start 0.504 -0.248) (end -0.494 -0.248)
      (stroke (width 0.15) (type solid)) (layer "B.Fab"))
    (fp_line (start 0.504 0.25) (end 0.504 -0.248)
      (stroke (width 0.15) (type solid)) (layer "B.Fab"))
    (pad "1" smd roundrect (at -0.48 0 180) (size 0.59 0.64) (layers "B.Cu" "B.Paste" "B.Mask") (roundrect_rratio 0.25)
      (net 23 "AUX_N") (pintype "passive"))
    (pad "2" smd roundrect (at 0.48 0 180) (size 0.59 0.64) (layers "B.Cu" "B.Paste" "B.Mask") (roundrect_rratio 0.25)
      (net 87 "/TB Controller/PA_AUX_N") (pintype "passive"))
  )

  (footprint "antmicro-footprints:R_0402_1005Metric" (layer "B.Cu")
    (at 114.145 86.17 -90)
    (descr "Resistor SMD 0402")
    (tags "resistor SMD 0402")
    (property "Author" "Antmicro")
    (property "License" "Apache-2.0")
    (property "MPN" "CR0402-FX-1103GLF")
    (property "Manufacturer" "Bourns")
    (property "Sheetfile" "power.kicad_sch")
    (property "Sheetname" "Power")
    (property "Tolerance" "1%")
    (property "Val" "110k")
    (property "ki_description" "SMD Chip Resistor, 110 kohm, ± 1%, 63 mW, 0402 [1005 Metric], Thick Film, General Purpose")
    (property "ki_keywords" "0402, SMT, RESISTOR, PASSIVE")
    (attr smd)
    (fp_text reference "R43" (at 0.825 -0.409 90) (layer "B.SilkS")
        (effects (font (size 0.7 0.7) (thickness 0.15)) (justify left bottom mirror))
    )
    (fp_text value "R_110k_0402" (at -1.011843 -1.772047 90) (layer "B.Fab")
        (effects (font (size 0.7 0.7) (thickness 0.15)) (justify left bottom mirror))
    )
    (fp_text user "License: Apache-2.0" (at -0.95 -5.169 90) (layer "B.Fab") hide
        (effects (font (size 0.7 0.7) (thickness 0.15)) (justify left bottom mirror))
    )
    (fp_text user "Author: Antmicro" (at -0.95 -4.169 90) (layer "B.Fab") hide
        (effects (font (size 0.7 0.7) (thickness 0.15)) (justify left bottom mirror))
    )
    (fp_text user "${REFERENCE}" (at -0.95 -3.168 90) (layer "B.Fab") hide
        (effects (font (size 0.7 0.7) (thickness 0.15)) (justify left bottom mirror))
    )
    (fp_rect (start -0.925 0.47) (end 0.925 -0.47)
      (stroke (width 0.05) (type default)) (fill none) (layer "B.CrtYd"))
    (fp_rect (start -0.5 0.25) (end 0.5 -0.25)
      (stroke (width 0.15) (type solid)) (fill none) (layer "B.Fab"))
    (pad "1" smd roundrect (at -0.48 0 270) (size 0.59 0.64) (layers "B.Cu" "B.Paste" "B.Mask") (roundrect_rratio 0.25)
      (net 169 "Net-(U1-FB)") (pintype "passive"))
    (pad "2" smd roundrect (at 0.48 0 270) (size 0.59 0.64) (layers "B.Cu" "B.Paste" "B.Mask") (roundrect_rratio 0.25)
      (net 75 "Net-(C32-Pad2)") (pintype "passive"))
  )

  (footprint "antmicro-footprints:R_0402_1005Metric" (layer "B.Cu")
    (at 152.91 60.47 90)
    (descr "Resistor SMD 0402")
    (tags "resistor SMD 0402")
    (property "Author" "Antmicro")
    (property "License" "Apache-2.0")
    (property "MPN" "CR0402-FX-1002GLF")
    (property "Manufacturer" "Bourns")
    (property "Sheetfile" "power.kicad_sch")
    (property "Sheetname" "Power")
    (property "Tolerance" "1%")
    (property "Val" "10k")
    (property "ki_description" "SMD Chip Resistor, 10 kohm, ± 1%, 62.5 mW, 0402 [1005 Metric], Thick Film, General Purpose")
    (property "ki_keywords" "0402, SMT, RESISTOR, PASSIVE")
    (attr smd)
    (fp_text reference "R17" (at 3.193 0.379 270) (layer "B.SilkS")
        (effects (font (size 0.7 0.7) (thickness 0.15)) (justify left bottom mirror))
    )
    (fp_text value "R_10k_0402" (at -1.011843 -1.772047 270) (layer "B.Fab")
        (effects (font (size 0.7 0.7) (thickness 0.15)) (justify left bottom mirror))
    )
    (fp_text user "Author: Antmicro" (at -0.95 -4.169 270) (layer "B.Fab") hide
        (effects (font (size 0.7 0.7) (thickness 0.15)) (justify left bottom mirror))
    )
    (fp_text user "License: Apache-2.0" (at -0.95 -5.169 270) (layer "B.Fab") hide
        (effects (font (size 0.7 0.7) (thickness 0.15)) (justify left bottom mirror))
    )
    (fp_text user "${REFERENCE}" (at -0.95 -3.168 270) (layer "B.Fab") hide
        (effects (font (size 0.7 0.7) (thickness 0.15)) (justify left bottom mirror))
    )
    (fp_rect (start -0.925 0.47) (end 0.925 -0.47)
      (stroke (width 0.05) (type default)) (fill none) (layer "B.CrtYd"))
    (fp_rect (start -0.5 0.25) (end 0.5 -0.25)
      (stroke (width 0.15) (type solid)) (fill none) (layer "B.Fab"))
    (pad "1" smd roundrect (at -0.48 0 90) (size 0.59 0.64) (layers "B.Cu" "B.Paste" "B.Mask") (roundrect_rratio 0.25)
      (net 9 "/Power/TPS_3V3") (pintype "passive"))
    (pad "2" smd roundrect (at 0.48 0 90) (size 0.59 0.64) (layers "B.Cu" "B.Paste" "B.Mask") (roundrect_rratio 0.25)
      (net 152 "Net-(U3-GPIO0(HD3_AMSEL))") (pintype "passive"))
  )

  (footprint "antmicro-footprints:R_0402_1005Metric" (layer "B.Cu")
    (at 135.175 68.77 90)
    (descr "Resistor SMD 0402")
    (tags "resistor SMD 0402")
    (property "Author" "Antmicro")
    (property "License" "Apache-2.0")
    (property "MPN" "CR0402-FX-1003GLF")
    (property "Manufacturer" "Bourns")
    (property "Sheetfile" "tb.kicad_sch")
    (property "Sheetname" "TB Controller")
    (property "Tolerance" "1%")
    (property "Val" "100k")
    (property "ki_description" "SMD Chip Resistor, 100 kohm, ± 1%, 62.5 mW, 0402 [1005 Metric], Thick Film, General Purpose")
    (property "ki_keywords" "0402, SMT, RESISTOR, PASSIVE")
    (attr smd)
    (fp_text reference "R75" (at 1.124 3.736 270) (layer "B.SilkS")
        (effects (font (size 0.7 0.7) (thickness 0.15)) (justify left bottom mirror))
    )
    (fp_text value "R_100k_0402" (at -1.011843 -1.772047 270) (layer "B.Fab")
        (effects (font (size 0.7 0.7) (thickness 0.15)) (justify left bottom mirror))
    )
    (fp_text user "License: Apache-2.0" (at -0.95 -5.169 270) (layer "B.Fab") hide
        (effects (font (size 0.7 0.7) (thickness 0.15)) (justify left bottom mirror))
    )
    (fp_text user "${REFERENCE}" (at -0.95 -3.168 270) (layer "B.Fab") hide
        (effects (font (size 0.7 0.7) (thickness 0.15)) (justify left bottom mirror))
    )
    (fp_text user "Author: Antmicro" (at -0.95 -4.169 270) (layer "B.Fab") hide
        (effects (font (size 0.7 0.7) (thickness 0.15)) (justify left bottom mirror))
    )
    (fp_rect (start -0.925 0.47) (end 0.925 -0.47)
      (stroke (width 0.05) (type default)) (fill none) (layer "B.CrtYd"))
    (fp_rect (start -0.5 0.25) (end 0.5 -0.25)
      (stroke (width 0.15) (type solid)) (fill none) (layer "B.Fab"))
    (pad "1" smd roundrect (at -0.48 0 90) (size 0.59 0.64) (layers "B.Cu" "B.Paste" "B.Mask") (roundrect_rratio 0.25)
      (net 190 "Net-(U4C-DPSRC_HPD)") (pintype "passive"))
    (pad "2" smd roundrect (at 0.48 0 90) (size 0.59 0.64) (layers "B.Cu" "B.Paste" "B.Mask") (roundrect_rratio 0.25)
      (net 1 "GND") (pintype "passive"))
  )

  (footprint "antmicro-footprints:C_0402_1005Metric" (layer "B.Cu")
    (at 141.15 76.43 90)
    (descr "Capacitor SMD 0402")
    (tags "capacitor SMD 0402")
    (property "Author" "Antmicro")
    (property "Dielectric" "X5R")
    (property "License" "Apache-2.0")
    (property "MPN" "GRM155R61H104KE14D")
    (property "Manufacturer" "Murata")
    (property "Sheetfile" "tb-power.kicad_sch")
    (property "Sheetname" "Thunderbolt Controller - Power")
    (property "Val" "100n")
    (property "Voltage" "50V")
    (property "ki_description" "SMD Multilayer Ceramic Capacitor, 0.1 µF, 50 V, 0402 [1005 Metric], ± 10%, X5R, GRM Series")
    (property "ki_keywords" "0402, SMT, CAPACITOR, PASSIVE, CERAMIC, MLCC")
    (attr smd)
    (fp_text reference "C88" (at 5.437 1.471 270) (layer "B.SilkS")
        (effects (font (size 0.7 0.7) (thickness 0.15)) (justify left bottom mirror))
    )
    (fp_text value "C_100n_0402" (at -1.022927 -2.155213 270) (layer "B.Fab")
        (effects (font (size 0.7 0.7) (thickness 0.15)) (justify left bottom mirror))
    )
    (fp_text user "${REFERENCE}" (at -0.939 -4.599 270) (layer "B.Fab") hide
        (effects (font (size 0.7 0.7) (thickness 0.15)) (justify left bottom mirror))
    )
    (fp_text user "License: Apache-2.0" (at -0.939 -5.799 270) (layer "B.Fab") hide
        (effects (font (size 0.7 0.7) (thickness 0.15)) (justify left bottom mirror))
    )
    (fp_text user "Author: Antmicro" (at -0.939 -3.399 270) (layer "B.Fab") hide
        (effects (font (size 0.7 0.7) (thickness 0.15)) (justify left bottom mirror))
    )
    (fp_rect (start -0.925 0.47) (end 0.925 -0.47)
      (stroke (width 0.05) (type default)) (fill none) (layer "B.CrtYd"))
    (fp_line (start -0.494 -0.248) (end -0.494 0.25)
      (stroke (width 0.15) (type solid)) (layer "B.Fab"))
    (fp_line (start -0.494 0.25) (end 0.504 0.25)
      (stroke (width 0.15) (type solid)) (layer "B.Fab"))
    (fp_line (start 0.504 -0.248) (end -0.494 -0.248)
      (stroke (width 0.15) (type solid)) (layer "B.Fab"))
    (fp_line (start 0.504 0.25) (end 0.504 -0.248)
      (stroke (width 0.15) (type solid)) (layer "B.Fab"))
    (pad "1" smd roundrect (at -0.48 0 90) (size 0.59 0.64) (layers "B.Cu" "B.Paste" "B.Mask") (roundrect_rratio 0.25)
      (net 1 "GND") (pintype "passive"))
    (pad "2" smd roundrect (at 0.48 0 90) (size 0.59 0.64) (layers "B.Cu" "B.Paste" "B.Mask") (roundrect_rratio 0.25)
      (net 2 "3V3_SYS") (pintype "passive"))
  )

  (footprint "antmicro-footprints:R_0402_1005Metric" (layer "B.Cu")
    (at 126.25 62.75)
    (descr "Resistor SMD 0402")
    (tags "resistor SMD 0402")
    (property "Author" "Antmicro")
    (property "License" "Apache-2.0")
    (property "MPN" "CR0402-FX-3300GLF")
    (property "Manufacturer" "Bourns")
    (property "Sheetfile" "power.kicad_sch")
    (property "Sheetname" "Power")
    (property "Tolerance" "1%")
    (property "Val" "330R")
    (property "ki_description" "SMD Chip Resistor, 330 ohm, ± 1%, 62.5 mW, 0402 [1005 Metric], Thick Film, General Purpose")
    (property "ki_keywords" "0402, SMT, RESISTOR, PASSIVE")
    (attr smd)
    (fp_text reference "R42" (at 1.131 -0.647 180) (layer "B.SilkS")
        (effects (font (size 0.7 0.7) (thickness 0.15)) (justify left bottom mirror))
    )
    (fp_text value "R_330R_0402" (at -1.011843 -1.772047 180) (layer "B.Fab")
        (effects (font (size 0.7 0.7) (thickness 0.15)) (justify left bottom mirror))
    )
    (fp_text user "License: Apache-2.0" (at -0.95 -5.169 180) (layer "B.Fab") hide
        (effects (font (size 0.7 0.7) (thickness 0.15)) (justify left bottom mirror))
    )
    (fp_text user "${REFERENCE}" (at -0.95 -3.168 180) (layer "B.Fab") hide
        (effects (font (size 0.7 0.7) (thickness 0.15)) (justify left bottom mirror))
    )
    (fp_text user "Author: Antmicro" (at -0.95 -4.169 180) (layer "B.Fab") hide
        (effects (font (size 0.7 0.7) (thickness 0.15)) (justify left bottom mirror))
    )
    (fp_rect (start -0.925 0.47) (end 0.925 -0.47)
      (stroke (width 0.05) (type default)) (fill none) (layer "B.CrtYd"))
    (fp_rect (start -0.5 0.25) (end 0.5 -0.25)
      (stroke (width 0.15) (type solid)) (fill none) (layer "B.Fab"))
    (pad "1" smd roundrect (at -0.48 0) (size 0.59 0.64) (layers "B.Cu" "B.Paste" "B.Mask") (roundrect_rratio 0.25)
      (net 1 "GND") (pintype "passive"))
    (pad "2" smd roundrect (at 0.48 0) (size 0.59 0.64) (layers "B.Cu" "B.Paste" "B.Mask") (roundrect_rratio 0.25)
      (net 120 "Net-(D2-C)") (pintype "passive"))
  )

  (footprint "antmicro-footprints:C_0402_1005Metric" (layer "B.Cu")
    (at 108.915 80.65 180)
    (descr "Capacitor SMD 0402")
    (tags "capacitor SMD 0402")
    (property "Author" "Antmicro")
    (property "Dielectric" "X5R")
    (property "License" "Apache-2.0")
    (property "MPN" "GRM155R61H104KE14D")
    (property "Manufacturer" "Murata")
    (property "Sheetfile" "power.kicad_sch")
    (property "Sheetname" "Power")
    (property "Val" "100n")
    (property "Voltage" "50V")
    (property "ki_description" "SMD Multilayer Ceramic Capacitor, 0.1 µF, 50 V, 0402 [1005 Metric], ± 10%, X5R, GRM Series")
    (property "ki_keywords" "0402, SMT, CAPACITOR, PASSIVE, CERAMIC, MLCC")
    (attr smd)
    (fp_text reference "C14" (at -1.067 5.72) (layer "B.SilkS")
        (effects (font (size 0.7 0.7) (thickness 0.15)) (justify left bottom mirror))
    )
    (fp_text value "C_100n_0402" (at -1.022927 -2.155213) (layer "B.Fab")
        (effects (font (size 0.7 0.7) (thickness 0.15)) (justify left bottom mirror))
    )
    (fp_text user "${REFERENCE}" (at -0.939 -4.599) (layer "B.Fab") hide
        (effects (font (size 0.7 0.7) (thickness 0.15)) (justify left bottom mirror))
    )
    (fp_text user "License: Apache-2.0" (at -0.939 -5.799) (layer "B.Fab") hide
        (effects (font (size 0.7 0.7) (thickness 0.15)) (justify left bottom mirror))
    )
    (fp_text user "Author: Antmicro" (at -0.939 -3.399) (layer "B.Fab") hide
        (effects (font (size 0.7 0.7) (thickness 0.15)) (justify left bottom mirror))
    )
    (fp_rect (start -0.925 0.47) (end 0.925 -0.47)
      (stroke (width 0.05) (type default)) (fill none) (layer "B.CrtYd"))
    (fp_line (start -0.494 -0.248) (end -0.494 0.25)
      (stroke (width 0.15) (type solid)) (layer "B.Fab"))
    (fp_line (start -0.494 0.25) (end 0.504 0.25)
      (stroke (width 0.15) (type solid)) (layer "B.Fab"))
    (fp_line (start 0.504 -0.248) (end -0.494 -0.248)
      (stroke (width 0.15) (type solid)) (layer "B.Fab"))
    (fp_line (start 0.504 0.25) (end 0.504 -0.248)
      (stroke (width 0.15) (type solid)) (layer "B.Fab"))
    (pad "1" smd roundrect (at -0.48 0 180) (size 0.59 0.64) (layers "B.Cu" "B.Paste" "B.Mask") (roundrect_rratio 0.25)
      (net 1 "GND") (pintype "passive"))
    (pad "2" smd roundrect (at 0.48 0 180) (size 0.59 0.64) (layers "B.Cu" "B.Paste" "B.Mask") (roundrect_rratio 0.25)
      (net 74 "Net-(C10-Pad2)") (pintype "passive"))
  )

  (footprint "antmicro-footprints:R_0402_1005Metric" (layer "B.Cu")
    (at 108.915 84.68)
    (descr "Resistor SMD 0402")
    (tags "resistor SMD 0402")
    (property "Author" "Antmicro")
    (property "Current" "1A")
    (property "License" "Apache-2.0")
    (property "MPN" "ERJ2GE0R00X")
    (property "Manufacturer" "Panasonic")
    (property "Sheetfile" "power.kicad_sch")
    (property "Sheetname" "Power")
    (property "Tolerance" "")
    (property "Val" "0R")
    (property "ki_description" "SMD Chip Resistor, Jumper, 0 ohm, 100 mW, 0402 [1005 Metric], Thick Film, General Purpose")
    (property "ki_keywords" "0402, SMT, RESISTOR, PASSIVE")
    (attr smd)
    (fp_text reference "R27" (at -1.092 -5.686) (layer "B.SilkS")
        (effects (font (size 0.7 0.7) (thickness 0.15)) (justify right bottom mirror))
    )
    (fp_text value "R_0R_0402" (at -1.011843 -1.772047) (layer "B.Fab")
        (effects (font (size 0.7 0.7) (thickness 0.15)) (justify right bottom mirror))
    )
    (fp_text user "${REFERENCE}" (at -0.95 -3.168) (layer "B.Fab") hide
        (effects (font (size 0.7 0.7) (thickness 0.15)) (justify right bottom mirror))
    )
    (fp_text user "Author: Antmicro" (at -0.95 -4.169) (layer "B.Fab") hide
        (effects (font (size 0.7 0.7) (thickness 0.15)) (justify right bottom mirror))
    )
    (fp_text user "License: Apache-2.0" (at -0.95 -5.169) (layer "B.Fab") hide
        (effects (font (size 0.7 0.7) (thickness 0.15)) (justify right bottom mirror))
    )
    (fp_rect (start -0.925 0.47) (end 0.925 -0.47)
      (stroke (width 0.05) (type default)) (fill none) (layer "B.CrtYd"))
    (fp_rect (start -0.5 0.25) (end 0.5 -0.25)
      (stroke (width 0.15) (type solid)) (fill none) (layer "B.Fab"))
    (pad "1" smd roundrect (at -0.48 0) (size 0.59 0.64) (layers "B.Cu" "B.Paste" "B.Mask") (roundrect_rratio 0.25)
      (net 5 "Net-(U1-VREF)") (pintype "passive"))
    (pad "2" smd roundrect (at 0.48 0) (size 0.59 0.64) (layers "B.Cu" "B.Paste" "B.Mask") (roundrect_rratio 0.25)
      (net 159 "Net-(U1-SYNC{slash}MODE)") (pintype "passive"))
  )

  (footprint "antmicro-footprints:C_0402_1005Metric" (layer "B.Cu")
    (at 134.8 84.725)
    (descr "Capacitor SMD 0402")
    (tags "capacitor SMD 0402")
    (property "Author" "Antmicro")
    (property "Dielectric" "")
    (property "License" "Apache-2.0")
    (property "MPN" "C1005X6S1A105K050BC")
    (property "Manufacturer" "TDK")
    (property "Sheetfile" "tb-power.kicad_sch")
    (property "Sheetname" "Thunderbolt Controller - Power")
    (property "Val" "1u")
    (property "Voltage" "")
    (property "ki_description" "SMD Multilayer Ceramic Capacitor, 1 µF, 10 V, 0402 [1005 Metric], ± 10%, X6S, C")
    (property "ki_keywords" "0402, SMT, CAPACITOR, PASSIVE, CERAMIC, MLCC")
    (attr smd)
    (fp_text reference "C68" (at 17.6 7.649 180) (layer "B.SilkS")
        (effects (font (size 0.7 0.7) (thickness 0.15)) (justify left bottom mirror))
    )
    (fp_text value "C_1u_0402" (at -1.022927 -2.155213 180) (layer "B.Fab")
        (effects (font (size 0.7 0.7) (thickness 0.15)) (justify left bottom mirror))
    )
    (fp_text user "${REFERENCE}" (at -0.939 -4.599 180) (layer "B.Fab") hide
        (effects (font (size 0.7 0.7) (thickness 0.15)) (justify left bottom mirror))
    )
    (fp_text user "Author: Antmicro" (at -0.939 -3.399 180) (layer "B.Fab") hide
        (effects (font (size 0.7 0.7) (thickness 0.15)) (justify left bottom mirror))
    )
    (fp_text user "License: Apache-2.0" (at -0.939 -5.799 180) (layer "B.Fab") hide
        (effects (font (size 0.7 0.7) (thickness 0.15)) (justify left bottom mirror))
    )
    (fp_rect (start -0.925 0.47) (end 0.925 -0.47)
      (stroke (width 0.05) (type default)) (fill none) (layer "B.CrtYd"))
    (fp_line (start -0.494 -0.248) (end -0.494 0.25)
      (stroke (width 0.15) (type solid)) (layer "B.Fab"))
    (fp_line (start -0.494 0.25) (end 0.504 0.25)
      (stroke (width 0.15) (type solid)) (layer "B.Fab"))
    (fp_line (start 0.504 -0.248) (end -0.494 -0.248)
      (stroke (width 0.15) (type solid)) (layer "B.Fab"))
    (fp_line (start 0.504 0.25) (end 0.504 -0.248)
      (stroke (width 0.15) (type solid)) (layer "B.Fab"))
    (pad "1" smd roundrect (at -0.48 0) (size 0.59 0.64) (layers "B.Cu" "B.Paste" "B.Mask") (roundrect_rratio 0.25)
      (net 1 "GND") (pintype "passive"))
    (pad "2" smd roundrect (at 0.48 0) (size 0.59 0.64) (layers "B.Cu" "B.Paste" "B.Mask") (roundrect_rratio 0.25)
      (net 108 "Net-(C56-Pad2)") (pintype "passive"))
  )

  (footprint "antmicro-footprints:C_0402_1005Metric" (layer "B.Cu")
    (at 112.115 86.169999 90)
    (descr "Capacitor SMD 0402")
    (tags "capacitor SMD 0402")
    (property "Author" "Antmicro")
    (property "Dielectric" "")
    (property "License" "Apache-2.0")
    (property "MPN" "CGA2B3X7S2A472K050BB")
    (property "Manufacturer" "TDK")
    (property "Sheetfile" "power.kicad_sch")
    (property "Sheetname" "Power")
    (property "Val" "4n7")
    (property "Voltage" "")
    (property "ki_description" "SMD Multilayer Ceramic Capacitor, 4700 pF, 100 V, 0402 [1005 Metric], ± 10%, X7S, CGA")
    (property "ki_keywords" "0402, SMT, CAPACITOR, PASSIVE, CERAMIC, MLCC")
    (attr smd)
    (fp_text reference "C30" (at -2.984001 0.407 90) (layer "B.SilkS")
        (effects (font (size 0.7 0.7) (thickness 0.15)) (justify right bottom mirror))
    )
    (fp_text value "C_4n7_0402" (at -1.022927 -2.155213 90) (layer "B.Fab")
        (effects (font (size 0.7 0.7) (thickness 0.15)) (justify right bottom mirror))
    )
    (fp_text user "${REFERENCE}" (at -0.939 -4.599 90) (layer "B.Fab") hide
        (effects (font (size 0.7 0.7) (thickness 0.15)) (justify right bottom mirror))
    )
    (fp_text user "Author: Antmicro" (at -0.939 -3.399 90) (layer "B.Fab") hide
        (effects (font (size 0.7 0.7) (thickness 0.15)) (justify right bottom mirror))
    )
    (fp_text user "License: Apache-2.0" (at -0.939 -5.799 90) (layer "B.Fab") hide
        (effects (font (size 0.7 0.7) (thickness 0.15)) (justify right bottom mirror))
    )
    (fp_rect (start -0.925 0.47) (end 0.925 -0.47)
      (stroke (width 0.05) (type default)) (fill none) (layer "B.CrtYd"))
    (fp_line (start -0.494 -0.248) (end -0.494 0.25)
      (stroke (width 0.15) (type solid)) (layer "B.Fab"))
    (fp_line (start -0.494 0.25) (end 0.504 0.25)
      (stroke (width 0.15) (type solid)) (layer "B.Fab"))
    (fp_line (start 0.504 -0.248) (end -0.494 -0.248)
      (stroke (width 0.15) (type solid)) (layer "B.Fab"))
    (fp_line (start 0.504 0.25) (end 0.504 -0.248)
      (stroke (width 0.15) (type solid)) (layer "B.Fab"))
    (pad "1" smd roundrect (at -0.48 0 90) (size 0.59 0.64) (layers "B.Cu" "B.Paste" "B.Mask") (roundrect_rratio 0.25)
      (net 1 "GND") (pintype "passive"))
    (pad "2" smd roundrect (at 0.48 0 90) (size 0.59 0.64) (layers "B.Cu" "B.Paste" "B.Mask") (roundrect_rratio 0.25)
      (net 7 "Net-(C30-Pad2)") (pintype "passive"))
  )

  (footprint "antmicro-footprints:R_0402_1005Metric" (layer "B.Cu")
    (at 132.1 70.72 90)
    (descr "Resistor SMD 0402")
    (tags "resistor SMD 0402")
    (property "Author" "Antmicro")
    (property "License" "Apache-2.0")
    (property "MPN" "CR0402-FX-1002GLF")
    (property "Manufacturer" "Bourns")
    (property "Sheetfile" "tb.kicad_sch")
    (property "Sheetname" "TB Controller")
    (property "Tolerance" "1%")
    (property "Val" "10k")
    (property "ki_description" "SMD Chip Resistor, 10 kohm, ± 1%, 62.5 mW, 0402 [1005 Metric], Thick Film, General Purpose")
    (property "ki_keywords" "0402, SMT, RESISTOR, PASSIVE")
    (attr smd)
    (fp_text reference "R79" (at -0.908 0.361 270) (layer "B.SilkS")
        (effects (font (size 0.7 0.7) (thickness 0.15)) (justify left bottom mirror))
    )
    (fp_text value "R_10k_0402" (at -1.011843 -1.772047 270) (layer "B.Fab")
        (effects (font (size 0.7 0.7) (thickness 0.15)) (justify left bottom mirror))
    )
    (fp_text user "License: Apache-2.0" (at -0.95 -5.169 270) (layer "B.Fab") hide
        (effects (font (size 0.7 0.7) (thickness 0.15)) (justify left bottom mirror))
    )
    (fp_text user "${REFERENCE}" (at -0.95 -3.168 270) (layer "B.Fab") hide
        (effects (font (size 0.7 0.7) (thickness 0.15)) (justify left bottom mirror))
    )
    (fp_text user "Author: Antmicro" (at -0.95 -4.169 270) (layer "B.Fab") hide
        (effects (font (size 0.7 0.7) (thickness 0.15)) (justify left bottom mirror))
    )
    (fp_rect (start -0.925 0.47) (end 0.925 -0.47)
      (stroke (width 0.05) (type default)) (fill none) (layer "B.CrtYd"))
    (fp_rect (start -0.5 0.25) (end 0.5 -0.25)
      (stroke (width 0.15) (type solid)) (fill none) (layer "B.Fab"))
    (pad "1" smd roundrect (at -0.48 0 90) (size 0.59 0.64) (layers "B.Cu" "B.Paste" "B.Mask") (roundrect_rratio 0.25)
      (net 194 "Net-(U4C-GPIO_5)") (pintype "passive"))
    (pad "2" smd roundrect (at 0.48 0 90) (size 0.59 0.64) (layers "B.Cu" "B.Paste" "B.Mask") (roundrect_rratio 0.25)
      (net 1 "GND") (pintype "passive"))
  )

  (footprint "antmicro-footprints:C_0402_1005Metric" (layer "B.Cu")
    (at 126.5 92.65 -90)
    (descr "Capacitor SMD 0402")
    (tags "capacitor SMD 0402")
    (property "Author" "Antmicro")
    (property "Dielectric" "")
    (property "License" "Apache-2.0")
    (property "MPN" "CC0402KRX5R6BB224")
    (property "Manufacturer" "YAGEO")
    (property "Sheetfile" "tb.kicad_sch")
    (property "Sheetname" "TB Controller")
    (property "Val" "220n")
    (property "Voltage" "")
    (property "ki_description" "SMD Multilayer Ceramic Capacitor, 0.22 µF, 10 V, 0402 [1005 Metric], ± 10%, X5R, CC Series")
    (property "ki_keywords" "0402, SMT, CAPACITOR, PASSIVE, MLCC, CERAMIC")
    (attr smd)
    (fp_text reference "C109" (at -3.877 -0.47 90) (layer "B.SilkS")
        (effects (font (size 0.7 0.7) (thickness 0.15)) (justify left bottom mirror))
    )
    (fp_text value "C_220n_0402" (at -1.022927 -2.155213 90) (layer "B.Fab")
        (effects (font (size 0.7 0.7) (thickness 0.15)) (justify left bottom mirror))
    )
    (fp_text user "${REFERENCE}" (at -0.939 -4.599 90) (layer "B.Fab") hide
        (effects (font (size 0.7 0.7) (thickness 0.15)) (justify left bottom mirror))
    )
    (fp_text user "License: Apache-2.0" (at -0.939 -5.799 90) (layer "B.Fab") hide
        (effects (font (size 0.7 0.7) (thickness 0.15)) (justify left bottom mirror))
    )
    (fp_text user "Author: Antmicro" (at -0.939 -3.399 90) (layer "B.Fab") hide
        (effects (font (size 0.7 0.7) (thickness 0.15)) (justify left bottom mirror))
    )
    (fp_rect (start -0.925 0.47) (end 0.925 -0.47)
      (stroke (width 0.05) (type default)) (fill none) (layer "B.CrtYd"))
    (fp_line (start -0.494 -0.248) (end -0.494 0.25)
      (stroke (width 0.15) (type solid)) (layer "B.Fab"))
    (fp_line (start -0.494 0.25) (end 0.504 0.25)
      (stroke (width 0.15) (type solid)) (layer "B.Fab"))
    (fp_line (start 0.504 -0.248) (end -0.494 -0.248)
      (stroke (width 0.15) (type solid)) (layer "B.Fab"))
    (fp_line (start 0.504 0.25) (end 0.504 -0.248)
      (stroke (width 0.15) (type solid)) (layer "B.Fab"))
    (pad "1" smd roundrect (at -0.48 0 270) (size 0.59 0.64) (layers "B.Cu" "B.Paste" "B.Mask") (roundrect_rratio 0.25)
      (net 80 "/TB Controller/TX0_P") (pintype "passive"))
    (pad "2" smd roundrect (at 0.48 0 270) (size 0.59 0.64) (layers "B.Cu" "B.Paste" "B.Mask") (roundrect_rratio 0.25)
      (net 28 "PCIE_TX0_P") (pintype "passive"))
  )

  (footprint "antmicro-footprints:C_0402_1005Metric" (layer "B.Cu")
    (at 123 79.2)
    (descr "Capacitor SMD 0402")
    (tags "capacitor SMD 0402")
    (property "Author" "Antmicro")
    (property "Dielectric" "X5R")
    (property "License" "Apache-2.0")
    (property "MPN" "GRM155R61H104KE14D")
    (property "Manufacturer" "Murata")
    (property "Sheetfile" "tb.kicad_sch")
    (property "Sheetname" "TB Controller")
    (property "Val" "100n")
    (property "Voltage" "50V")
    (property "ki_description" "SMD Multilayer Ceramic Capacitor, 0.1 µF, 50 V, 0402 [1005 Metric], ± 10%, X5R, GRM Series")
    (property "ki_keywords" "0402, SMT, CAPACITOR, PASSIVE, CERAMIC, MLCC")
    (attr smd)
    (fp_text reference "C115" (at 1.079 1.445 180) (layer "B.SilkS")
        (effects (font (size 0.7 0.7) (thickness 0.15)) (justify left bottom mirror))
    )
    (fp_text value "C_100n_0402" (at -1.022927 -2.155213 180) (layer "B.Fab")
        (effects (font (size 0.7 0.7) (thickness 0.15)) (justify left bottom mirror))
    )
    (fp_text user "License: Apache-2.0" (at -0.939 -5.799 180) (layer "B.Fab") hide
        (effects (font (size 0.7 0.7) (thickness 0.15)) (justify left bottom mirror))
    )
    (fp_text user "Author: Antmicro" (at -0.939 -3.399 180) (layer "B.Fab") hide
        (effects (font (size 0.7 0.7) (thickness 0.15)) (justify left bottom mirror))
    )
    (fp_text user "${REFERENCE}" (at -0.939 -4.599 180) (layer "B.Fab") hide
        (effects (font (size 0.7 0.7) (thickness 0.15)) (justify left bottom mirror))
    )
    (fp_rect (start -0.925 0.47) (end 0.925 -0.47)
      (stroke (width 0.05) (type default)) (fill none) (layer "B.CrtYd"))
    (fp_line (start -0.494 -0.248) (end -0.494 0.25)
      (stroke (width 0.15) (type solid)) (layer "B.Fab"))
    (fp_line (start -0.494 0.25) (end 0.504 0.25)
      (stroke (width 0.15) (type solid)) (layer "B.Fab"))
    (fp_line (start 0.504 -0.248) (end -0.494 -0.248)
      (stroke (width 0.15) (type solid)) (layer "B.Fab"))
    (fp_line (start 0.504 0.25) (end 0.504 -0.248)
      (stroke (width 0.15) (type solid)) (layer "B.Fab"))
    (pad "1" smd roundrect (at -0.48 0) (size 0.59 0.64) (layers "B.Cu" "B.Paste" "B.Mask") (roundrect_rratio 0.25)
      (net 1 "GND") (pintype "passive"))
    (pad "2" smd roundrect (at 0.48 0) (size 0.59 0.64) (layers "B.Cu" "B.Paste" "B.Mask") (roundrect_rratio 0.25)
      (net 2 "3V3_SYS") (pintype "passive"))
  )

  (footprint "antmicro-footprints:C_0402_1005Metric" (layer "B.Cu")
    (at 155.08 81.74 180)
    (descr "Capacitor SMD 0402")
    (tags "capacitor SMD 0402")
    (property "Author" "Antmicro")
    (property "Dielectric" "")
    (property "License" "Apache-2.0")
    (property "MPN" "CC0402KRX5R6BB224")
    (property "Manufacturer" "YAGEO")
    (property "Sheetfile" "tb.kicad_sch")
    (property "Sheetname" "TB Controller")
    (property "Val" "220n")
    (property "Voltage" "")
    (property "ki_description" "SMD Multilayer Ceramic Capacitor, 0.22 µF, 10 V, 0402 [1005 Metric], ± 10%, X5R, CC Series")
    (property "ki_keywords" "0402, SMT, CAPACITOR, PASSIVE, MLCC, CERAMIC")
    (attr smd)
    (fp_text reference "C99" (at 1.034 -0.431) (layer "B.SilkS")
        (effects (font (size 0.7 0.7) (thickness 0.15)) (justify left bottom mirror))
    )
    (fp_text value "C_220n_0402" (at -1.022927 -2.155213) (layer "B.Fab")
        (effects (font (size 0.7 0.7) (thickness 0.15)) (justify left bottom mirror))
    )
    (fp_text user "Author: Antmicro" (at -0.939 -3.399) (layer "B.Fab") hide
        (effects (font (size 0.7 0.7) (thickness 0.15)) (justify left bottom mirror))
    )
    (fp_text user "License: Apache-2.0" (at -0.939 -5.799) (layer "B.Fab") hide
        (effects (font (size 0.7 0.7) (thickness 0.15)) (justify left bottom mirror))
    )
    (fp_text user "${REFERENCE}" (at -0.939 -4.599) (layer "B.Fab") hide
        (effects (font (size 0.7 0.7) (thickness 0.15)) (justify left bottom mirror))
    )
    (fp_rect (start -0.925 0.47) (end 0.925 -0.47)
      (stroke (width 0.05) (type default)) (fill none) (layer "B.CrtYd"))
    (fp_line (start -0.494 -0.248) (end -0.494 0.25)
      (stroke (width 0.15) (type solid)) (layer "B.Fab"))
    (fp_line (start -0.494 0.25) (end 0.504 0.25)
      (stroke (width 0.15) (type solid)) (layer "B.Fab"))
    (fp_line (start 0.504 -0.248) (end -0.494 -0.248)
      (stroke (width 0.15) (type solid)) (layer "B.Fab"))
    (fp_line (start 0.504 0.25) (end 0.504 -0.248)
      (stroke (width 0.15) (type solid)) (layer "B.Fab"))
    (pad "1" smd roundrect (at -0.48 0 180) (size 0.59 0.64) (layers "B.Cu" "B.Paste" "B.Mask") (roundrect_rratio 0.25)
      (net 12 "TB_TX0_P") (pintype "passive"))
    (pad "2" smd roundrect (at 0.48 0 180) (size 0.59 0.64) (layers "B.Cu" "B.Paste" "B.Mask") (roundrect_rratio 0.25)
      (net 13 "/TB Controller/PA_TX0_P") (pintype "passive"))
  )

  (footprint "antmicro-footprints:C_0402_1005Metric" (layer "B.Cu")
    (at 135.115 58.1 180)
    (descr "Capacitor SMD 0402")
    (tags "capacitor SMD 0402")
    (property "Author" "Antmicro")
    (property "Dielectric" "X5R")
    (property "License" "Apache-2.0")
    (property "MPN" "GRM155R61H104KE14D")
    (property "Manufacturer" "Murata")
    (property "Sheetfile" "tb.kicad_sch")
    (property "Sheetname" "TB Controller")
    (property "Val" "100n")
    (property "Voltage" "50V")
    (property "ki_description" "SMD Multilayer Ceramic Capacitor, 0.1 µF, 50 V, 0402 [1005 Metric], ± 10%, X5R, GRM Series")
    (property "ki_keywords" "0402, SMT, CAPACITOR, PASSIVE, CERAMIC, MLCC")
    (attr smd)
    (fp_text reference "C101" (at 1.003 -0.447) (layer "B.SilkS")
        (effects (font (size 0.7 0.7) (thickness 0.15)) (justify left bottom mirror))
    )
    (fp_text value "C_100n_0402" (at -1.022927 -2.155213) (layer "B.Fab")
        (effects (font (size 0.7 0.7) (thickness 0.15)) (justify left bottom mirror))
    )
    (fp_text user "License: Apache-2.0" (at -0.939 -5.799) (layer "B.Fab") hide
        (effects (font (size 0.7 0.7) (thickness 0.15)) (justify left bottom mirror))
    )
    (fp_text user "${REFERENCE}" (at -0.939 -4.599) (layer "B.Fab") hide
        (effects (font (size 0.7 0.7) (thickness 0.15)) (justify left bottom mirror))
    )
    (fp_text user "Author: Antmicro" (at -0.939 -3.399) (layer "B.Fab") hide
        (effects (font (size 0.7 0.7) (thickness 0.15)) (justify left bottom mirror))
    )
    (fp_rect (start -0.925 0.47) (end 0.925 -0.47)
      (stroke (width 0.05) (type default)) (fill none) (layer "B.CrtYd"))
    (fp_line (start -0.494 -0.248) (end -0.494 0.25)
      (stroke (width 0.15) (type solid)) (layer "B.Fab"))
    (fp_line (start -0.494 0.25) (end 0.504 0.25)
      (stroke (width 0.15) (type solid)) (layer "B.Fab"))
    (fp_line (start 0.504 -0.248) (end -0.494 -0.248)
      (stroke (width 0.15) (type solid)) (layer "B.Fab"))
    (fp_line (start 0.504 0.25) (end 0.504 -0.248)
      (stroke (width 0.15) (type solid)) (layer "B.Fab"))
    (pad "1" smd roundrect (at -0.48 0 180) (size 0.59 0.64) (layers "B.Cu" "B.Paste" "B.Mask") (roundrect_rratio 0.25)
      (net 16 "AUX_P") (pintype "passive"))
    (pad "2" smd roundrect (at 0.48 0 180) (size 0.59 0.64) (layers "B.Cu" "B.Paste" "B.Mask") (roundrect_rratio 0.25)
      (net 86 "/TB Controller/PA_AUX_P") (pintype "passive"))
  )

  (footprint "antmicro-footprints:R_0402_1005Metric" (layer "B.Cu")
    (at 148.5 70.94 90)
    (descr "Resistor SMD 0402")
    (tags "resistor SMD 0402")
    (property "Author" "Antmicro")
    (property "License" "Apache-2.0")
    (property "MPN" "CR0402-FX-3300GLF")
    (property "Manufacturer" "Bourns")
    (property "Sheetfile" "tb-power.kicad_sch")
    (property "Sheetname" "Thunderbolt Controller - Power")
    (property "Tolerance" "1%")
    (property "Val" "330R")
    (property "ki_description" "SMD Chip Resistor, 330 ohm, ± 1%, 62.5 mW, 0402 [1005 Metric], Thick Film, General Purpose")
    (property "ki_keywords" "0402, SMT, RESISTOR, PASSIVE")
    (attr smd)
    (fp_text reference "R49" (at 3.122 0.455 270) (layer "B.SilkS")
        (effects (font (size 0.7 0.7) (thickness 0.15)) (justify left bottom mirror))
    )
    (fp_text value "R_330R_0402" (at -1.011843 -1.772047 270) (layer "B.Fab")
        (effects (font (size 0.7 0.7) (thickness 0.15)) (justify left bottom mirror))
    )
    (fp_text user "Author: Antmicro" (at -0.95 -4.169 270) (layer "B.Fab") hide
        (effects (font (size 0.7 0.7) (thickness 0.15)) (justify left bottom mirror))
    )
    (fp_text user "${REFERENCE}" (at -0.95 -3.168 270) (layer "B.Fab") hide
        (effects (font (size 0.7 0.7) (thickness 0.15)) (justify left bottom mirror))
    )
    (fp_text user "License: Apache-2.0" (at -0.95 -5.169 270) (layer "B.Fab") hide
        (effects (font (size 0.7 0.7) (thickness 0.15)) (justify left bottom mirror))
    )
    (fp_rect (start -0.925 0.47) (end 0.925 -0.47)
      (stroke (width 0.05) (type default)) (fill none) (layer "B.CrtYd"))
    (fp_rect (start -0.5 0.25) (end 0.5 -0.25)
      (stroke (width 0.15) (type solid)) (fill none) (layer "B.Fab"))
    (pad "1" smd roundrect (at -0.48 0 90) (size 0.59 0.64) (layers "B.Cu" "B.Paste" "B.Mask") (roundrect_rratio 0.25)
      (net 139 "Net-(Q1-C)") (pintype "passive"))
    (pad "2" smd roundrect (at 0.48 0 90) (size 0.59 0.64) (layers "B.Cu" "B.Paste" "B.Mask") (roundrect_rratio 0.25)
      (net 122 "Net-(D4-C)") (pintype "passive"))
  )

  (footprint "antmicro-footprints:C_0603_1608Metric" (layer "B.Cu")
    (at 163.43 89.8 90)
    (descr "Capacitor SMD 0603")
    (tags "capacitor 0603")
    (property "Author" "Antmicro")
    (property "Dielectric" "")
    (property "License" "Apache-2.0")
    (property "MPN" "CL10A226MO7JZNC")
    (property "Manufacturer" "Samsung Electro-Mechanics")
    (property "Sheetfile" "power.kicad_sch")
    (property "Sheetname" "Power")
    (property "Val" "22u")
    (property "Voltage" "16V")
    (property "ki_description" "SMD Multilayer Ceramic Capacitor")
    (property "ki_keywords" "0603, SMT, CAPACITOR, PASSIVE, CERAMIC")
    (attr smd)
    (fp_text reference "C122" (at 4.202 0.4 270) (layer "B.SilkS")
        (effects (font (size 0.7 0.7) (thickness 0.15)) (justify left bottom mirror))
    )
    (fp_text value "C_22u_16V_0603" (at -1.42757 -1.770288 270) (layer "B.Fab")
        (effects (font (size 0.7 0.7) (thickness 0.15)) (justify left bottom mirror))
    )
    (fp_text user "License: Apache-2.0" (at -1.682 -5.895 270) (layer "B.Fab") hide
        (effects (font (size 0.7 0.7) (thickness 0.15)) (justify left bottom mirror))
    )
    (fp_text user "Author: Antmicro" (at -1.682 -4.894 270) (layer "B.Fab") hide
        (effects (font (size 0.7 0.7) (thickness 0.15)) (justify left bottom mirror))
    )
    (fp_text user "${REFERENCE}" (at -1.682 -3.895 270) (layer "B.Fab") hide
        (effects (font (size 0.7 0.7) (thickness 0.15)) (justify left bottom mirror))
    )
    (fp_line (start -0.15 -0.4) (end 0.15 -0.4)
      (stroke (width 0.15) (type solid)) (layer "B.SilkS"))
    (fp_line (start -0.15 0.4) (end 0.15 0.4)
      (stroke (width 0.15) (type solid)) (layer "B.SilkS"))
    (fp_rect (start -1.25 0.65) (end 1.25 -0.65)
      (stroke (width 0.05) (type solid)) (fill none) (layer "B.CrtYd"))
    (fp_rect (start -0.8 0.4) (end 0.8 -0.4)
      (stroke (width 0.15) (type solid)) (fill none) (layer "B.Fab"))
    (pad "1" smd roundrect (at -0.7 0 90) (size 0.8 1) (layers "B.Cu" "B.Paste" "B.Mask") (roundrect_rratio 0.2)
      (net 1 "GND") (pintype "passive"))
    (pad "2" smd roundrect (at 0.7 0 90) (size 0.8 1) (layers "B.Cu" "B.Paste" "B.Mask") (roundrect_rratio 0.2)
      (net 61 "12V0_MOLEX") (pintype "passive"))
  )

  (footprint "antmicro-footprints:C_0402_1005Metric" (layer "B.Cu")
    (at 132.85 80.825)
    (descr "Capacitor SMD 0402")
    (tags "capacitor SMD 0402")
    (property "Author" "Antmicro")
    (property "Dielectric" "X5R")
    (property "License" "Apache-2.0")
    (property "MPN" "GRM155R61H104KE14D")
    (property "Manufacturer" "Murata")
    (property "Sheetfile" "tb-power.kicad_sch")
    (property "Sheetname" "Thunderbolt Controller - Power")
    (property "Val" "100n")
    (property "Voltage" "50V")
    (property "ki_description" "SMD Multilayer Ceramic Capacitor, 0.1 µF, 50 V, 0402 [1005 Metric], ± 10%, X5R, GRM Series")
    (property "ki_keywords" "0402, SMT, CAPACITOR, PASSIVE, CERAMIC, MLCC")
    (attr smd)
    (fp_text reference "C92" (at 17.518 7.694 180) (layer "B.SilkS")
        (effects (font (size 0.7 0.7) (thickness 0.15)) (justify left bottom mirror))
    )
    (fp_text value "C_100n_0402" (at -1.022927 -2.155213 180) (layer "B.Fab")
        (effects (font (size 0.7 0.7) (thickness 0.15)) (justify left bottom mirror))
    )
    (fp_text user "Author: Antmicro" (at -0.939 -3.399 180) (layer "B.Fab") hide
        (effects (font (size 0.7 0.7) (thickness 0.15)) (justify left bottom mirror))
    )
    (fp_text user "License: Apache-2.0" (at -0.939 -5.799 180) (layer "B.Fab") hide
        (effects (font (size 0.7 0.7) (thickness 0.15)) (justify left bottom mirror))
    )
    (fp_text user "${REFERENCE}" (at -0.939 -4.599 180) (layer "B.Fab") hide
        (effects (font (size 0.7 0.7) (thickness 0.15)) (justify left bottom mirror))
    )
    (fp_rect (start -0.925 0.47) (end 0.925 -0.47)
      (stroke (width 0.05) (type default)) (fill none) (layer "B.CrtYd"))
    (fp_line (start -0.494 -0.248) (end -0.494 0.25)
      (stroke (width 0.15) (type solid)) (layer "B.Fab"))
    (fp_line (start -0.494 0.25) (end 0.504 0.25)
      (stroke (width 0.15) (type solid)) (layer "B.Fab"))
    (fp_line (start 0.504 -0.248) (end -0.494 -0.248)
      (stroke (width 0.15) (type solid)) (layer "B.Fab"))
    (fp_line (start 0.504 0.25) (end 0.504 -0.248)
      (stroke (width 0.15) (type solid)) (layer "B.Fab"))
    (pad "1" smd roundrect (at -0.48 0) (size 0.59 0.64) (layers "B.Cu" "B.Paste" "B.Mask") (roundrect_rratio 0.25)
      (net 1 "GND") (pintype "passive"))
    (pad "2" smd roundrect (at 0.48 0) (size 0.59 0.64) (layers "B.Cu" "B.Paste" "B.Mask") (roundrect_rratio 0.25)
      (net 114 "Net-(U4A-VCC3P3_S0)") (pintype "passive"))
  )

  (footprint "antmicro-footprints:C_0402_1005Metric" (layer "B.Cu")
    (at 142.682242 89.259183 45)
    (descr "Capacitor SMD 0402")
    (tags "capacitor SMD 0402")
    (property "Author" "Antmicro")
    (property "Dielectric" "C0G")
    (property "License" "Apache-2.0")
    (property "MPN" "GCM1555C1H100GA16D")
    (property "Manufacturer" "Murata")
    (property "Sheetfile" "tb.kicad_sch")
    (property "Sheetname" "TB Controller")
    (property "Val" "10p")
    (property "Voltage" "50V")
    (property "ki_description" "SMD Multilayer Ceramic Capacitor, 10 pF, 50 V, 0402 [1005 Metric], ± 2%, C0G / NP0, GCM")
    (property "ki_keywords" "0402, SMT, CAPACITOR, PASSIVE")
    (attr smd)
    (fp_text reference "C117" (at 1.827122 -0.656496 225) (layer "B.SilkS")
        (effects (font (size 0.7 0.7) (thickness 0.15)) (justify left bottom mirror))
    )
    (fp_text value "C_10p_0402" (at -1.022927 -2.155213 225) (layer "B.Fab")
        (effects (font (size 0.7 0.7) (thickness 0.15)) (justify left bottom mirror))
    )
    (fp_text user "${REFERENCE}" (at -0.939 -4.599 225) (layer "B.Fab") hide
        (effects (font (size 0.7 0.7) (thickness 0.15)) (justify left bottom mirror))
    )
    (fp_text user "Author: Antmicro" (at -0.939 -3.399 225) (layer "B.Fab") hide
        (effects (font (size 0.7 0.7) (thickness 0.15)) (justify left bottom mirror))
    )
    (fp_text user "License: Apache-2.0" (at -0.939 -5.799 225) (layer "B.Fab") hide
        (effects (font (size 0.7 0.7) (thickness 0.15)) (justify left bottom mirror))
    )
    (fp_rect (start -0.925 0.47) (end 0.925 -0.47)
      (stroke (width 0.05) (type default)) (fill none) (layer "B.CrtYd"))
    (fp_line (start -0.494 -0.248) (end -0.494 0.25)
      (stroke (width 0.15) (type solid)) (layer "B.Fab"))
    (fp_line (start -0.494 0.25) (end 0.504 0.25)
      (stroke (width 0.15) (type solid)) (layer "B.Fab"))
    (fp_line (start 0.504 -0.248) (end -0.494 -0.248)
      (stroke (width 0.15) (type solid)) (layer "B.Fab"))
    (fp_line (start 0.504 0.25) (end 0.504 -0.248)
      (stroke (width 0.15) (type solid)) (layer "B.Fab"))
    (pad "1" smd roundrect (at -0.48 0 45) (size 0.59 0.64) (layers "B.Cu" "B.Paste" "B.Mask") (roundrect_rratio 0.25)
      (net 118 "Net-(U4D-XTAL_25_OUT)") (pintype "passive"))
    (pad "2" smd roundrect (at 0.48 0 45) (size 0.59 0.64) (layers "B.Cu" "B.Paste" "B.Mask") (roundrect_rratio 0.25)
      (net 1 "GND") (pintype "passive"))
  )

  (footprint "antmicro-footprints:R_0402_1005Metric" (layer "B.Cu")
    (at 151.41 62.97)
    (descr "Resistor SMD 0402")
    (tags "resistor SMD 0402")
    (property "Author" "Antmicro")
    (property "Current" "1A")
    (property "License" "Apache-2.0")
    (property "MPN" "ERJ2GE0R00X")
    (property "Manufacturer" "Panasonic")
    (property "Sheetfile" "power.kicad_sch")
    (property "Sheetname" "Power")
    (property "Tolerance" "")
    (property "Val" "0R")
    (property "ki_description" "SMD Chip Resistor, Jumper, 0 ohm, 100 mW, 0402 [1005 Metric], Thick Film, General Purpose")
    (property "ki_keywords" "0402, SMT, RESISTOR, PASSIVE")
    (attr smd)
    (fp_text reference "R31" (at -0.915 0.482 180) (layer "B.SilkS")
        (effects (font (size 0.7 0.7) (thickness 0.15)) (justify left bottom mirror))
    )
    (fp_text value "R_0R_0402" (at -1.011843 -1.772047 180) (layer "B.Fab")
        (effects (font (size 0.7 0.7) (thickness 0.15)) (justify left bottom mirror))
    )
    (fp_text user "${REFERENCE}" (at -0.95 -3.168 180) (layer "B.Fab") hide
        (effects (font (size 0.7 0.7) (thickness 0.15)) (justify left bottom mirror))
    )
    (fp_text user "Author: Antmicro" (at -0.95 -4.169 180) (layer "B.Fab") hide
        (effects (font (size 0.7 0.7) (thickness 0.15)) (justify left bottom mirror))
    )
    (fp_text user "License: Apache-2.0" (at -0.95 -5.169 180) (layer "B.Fab") hide
        (effects (font (size 0.7 0.7) (thickness 0.15)) (justify left bottom mirror))
    )
    (fp_rect (start -0.925 0.47) (end 0.925 -0.47)
      (stroke (width 0.05) (type default)) (fill none) (layer "B.CrtYd"))
    (fp_rect (start -0.5 0.25) (end 0.5 -0.25)
      (stroke (width 0.15) (type solid)) (fill none) (layer "B.Fab"))
    (pad "1" smd roundrect (at -0.48 0) (size 0.59 0.64) (layers "B.Cu" "B.Paste" "B.Mask") (roundrect_rratio 0.25)
      (net 164 "Net-(U3-I2C_ADDR)") (pintype "passive"))
    (pad "2" smd roundrect (at 0.48 0) (size 0.59 0.64) (layers "B.Cu" "B.Paste" "B.Mask") (roundrect_rratio 0.25)
      (net 1 "GND") (pintype "passive"))
  )

  (footprint "antmicro-footprints:C_0402_1005Metric" (layer "B.Cu")
    (at 153.91 60.47 -90)
    (descr "Capacitor SMD 0402")
    (tags "capacitor SMD 0402")
    (property "Author" "Antmicro")
    (property "Dielectric" "")
    (property "License" "Apache-2.0")
    (property "MPN" "C1005X6S1A105K050BC")
    (property "Manufacturer" "TDK")
    (property "Sheetfile" "power.kicad_sch")
    (property "Sheetname" "Power")
    (property "Val" "1u")
    (property "Voltage" "")
    (property "ki_description" "SMD Multilayer Ceramic Capacitor, 1 µF, 10 V, 0402 [1005 Metric], ± 10%, X6S, C")
    (property "ki_keywords" "0402, SMT, CAPACITOR, PASSIVE, CERAMIC, MLCC")
    (attr smd)
    (fp_text reference "C22" (at -3.193 -0.268 90) (layer "B.SilkS")
        (effects (font (size 0.7 0.7) (thickness 0.15)) (justify left bottom mirror))
    )
    (fp_text value "C_1u_0402" (at -1.022927 -2.155213 90) (layer "B.Fab")
        (effects (font (size 0.7 0.7) (thickness 0.15)) (justify left bottom mirror))
    )
    (fp_text user "Author: Antmicro" (at -0.939 -3.399 90) (layer "B.Fab") hide
        (effects (font (size 0.7 0.7) (thickness 0.15)) (justify left bottom mirror))
    )
    (fp_text user "${REFERENCE}" (at -0.939 -4.599 90) (layer "B.Fab") hide
        (effects (font (size 0.7 0.7) (thickness 0.15)) (justify left bottom mirror))
    )
    (fp_text user "License: Apache-2.0" (at -0.939 -5.799 90) (layer "B.Fab") hide
        (effects (font (size 0.7 0.7) (thickness 0.15)) (justify left bottom mirror))
    )
    (fp_rect (start -0.925 0.47) (end 0.925 -0.47)
      (stroke (width 0.05) (type default)) (fill none) (layer "B.CrtYd"))
    (fp_line (start -0.494 -0.248) (end -0.494 0.25)
      (stroke (width 0.15) (type solid)) (layer "B.Fab"))
    (fp_line (start -0.494 0.25) (end 0.504 0.25)
      (stroke (width 0.15) (type solid)) (layer "B.Fab"))
    (fp_line (start 0.504 -0.248) (end -0.494 -0.248)
      (stroke (width 0.15) (type solid)) (layer "B.Fab"))
    (fp_line (start 0.504 0.25) (end 0.504 -0.248)
      (stroke (width 0.15) (type solid)) (layer "B.Fab"))
    (pad "1" smd roundrect (at -0.48 0 270) (size 0.59 0.64) (layers "B.Cu" "B.Paste" "B.Mask") (roundrect_rratio 0.25)
      (net 1 "GND") (pintype "passive"))
    (pad "2" smd roundrect (at 0.48 0 270) (size 0.59 0.64) (layers "B.Cu" "B.Paste" "B.Mask") (roundrect_rratio 0.25)
      (net 2 "3V3_SYS") (pintype "passive"))
  )

  (footprint "antmicro-footprints:L_0603_1608Metric" (layer "B.Cu")
    (at 128.44 82.04)
    (property "Author" "Antmicro")
    (property "IMax" "1.8A")
    (property "ISat" "1.9A")
    (property "License" "Apache-2.0")
    (property "MPN" "DFE18SBN1R0ME0L")
    (property "Manufacturer" "Murata")
    (property "Sheetfile" "tb-power.kicad_sch")
    (property "Sheetname" "Thunderbolt Controller - Power")
    (property "Size" "1.6x0.8")
    (property "Val" "1u/1.8A")
    (property "ki_description" "Power Inductor (SMT), 1 µH, 1.8 A, Shielded, 1.9 A, DFE Series, 0603 [1608 Metric]")
    (property "ki_keywords" "INDUCTOR, PASSIVE")
    (attr smd)
    (fp_text reference "L4" (at 0.592 1.653 180) (layer "B.SilkS")
        (effects (font (size 0.7 0.7) (thickness 0.15)) (justify left bottom mirror))
    )
    (fp_text value "L_1u_1.8A_0603" (at 0 -2 180) (layer "B.Fab")
        (effects (font (size 0.7 0.7) (thickness 0.15)) (justify left bottom mirror))
    )
    (fp_text user "License: Apache-2.0" (at -1.9 -5.75 180) (layer "B.Fab") hide
        (effects (font (size 0.7 0.7) (thickness 0.15)) (justify left bottom mirror))
    )
    (fp_text user "Author: Antmicro" (at -1.9 -4.4 180) (layer "B.Fab") hide
        (effects (font (size 0.7 0.7) (thickness 0.15)) (justify left bottom mirror))
    )
    (fp_text user "${REFERENCE}" (at -1.9 -3.1 180) (layer "B.Fab") hide
        (effects (font (size 0.7 0.7) (thickness 0.15)) (justify left bottom mirror))
    )
    (fp_line (start -0.15 -0.4) (end 0.15 -0.4)
      (stroke (width 0.15) (type solid)) (layer "B.SilkS"))
    (fp_line (start -0.15 0.4) (end 0.15 0.4)
      (stroke (width 0.15) (type solid)) (layer "B.SilkS"))
    (fp_rect (start -1.25 0.65) (end 1.25 -0.65)
      (stroke (width 0.05) (type solid)) (fill none) (layer "B.CrtYd"))
    (fp_rect (start -0.8 0.4) (end 0.8 -0.4)
      (stroke (width 0.1) (type solid)) (fill none) (layer "B.Fab"))
    (pad "1" smd roundrect (at -0.7 0) (size 0.8 1) (layers "B.Cu" "B.Paste" "B.Mask") (roundrect_rratio 0.2)
      (net 114 "Net-(U4A-VCC3P3_S0)") (pintype "passive"))
    (pad "2" smd roundrect (at 0.7 0) (size 0.8 1) (layers "B.Cu" "B.Paste" "B.Mask") (roundrect_rratio 0.2)
      (net 2 "3V3_SYS") (pintype "passive"))
  )

  (footprint "antmicro-footprints:R_0402_1005Metric" (layer "B.Cu")
    (at 159.425 60.97 180)
    (descr "Resistor SMD 0402")
    (tags "resistor SMD 0402")
    (property "Author" "Antmicro")
    (property "Current" "1A")
    (property "License" "Apache-2.0")
    (property "MPN" "ERJ2GE0R00X")
    (property "Manufacturer" "Panasonic")
    (property "Sheetfile" "power.kicad_sch")
    (property "Sheetname" "Power")
    (property "Tolerance" "")
    (property "Val" "0R")
    (property "ki_description" "SMD Chip Resistor, Jumper, 0 ohm, 100 mW, 0402 [1005 Metric], Thick Film, General Purpose")
    (property "ki_keywords" "0402, SMT, RESISTOR, PASSIVE")
    (attr smd)
    (fp_text reference "R18" (at -1.160616 -2.261603) (layer "B.SilkS")
        (effects (font (size 0.7 0.7) (thickness 0.15)) (justify left bottom mirror))
    )
    (fp_text value "R_0R_0402" (at -1.011843 -1.772047) (layer "B.Fab")
        (effects (font (size 0.7 0.7) (thickness 0.15)) (justify left bottom mirror))
    )
    (fp_text user "${REFERENCE}" (at -0.95 -3.168) (layer "B.Fab") hide
        (effects (font (size 0.7 0.7) (thickness 0.15)) (justify left bottom mirror))
    )
    (fp_text user "License: Apache-2.0" (at -0.95 -5.169) (layer "B.Fab") hide
        (effects (font (size 0.7 0.7) (thickness 0.15)) (justify left bottom mirror))
    )
    (fp_text user "Author: Antmicro" (at -0.95 -4.169) (layer "B.Fab") hide
        (effects (font (size 0.7 0.7) (thickness 0.15)) (justify left bottom mirror))
    )
    (fp_rect (start -0.925 0.47) (end 0.925 -0.47)
      (stroke (width 0.05) (type default)) (fill none) (layer "B.CrtYd"))
    (fp_rect (start -0.5 0.25) (end 0.5 -0.25)
      (stroke (width 0.15) (type solid)) (fill none) (layer "B.Fab"))
    (pad "1" smd roundrect (at -0.48 0 180) (size 0.59 0.64) (layers "B.Cu" "B.Paste" "B.Mask") (roundrect_rratio 0.25)
      (net 58 "HPD") (pintype "passive"))
    (pad "2" smd roundrect (at 0.48 0 180) (size 0.59 0.64) (layers "B.Cu" "B.Paste" "B.Mask") (roundrect_rratio 0.25)
      (net 153 "Net-(U3-GPIO4(HPD_TXRX))") (pintype "passive"))
  )

  (footprint "antmicro-footprints:C_0402_1005Metric" (layer "B.Cu")
    (at 136.75 77.9)
    (descr "Capacitor SMD 0402")
    (tags "capacitor SMD 0402")
    (property "Author" "Antmicro")
    (property "Dielectric" "")
    (property "License" "Apache-2.0")
    (property "MPN" "C1005X6S1A105K050BC")
    (property "Manufacturer" "TDK")
    (property "Sheetfile" "tb-power.kicad_sch")
    (property "Sheetname" "Thunderbolt Controller - Power")
    (property "Val" "1u")
    (property "Voltage" "")
    (property "ki_description" "SMD Multilayer Ceramic Capacitor, 1 µF, 10 V, 0402 [1005 Metric], ± 10%, X6S, C")
    (property "ki_keywords" "0402, SMT, CAPACITOR, PASSIVE, CERAMIC, MLCC")
    (attr smd)
    (fp_text reference "C72" (at 17.682 7.825 180) (layer "B.SilkS")
        (effects (font (size 0.7 0.7) (thickness 0.15)) (justify left bottom mirror))
    )
    (fp_text value "C_1u_0402" (at -1.022927 -2.155213 180) (layer "B.Fab")
        (effects (font (size 0.7 0.7) (thickness 0.15)) (justify left bottom mirror))
    )
    (fp_text user "Author: Antmicro" (at -0.939 -3.399 180) (layer "B.Fab") hide
        (effects (font (size 0.7 0.7) (thickness 0.15)) (justify left bottom mirror))
    )
    (fp_text user "${REFERENCE}" (at -0.939 -4.599 180) (layer "B.Fab") hide
        (effects (font (size 0.7 0.7) (thickness 0.15)) (justify left bottom mirror))
    )
    (fp_text user "License: Apache-2.0" (at -0.939 -5.799 180) (layer "B.Fab") hide
        (effects (font (size 0.7 0.7) (thickness 0.15)) (justify left bottom mirror))
    )
    (fp_rect (start -0.925 0.47) (end 0.925 -0.47)
      (stroke (width 0.05) (type default)) (fill none) (layer "B.CrtYd"))
    (fp_line (start -0.494 -0.248) (end -0.494 0.25)
      (stroke (width 0.15) (type solid)) (layer "B.Fab"))
    (fp_line (start -0.494 0.25) (end 0.504 0.25)
      (stroke (width 0.15) (type solid)) (layer "B.Fab"))
    (fp_line (start 0.504 -0.248) (end -0.494 -0.248)
      (stroke (width 0.15) (type solid)) (layer "B.Fab"))
    (fp_line (start 0.504 0.25) (end 0.504 -0.248)
      (stroke (width 0.15) (type solid)) (layer "B.Fab"))
    (pad "1" smd roundrect (at -0.48 0) (size 0.59 0.64) (layers "B.Cu" "B.Paste" "B.Mask") (roundrect_rratio 0.25)
      (net 1 "GND") (pintype "passive"))
    (pad "2" smd roundrect (at 0.48 0) (size 0.59 0.64) (layers "B.Cu" "B.Paste" "B.Mask") (roundrect_rratio 0.25)
      (net 2 "3V3_SYS") (pintype "passive"))
  )

  (footprint "antmicro-footprints:NetTie-2_SMD_Pad0.127mm" (layer "B.Cu")
    (at 116.16 86.95 135)
    (descr "Net tie, 2 pin, 0.127mm  SMD pads")
    (tags "net tie")
    (property "Author" "Antmicro")
    (property "License" "Apache-2.0")
    (property "MPN" "")
    (property "Manufacturer" "")
    (property "Sheetfile" "power.kicad_sch")
    (property "Sheetname" "Power")
    (property "exclude_from_bom" "")
    (property "ki_description" "Net tie, 2 pins")
    (attr through_hole exclude_from_pos_files exclude_from_bom)
    (net_tie_pad_groups "1, 2")
    (fp_text reference "TP11" (at -0.128 1.345 135) (layer "B.SilkS") hide
        (effects (font (size 0.7 0.7) (thickness 0.15)) (justify right bottom mirror))
    )
    (fp_text value "Net-Tie_P0.127mm" (at 0 -1.199 135) (layer "B.Fab")
        (effects (font (size 0.7 0.7) (thickness 0.15)) (justify right bottom mirror))
    )
    (fp_text user "License: Apache-2.0" (at -0.128 -5.6 135) (layer "B.Fab") hide
        (effects (font (size 0.7 0.7) (thickness 0.15)) (justify right bottom mirror))
    )
    (fp_text user "${REFERENCE}" (at -0.128 -3.2 135) (layer "B.Fab") hide
        (effects (font (size 0.7 0.7) (thickness 0.15)) (justify right bottom mirror))
    )
    (fp_text user "Author: Antmicro" (at -0.128 -4.4 135) (layer "B.Fab") hide
        (effects (font (size 0.7 0.7) (thickness 0.15)) (justify right bottom mirror))
    )
    (fp_poly
      (pts
        (xy -0.0635 0.0635)
        (xy 0.0625 0.0635)
        (xy 0.0625 -0.0635)
        (xy -0.0635 -0.0635)
      )

      (stroke (width 0) (type solid)) (fill solid) (layer "B.Cu"))
    (fp_poly
      (pts
        (xy 0.2 0.16)
        (xy 0.29 0.07)
        (xy 0.29 -0.07)
        (xy 0.2 -0.16)
        (xy -0.2 -0.16)
        (xy -0.29 -0.07)
        (xy -0.29 0.06)
        (xy -0.19 0.16)
      )

      (stroke (width 0.05) (type solid)) (fill none) (layer "B.CrtYd"))
    (pad "1" smd roundrect (at -0.127 0 315) (size 0.127 0.127) (layers "B.Cu") (roundrect_rratio 0.5)
      (chamfer_ratio 0) (chamfer top_left bottom_left)
      (net 60 "12V0_DCDC") (pinfunction "1") (pintype "passive"))
    (pad "2" smd roundrect (at 0.126 0 135) (size 0.127 0.127) (layers "B.Cu") (roundrect_rratio 0.5)
      (chamfer_ratio 0) (chamfer top_left bottom_left)
      (net 85 "/Power/I_SENSE_N") (pinfunction "2") (pintype "passive"))
  )

  (footprint "antmicro-footprints:R_0402_1005Metric" (layer "B.Cu")
    (at 145.62 75.96 180)
    (descr "Resistor SMD 0402")
    (tags "resistor SMD 0402")
    (property "Author" "Antmicro")
    (property "License" "Apache-2.0")
    (property "MPN" "CR0402-FX-1004GLF")
    (property "Manufacturer" "Bourns")
    (property "Sheetfile" "tb.kicad_sch")
    (property "Sheetname" "TB Controller")
    (property "Tolerance" "1%")
    (property "Val" "1M")
    (property "ki_description" "SMD Chip Resistor, 1 Mohm, ± 1%, 62.5 mW, 0402 [1005 Metric], Thick Film, General Purpose")
    (property "ki_keywords" "0402, SMT, RESISTOR, PASSIVE")
    (attr smd)
    (fp_text reference "R71" (at -3.097 -0.367) (layer "B.SilkS")
        (effects (font (size 0.7 0.7) (thickness 0.15)) (justify left bottom mirror))
    )
    (fp_text value "R_1M_0402" (at -1.011843 -1.772047) (layer "B.Fab")
        (effects (font (size 0.7 0.7) (thickness 0.15)) (justify left bottom mirror))
    )
    (fp_text user "License: Apache-2.0" (at -0.95 -5.169) (layer "B.Fab") hide
        (effects (font (size 0.7 0.7) (thickness 0.15)) (justify left bottom mirror))
    )
    (fp_text user "Author: Antmicro" (at -0.95 -4.169) (layer "B.Fab") hide
        (effects (font (size 0.7 0.7) (thickness 0.15)) (justify left bottom mirror))
    )
    (fp_text user "${REFERENCE}" (at -0.95 -3.168) (layer "B.Fab") hide
        (effects (font (size 0.7 0.7) (thickness 0.15)) (justify left bottom mirror))
    )
    (fp_rect (start -0.925 0.47) (end 0.925 -0.47)
      (stroke (width 0.05) (type default)) (fill none) (layer "B.CrtYd"))
    (fp_rect (start -0.5 0.25) (end 0.5 -0.25)
      (stroke (width 0.15) (type solid)) (fill none) (layer "B.Fab"))
    (pad "1" smd roundrect (at -0.48 0 180) (size 0.59 0.64) (layers "B.Cu" "B.Paste" "B.Mask") (roundrect_rratio 0.25)
      (net 186 "Net-(U4E-PB_LSRX)") (pintype "passive"))
    (pad "2" smd roundrect (at 0.48 0 180) (size 0.59 0.64) (layers "B.Cu" "B.Paste" "B.Mask") (roundrect_rratio 0.25)
      (net 1 "GND") (pintype "passive"))
  )

  (footprint "antmicro-footprints:R_0402_1005Metric" (layer "B.Cu")
    (at 103.69 88.425 -90)
    (descr "Resistor SMD 0402")
    (tags "resistor SMD 0402")
    (property "Author" "Antmicro")
    (property "License" "Apache-2.0")
    (property "MPN" "CR0402-FX-1002GLF")
    (property "Manufacturer" "Bourns")
    (property "Sheetfile" "power.kicad_sch")
    (property "Sheetname" "Power")
    (property "Tolerance" "1%")
    (property "Val" "10k")
    (property "ki_description" "SMD Chip Resistor, 10 kohm, ± 1%, 62.5 mW, 0402 [1005 Metric], Thick Film, General Purpose")
    (property "ki_keywords" "0402, SMT, RESISTOR, PASSIVE")
    (attr smd)
    (fp_text reference "R91" (at -3.081 -0.45 90) (layer "B.SilkS")
        (effects (font (size 0.7 0.7) (thickness 0.15)) (justify left bottom mirror))
    )
    (fp_text value "R_10k_0402" (at -1.011843 -1.772047 90) (layer "B.Fab")
        (effects (font (size 0.7 0.7) (thickness 0.15)) (justify left bottom mirror))
    )
    (fp_text user "${REFERENCE}" (at -0.95 -3.168 90) (layer "B.Fab") hide
        (effects (font (size 0.7 0.7) (thickness 0.15)) (justify left bottom mirror))
    )
    (fp_text user "License: Apache-2.0" (at -0.95 -5.169 90) (layer "B.Fab") hide
        (effects (font (size 0.7 0.7) (thickness 0.15)) (justify left bottom mirror))
    )
    (fp_text user "Author: Antmicro" (at -0.95 -4.169 90) (layer "B.Fab") hide
        (effects (font (size 0.7 0.7) (thickness 0.15)) (justify left bottom mirror))
    )
    (fp_rect (start -0.925 0.47) (end 0.925 -0.47)
      (stroke (width 0.05) (type default)) (fill none) (layer "B.CrtYd"))
    (fp_rect (start -0.5 0.25) (end 0.5 -0.25)
      (stroke (width 0.15) (type solid)) (fill none) (layer "B.Fab"))
    (pad "1" smd roundrect (at -0.48 0 270) (size 0.59 0.64) (layers "B.Cu" "B.Paste" "B.Mask") (roundrect_rratio 0.25)
      (net 61 "12V0_MOLEX") (pintype "passive"))
    (pad "2" smd roundrect (at 0.48 0 270) (size 0.59 0.64) (layers "B.Cu" "B.Paste" "B.Mask") (roundrect_rratio 0.25)
      (net 140 "Net-(Q2-B)") (pintype "passive"))
  )

  (footprint "antmicro-footprints:C_0402_1005Metric" (layer "B.Cu")
    (at 132.85 79.85 180)
    (descr "Capacitor SMD 0402")
    (tags "capacitor SMD 0402")
    (property "Author" "Antmicro")
    (property "Dielectric" "")
    (property "License" "Apache-2.0")
    (property "MPN" "C1005X6S1A105K050BC")
    (property "Manufacturer" "TDK")
    (property "Sheetfile" "tb-power.kicad_sch")
    (property "Sheetname" "Thunderbolt Controller - Power")
    (property "Val" "1u")
    (property "Voltage" "")
    (property "ki_description" "SMD Multilayer Ceramic Capacitor, 1 µF, 10 V, 0402 [1005 Metric], ± 10%, X6S, C")
    (property "ki_keywords" "0402, SMT, CAPACITOR, PASSIVE, CERAMIC, MLCC")
    (attr smd)
    (fp_text reference "C53" (at -17.518 -7.653) (layer "B.SilkS")
        (effects (font (size 0.7 0.7) (thickness 0.15)) (justify left bottom mirror))
    )
    (fp_text value "C_1u_0402" (at -1.022927 -2.155213) (layer "B.Fab")
        (effects (font (size 0.7 0.7) (thickness 0.15)) (justify left bottom mirror))
    )
    (fp_text user "${REFERENCE}" (at -0.939 -4.599) (layer "B.Fab") hide
        (effects (font (size 0.7 0.7) (thickness 0.15)) (justify left bottom mirror))
    )
    (fp_text user "License: Apache-2.0" (at -0.939 -5.799) (layer "B.Fab") hide
        (effects (font (size 0.7 0.7) (thickness 0.15)) (justify left bottom mirror))
    )
    (fp_text user "Author: Antmicro" (at -0.939 -3.399) (layer "B.Fab") hide
        (effects (font (size 0.7 0.7) (thickness 0.15)) (justify left bottom mirror))
    )
    (fp_rect (start -0.925 0.47) (end 0.925 -0.47)
      (stroke (width 0.05) (type default)) (fill none) (layer "B.CrtYd"))
    (fp_line (start -0.494 -0.248) (end -0.494 0.25)
      (stroke (width 0.15) (type solid)) (layer "B.Fab"))
    (fp_line (start -0.494 0.25) (end 0.504 0.25)
      (stroke (width 0.15) (type solid)) (layer "B.Fab"))
    (fp_line (start 0.504 -0.248) (end -0.494 -0.248)
      (stroke (width 0.15) (type solid)) (layer "B.Fab"))
    (fp_line (start 0.504 0.25) (end 0.504 -0.248)
      (stroke (width 0.15) (type solid)) (layer "B.Fab"))
    (pad "1" smd roundrect (at -0.48 0 180) (size 0.59 0.64) (layers "B.Cu" "B.Paste" "B.Mask") (roundrect_rratio 0.25)
      (net 1 "GND") (pintype "passive"))
    (pad "2" smd roundrect (at 0.48 0 180) (size 0.59 0.64) (layers "B.Cu" "B.Paste" "B.Mask") (roundrect_rratio 0.25)
      (net 106 "Net-(C53-Pad2)") (pintype "passive"))
  )

  (footprint "antmicro-footprints:C_0402_1005Metric" (layer "B.Cu")
    (at 159.91 59.47 -90)
    (descr "Capacitor SMD 0402")
    (tags "capacitor SMD 0402")
    (property "Author" "Antmicro")
    (property "Dielectric" "X5S")
    (property "License" "Apache-2.0")
    (property "MPN" "GRM155C61E475ME15J")
    (property "Manufacturer" "Murata")
    (property "Sheetfile" "power.kicad_sch")
    (property "Sheetname" "Power")
    (property "Val" "4u7")
    (property "Voltage" "25V")
    (property "dnp" "")
    (property "ki_description" "SMD Multilayer Ceramic Capacitor")
    (property "ki_keywords" "0402, SMT, CAPACITOR, PASSIVE, CERAMIC")
    (attr smd)
    (fp_text reference "C21" (at -3.082 -0.364 90) (layer "B.SilkS")
        (effects (font (size 0.7 0.7) (thickness 0.15)) (justify left bottom mirror))
    )
    (fp_text value "C_4u7_25V_0402" (at -1.022927 -2.155213 90) (layer "B.Fab")
        (effects (font (size 0.7 0.7) (thickness 0.15)) (justify left bottom mirror))
    )
    (fp_text user "License: Apache-2.0" (at -0.939 -5.799 90) (layer "B.Fab") hide
        (effects (font (size 0.7 0.7) (thickness 0.15)) (justify left bottom mirror))
    )
    (fp_text user "${REFERENCE}" (at -0.939 -4.599 90) (layer "B.Fab") hide
        (effects (font (size 0.7 0.7) (thickness 0.15)) (justify left bottom mirror))
    )
    (fp_text user "Author: Antmicro" (at -0.939 -3.399 90) (layer "B.Fab") hide
        (effects (font (size 0.7 0.7) (thickness 0.15)) (justify left bottom mirror))
    )
    (fp_rect (start -0.925 0.47) (end 0.925 -0.47)
      (stroke (width 0.05) (type default)) (fill none) (layer "B.CrtYd"))
    (fp_line (start -0.494 -0.248) (end -0.494 0.25)
      (stroke (width 0.15) (type solid)) (layer "B.Fab"))
    (fp_line (start -0.494 0.25) (end 0.504 0.25)
      (stroke (width 0.15) (type solid)) (layer "B.Fab"))
    (fp_line (start 0.504 -0.248) (end -0.494 -0.248)
      (stroke (width 0.15) (type solid)) (layer "B.Fab"))
    (fp_line (start 0.504 0.25) (end 0.504 -0.248)
      (stroke (width 0.15) (type solid)) (layer "B.Fab"))
    (pad "1" smd roundrect (at -0.48 0 270) (size 0.59 0.64) (layers "B.Cu" "B.Paste" "B.Mask") (roundrect_rratio 0.25)
      (net 1 "GND") (pintype "passive"))
    (pad "2" smd roundrect (at 0.48 0 270) (size 0.59 0.64) (layers "B.Cu" "B.Paste" "B.Mask") (roundrect_rratio 0.25)
      (net 20 "PP_5V0") (pintype "passive"))
  )

  (footprint "antmicro-footprints:R_0402_1005Metric" (layer "B.Cu")
    (at 141.15 78.39 -90)
    (descr "Resistor SMD 0402")
    (tags "resistor SMD 0402")
    (property "Author" "Antmicro")
    (property "License" "Apache-2.0")
    (property "MPN" "CR0402-FX-4990GLF")
    (property "Manufacturer" "Bourns")
    (property "Sheetfile" "tb.kicad_sch")
    (property "Sheetname" "TB Controller")
    (property "Tolerance" "1%")
    (property "Val" "499R")
    (property "ki_description" "SMD Chip Resistor, 499 ohm, ± 1%, 63 mW, 0402 [1005 Metric], Thick Film, General Purpose")
    (property "ki_keywords" "0402, SMT, RESISTOR, PASSIVE")
    (attr smd)
    (fp_text reference "R68" (at 0.985 -0.455 90) (layer "B.SilkS")
        (effects (font (size 0.7 0.7) (thickness 0.15)) (justify left bottom mirror))
    )
    (fp_text value "R_499R_0402" (at -1.011843 -1.772047 90) (layer "B.Fab")
        (effects (font (size 0.7 0.7) (thickness 0.15)) (justify left bottom mirror))
    )
    (fp_text user "Author: Antmicro" (at -0.95 -4.169 90) (layer "B.Fab") hide
        (effects (font (size 0.7 0.7) (thickness 0.15)) (justify left bottom mirror))
    )
    (fp_text user "License: Apache-2.0" (at -0.95 -5.169 90) (layer "B.Fab") hide
        (effects (font (size 0.7 0.7) (thickness 0.15)) (justify left bottom mirror))
    )
    (fp_text user "${REFERENCE}" (at -0.95 -3.168 90) (layer "B.Fab") hide
        (effects (font (size 0.7 0.7) (thickness 0.15)) (justify left bottom mirror))
    )
    (fp_rect (start -0.925 0.47) (end 0.925 -0.47)
      (stroke (width 0.05) (type default)) (fill none) (layer "B.CrtYd"))
    (fp_rect (start -0.5 0.25) (end 0.5 -0.25)
      (stroke (width 0.15) (type solid)) (fill none) (layer "B.Fab"))
    (pad "1" smd roundrect (at -0.48 0 270) (size 0.59 0.64) (layers "B.Cu" "B.Paste" "B.Mask") (roundrect_rratio 0.25)
      (net 1 "GND") (pintype "passive"))
    (pad "2" smd roundrect (at 0.48 0 270) (size 0.59 0.64) (layers "B.Cu" "B.Paste" "B.Mask") (roundrect_rratio 0.25)
      (net 182 "Net-(U4E-PA_USB2_RBIAS)") (pintype "passive"))
  )

  (footprint "antmicro-footprints:R_0402_1005Metric" (layer "B.Cu")
    (at 133.125 66.82 -90)
    (descr "Resistor SMD 0402")
    (tags "resistor SMD 0402")
    (property "Author" "Antmicro")
    (property "License" "Apache-2.0")
    (property "MPN" "CR0402-FX-2201GLF")
    (property "Manufacturer" "Bourns")
    (property "Sheetfile" "tb.kicad_sch")
    (property "Sheetname" "TB Controller")
    (property "Tolerance" "1%")
    (property "Val" "2k2")
    (property "ki_description" "SMD Chip Resistor, 2.2 kohm, ± 1%, 62.5 mW, 0402 [1005 Metric], Thick Film, General Purpose")
    (property "ki_keywords" "0402, SMT, RESISTOR, PASSIVE")
    (attr smd)
    (fp_text reference "R61" (at -3.066 -0.325 90) (layer "B.SilkS")
        (effects (font (size 0.7 0.7) (thickness 0.15)) (justify left bottom mirror))
    )
    (fp_text value "R_2k2_0402" (at -1.011843 -1.772047 90) (layer "B.Fab")
        (effects (font (size 0.7 0.7) (thickness 0.15)) (justify left bottom mirror))
    )
    (fp_text user "${REFERENCE}" (at -0.95 -3.168 90) (layer "B.Fab") hide
        (effects (font (size 0.7 0.7) (thickness 0.15)) (justify left bottom mirror))
    )
    (fp_text user "License: Apache-2.0" (at -0.95 -5.169 90) (layer "B.Fab") hide
        (effects (font (size 0.7 0.7) (thickness 0.15)) (justify left bottom mirror))
    )
    (fp_text user "Author: Antmicro" (at -0.95 -4.169 90) (layer "B.Fab") hide
        (effects (font (size 0.7 0.7) (thickness 0.15)) (justify left bottom mirror))
    )
    (fp_rect (start -0.925 0.47) (end 0.925 -0.47)
      (stroke (width 0.05) (type default)) (fill none) (layer "B.CrtYd"))
    (fp_rect (start -0.5 0.25) (end 0.5 -0.25)
      (stroke (width 0.15) (type solid)) (fill none) (layer "B.Fab"))
    (pad "1" smd roundrect (at -0.48 0 270) (size 0.59 0.64) (layers "B.Cu" "B.Paste" "B.Mask") (roundrect_rratio 0.25)
      (net 1 "GND") (pintype "passive"))
    (pad "2" smd roundrect (at 0.48 0 270) (size 0.59 0.64) (layers "B.Cu" "B.Paste" "B.Mask") (roundrect_rratio 0.25)
      (net 175 "Net-(U4C-DPSNK1_DDC_CLK)") (pintype "passive"))
  )

  (footprint "antmicro-footprints:C_0402_1005Metric" (layer "B.Cu")
    (at 153.41 61.97 180)
    (descr "Capacitor SMD 0402")
    (tags "capacitor SMD 0402")
    (property "Author" "Antmicro")
    (property "Dielectric" "")
    (property "License" "Apache-2.0")
    (property "MPN" "C1005X5R1A225K050BC")
    (property "Manufacturer" "TDK")
    (property "Sheetfile" "power.kicad_sch")
    (property "Sheetname" "Power")
    (property "Val" "2u2")
    (property "Voltage" "")
    (property "ki_description" "SMD Multilayer Ceramic Capacitor, 2.2 µF, 10 V, 0402 [1005 Metric], ± 10%, X5R, C")
    (property "ki_keywords" "0402, SMT, CAPACITOR, PASSIVE, CERAMIC, MLCC")
    (attr smd)
    (fp_text reference "C37" (at -0.768 -4.451) (layer "B.SilkS")
        (effects (font (size 0.7 0.7) (thickness 0.15)) (justify left bottom mirror))
    )
    (fp_text value "C_2u2_0402" (at -1.022927 -2.155213) (layer "B.Fab")
        (effects (font (size 0.7 0.7) (thickness 0.15)) (justify left bottom mirror))
    )
    (fp_text user "License: Apache-2.0" (at -0.939 -5.799) (layer "B.Fab") hide
        (effects (font (size 0.7 0.7) (thickness 0.15)) (justify left bottom mirror))
    )
    (fp_text user "Author: Antmicro" (at -0.939 -3.399) (layer "B.Fab") hide
        (effects (font (size 0.7 0.7) (thickness 0.15)) (justify left bottom mirror))
    )
    (fp_text user "${REFERENCE}" (at -0.939 -4.599) (layer "B.Fab") hide
        (effects (font (size 0.7 0.7) (thickness 0.15)) (justify left bottom mirror))
    )
    (fp_rect (start -0.925 0.47) (end 0.925 -0.47)
      (stroke (width 0.05) (type default)) (fill none) (layer "B.CrtYd"))
    (fp_line (start -0.494 -0.248) (end -0.494 0.25)
      (stroke (width 0.15) (type solid)) (layer "B.Fab"))
    (fp_line (start -0.494 0.25) (end 0.504 0.25)
      (stroke (width 0.15) (type solid)) (layer "B.Fab"))
    (fp_line (start 0.504 -0.248) (end -0.494 -0.248)
      (stroke (width 0.15) (type solid)) (layer "B.Fab"))
    (fp_line (start 0.504 0.25) (end 0.504 -0.248)
      (stroke (width 0.15) (type solid)) (layer "B.Fab"))
    (pad "1" smd roundrect (at -0.48 0 180) (size 0.59 0.64) (layers "B.Cu" "B.Paste" "B.Mask") (roundrect_rratio 0.25)
      (net 104 "Net-(U3-LDO_BMC)") (pintype "passive"))
    (pad "2" smd roundrect (at 0.48 0 180) (size 0.59 0.64) (layers "B.Cu" "B.Paste" "B.Mask") (roundrect_rratio 0.25)
      (net 1 "GND") (pintype "passive"))
  )

  (footprint "antmicro-footprints:R_0402_1005Metric" (layer "B.Cu")
    (at 151.41 59.97)
    (descr "Resistor SMD 0402")
    (tags "resistor SMD 0402")
    (property "Author" "Antmicro")
    (property "License" "Apache-2.0")
    (property "MPN" "CR0402-FX-1002GLF")
    (property "Manufacturer" "Bourns")
    (property "Sheetfile" "power.kicad_sch")
    (property "Sheetname" "Power")
    (property "Tolerance" "1%")
    (property "Val" "10k")
    (property "ki_description" "SMD Chip Resistor, 10 kohm, ± 1%, 62.5 mW, 0402 [1005 Metric], Thick Film, General Purpose")
    (property "ki_keywords" "0402, SMT, RESISTOR, PASSIVE")
    (attr smd)
    (fp_text reference "R2" (at -0.915 0.482 180) (layer "B.SilkS")
        (effects (font (size 0.7 0.7) (thickness 0.15)) (justify left bottom mirror))
    )
    (fp_text value "R_10k_0402" (at -1.011843 -1.772047 180) (layer "B.Fab")
        (effects (font (size 0.7 0.7) (thickness 0.15)) (justify left bottom mirror))
    )
    (fp_text user "${REFERENCE}" (at -0.95 -3.168 180) (layer "B.Fab") hide
        (effects (font (size 0.7 0.7) (thickness 0.15)) (justify left bottom mirror))
    )
    (fp_text user "Author: Antmicro" (at -0.95 -4.169 180) (layer "B.Fab") hide
        (effects (font (size 0.7 0.7) (thickness 0.15)) (justify left bottom mirror))
    )
    (fp_text user "License: Apache-2.0" (at -0.95 -5.169 180) (layer "B.Fab") hide
        (effects (font (size 0.7 0.7) (thickness 0.15)) (justify left bottom mirror))
    )
    (fp_rect (start -0.925 0.47) (end 0.925 -0.47)
      (stroke (width 0.05) (type default)) (fill none) (layer "B.CrtYd"))
    (fp_rect (start -0.5 0.25) (end 0.5 -0.25)
      (stroke (width 0.15) (type solid)) (fill none) (layer "B.Fab"))
    (pad "1" smd roundrect (at -0.48 0) (size 0.59 0.64) (layers "B.Cu" "B.Paste" "B.Mask") (roundrect_rratio 0.25)
      (net 56 "I2C1_IRQ") (pintype "passive"))
    (pad "2" smd roundrect (at 0.48 0) (size 0.59 0.64) (layers "B.Cu" "B.Paste" "B.Mask") (roundrect_rratio 0.25)
      (net 2 "3V3_SYS") (pintype "passive"))
  )

  (footprint "antmicro-footprints:C_0402_1005Metric" (layer "B.Cu")
    (at 111.725 80.65)
    (descr "Capacitor SMD 0402")
    (tags "capacitor SMD 0402")
    (property "Author" "Antmicro")
    (property "Dielectric" "X5R")
    (property "License" "Apache-2.0")
    (property "MPN" "GRM155R61H104KE14D")
    (property "Manufacturer" "Murata")
    (property "Sheetfile" "power.kicad_sch")
    (property "Sheetname" "Power")
    (property "Val" "100n")
    (property "Voltage" "50V")
    (property "ki_description" "SMD Multilayer Ceramic Capacitor, 0.1 µF, 50 V, 0402 [1005 Metric], ± 10%, X5R, GRM Series")
    (property "ki_keywords" "0402, SMT, CAPACITOR, PASSIVE, CERAMIC, MLCC")
    (attr smd)
    (fp_text reference "C32" (at 1.051 -4.704 180) (layer "B.SilkS")
        (effects (font (size 0.7 0.7) (thickness 0.15)) (justify left bottom mirror))
    )
    (fp_text value "C_100n_0402" (at -1.022927 -2.155213 180) (layer "B.Fab")
        (effects (font (size 0.7 0.7) (thickness 0.15)) (justify left bottom mirror))
    )
    (fp_text user "Author: Antmicro" (at -0.939 -3.399 180) (layer "B.Fab") hide
        (effects (font (size 0.7 0.7) (thickness 0.15)) (justify left bottom mirror))
    )
    (fp_text user "${REFERENCE}" (at -0.939 -4.599 180) (layer "B.Fab") hide
        (effects (font (size 0.7 0.7) (thickness 0.15)) (justify left bottom mirror))
    )
    (fp_text user "License: Apache-2.0" (at -0.939 -5.799 180) (layer "B.Fab") hide
        (effects (font (size 0.7 0.7) (thickness 0.15)) (justify left bottom mirror))
    )
    (fp_rect (start -0.925 0.47) (end 0.925 -0.47)
      (stroke (width 0.05) (type default)) (fill none) (layer "B.CrtYd"))
    (fp_line (start -0.494 -0.248) (end -0.494 0.25)
      (stroke (width 0.15) (type solid)) (layer "B.Fab"))
    (fp_line (start -0.494 0.25) (end 0.504 0.25)
      (stroke (width 0.15) (type solid)) (layer "B.Fab"))
    (fp_line (start 0.504 -0.248) (end -0.494 -0.248)
      (stroke (width 0.15) (type solid)) (layer "B.Fab"))
    (fp_line (start 0.504 0.25) (end 0.504 -0.248)
      (stroke (width 0.15) (type solid)) (layer "B.Fab"))
    (pad "1" smd roundrect (at -0.48 0) (size 0.59 0.64) (layers "B.Cu" "B.Paste" "B.Mask") (roundrect_rratio 0.25)
      (net 1 "GND") (pintype "passive"))
    (pad "2" smd roundrect (at 0.48 0) (size 0.59 0.64) (layers "B.Cu" "B.Paste" "B.Mask") (roundrect_rratio 0.25)
      (net 75 "Net-(C32-Pad2)") (pintype "passive"))
  )

  (footprint "antmicro-footprints:R_0402_1005Metric" (layer "B.Cu")
    (at 136.2 66.82 -90)
    (descr "Resistor SMD 0402")
    (tags "resistor SMD 0402")
    (property "Author" "Antmicro")
    (property "License" "Apache-2.0")
    (property "MPN" "CR0402-FX-1002GLF")
    (property "Manufacturer" "Bourns")
    (property "Sheetfile" "tb.kicad_sch")
    (property "Sheetname" "TB Controller")
    (property "Tolerance" "1%")
    (property "Val" "10k")
    (property "ki_description" "SMD Chip Resistor, 10 kohm, ± 1%, 62.5 mW, 0402 [1005 Metric], Thick Film, General Purpose")
    (property "ki_keywords" "0402, SMT, RESISTOR, PASSIVE")
    (attr smd)
    (fp_text reference "R66" (at -3.066 -0.325 90) (layer "B.SilkS")
        (effects (font (size 0.7 0.7) (thickness 0.15)) (justify left bottom mirror))
    )
    (fp_text value "R_10k_0402" (at -1.011843 -1.772047 90) (layer "B.Fab")
        (effects (font (size 0.7 0.7) (thickness 0.15)) (justify left bottom mirror))
    )
    (fp_text user "Author: Antmicro" (at -0.95 -4.169 90) (layer "B.Fab") hide
        (effects (font (size 0.7 0.7) (thickness 0.15)) (justify left bottom mirror))
    )
    (fp_text user "License: Apache-2.0" (at -0.95 -5.169 90) (layer "B.Fab") hide
        (effects (font (size 0.7 0.7) (thickness 0.15)) (justify left bottom mirror))
    )
    (fp_text user "${REFERENCE}" (at -0.95 -3.168 90) (layer "B.Fab") hide
        (effects (font (size 0.7 0.7) (thickness 0.15)) (justify left bottom mirror))
    )
    (fp_rect (start -0.925 0.47) (end 0.925 -0.47)
      (stroke (width 0.05) (type default)) (fill none) (layer "B.CrtYd"))
    (fp_rect (start -0.5 0.25) (end 0.5 -0.25)
      (stroke (width 0.15) (type solid)) (fill none) (layer "B.Fab"))
    (pad "1" smd roundrect (at -0.48 0 270) (size 0.59 0.64) (layers "B.Cu" "B.Paste" "B.Mask") (roundrect_rratio 0.25)
      (net 2 "3V3_SYS") (pintype "passive"))
    (pad "2" smd roundrect (at 0.48 0 270) (size 0.59 0.64) (layers "B.Cu" "B.Paste" "B.Mask") (roundrect_rratio 0.25)
      (net 180 "Net-(U4D-TCK)") (pintype "passive"))
  )

  (footprint "antmicro-footprints:R_0402_1005Metric" (layer "B.Cu")
    (at 131.075 70.72 90)
    (descr "Resistor SMD 0402")
    (tags "resistor SMD 0402")
    (property "Author" "Antmicro")
    (property "License" "Apache-2.0")
    (property "MPN" "CR0402-FX-1003GLF")
    (property "Manufacturer" "Bourns")
    (property "Sheetfile" "tb.kicad_sch")
    (property "Sheetname" "TB Controller")
    (property "Tolerance" "1%")
    (property "Val" "100k")
    (property "ki_description" "SMD Chip Resistor, 100 kohm, ± 1%, 62.5 mW, 0402 [1005 Metric], Thick Film, General Purpose")
    (property "ki_keywords" "0402, SMT, RESISTOR, PASSIVE")
    (attr smd)
    (fp_text reference "R81" (at -0.908 0.361 270) (layer "B.SilkS")
        (effects (font (size 0.7 0.7) (thickness 0.15)) (justify left bottom mirror))
    )
    (fp_text value "R_100k_0402" (at -1.011843 -1.772047 270) (layer "B.Fab")
        (effects (font (size 0.7 0.7) (thickness 0.15)) (justify left bottom mirror))
    )
    (fp_text user "Author: Antmicro" (at -0.95 -4.169 270) (layer "B.Fab") hide
        (effects (font (size 0.7 0.7) (thickness 0.15)) (justify left bottom mirror))
    )
    (fp_text user "License: Apache-2.0" (at -0.95 -5.169 270) (layer "B.Fab") hide
        (effects (font (size 0.7 0.7) (thickness 0.15)) (justify left bottom mirror))
    )
    (fp_text user "${REFERENCE}" (at -0.95 -3.168 270) (layer "B.Fab") hide
        (effects (font (size 0.7 0.7) (thickness 0.15)) (justify left bottom mirror))
    )
    (fp_rect (start -0.925 0.47) (end 0.925 -0.47)
      (stroke (width 0.05) (type default)) (fill none) (layer "B.CrtYd"))
    (fp_rect (start -0.5 0.25) (end 0.5 -0.25)
      (stroke (width 0.15) (type solid)) (fill none) (layer "B.Fab"))
    (pad "1" smd roundrect (at -0.48 0 90) (size 0.59 0.64) (layers "B.Cu" "B.Paste" "B.Mask") (roundrect_rratio 0.25)
      (net 196 "Net-(U4C-GPIO_7)") (pintype "passive"))
    (pad "2" smd roundrect (at 0.48 0 90) (size 0.59 0.64) (layers "B.Cu" "B.Paste" "B.Mask") (roundrect_rratio 0.25)
      (net 1 "GND") (pintype "passive"))
  )

  (footprint "antmicro-footprints:R_0402_1005Metric" (layer "B.Cu")
    (at 132.1 66.82 -90)
    (descr "Resistor SMD 0402")
    (tags "resistor SMD 0402")
    (property "Author" "Antmicro")
    (property "License" "Apache-2.0")
    (property "MPN" "CR0402-FX-1002GLF")
    (property "Manufacturer" "Bourns")
    (property "Sheetfile" "tb.kicad_sch")
    (property "Sheetname" "TB Controller")
    (property "Tolerance" "1%")
    (property "Val" "10k")
    (property "ki_description" "SMD Chip Resistor, 10 kohm, ± 1%, 62.5 mW, 0402 [1005 Metric], Thick Film, General Purpose")
    (property "ki_keywords" "0402, SMT, RESISTOR, PASSIVE")
    (attr smd)
    (fp_text reference "R64" (at -3.066 -0.325 90) (layer "B.SilkS")
        (effects (font (size 0.7 0.7) (thickness 0.15)) (justify left bottom mirror))
    )
    (fp_text value "R_10k_0402" (at -1.011843 -1.772047 90) (layer "B.Fab")
        (effects (font (size 0.7 0.7) (thickness 0.15)) (justify left bottom mirror))
    )
    (fp_text user "License: Apache-2.0" (at -0.95 -5.169 90) (layer "B.Fab") hide
        (effects (font (size 0.7 0.7) (thickness 0.15)) (justify left bottom mirror))
    )
    (fp_text user "Author: Antmicro" (at -0.95 -4.169 90) (layer "B.Fab") hide
        (effects (font (size 0.7 0.7) (thickness 0.15)) (justify left bottom mirror))
    )
    (fp_text user "${REFERENCE}" (at -0.95 -3.168 90) (layer "B.Fab") hide
        (effects (font (size 0.7 0.7) (thickness 0.15)) (justify left bottom mirror))
    )
    (fp_rect (start -0.925 0.47) (end 0.925 -0.47)
      (stroke (width 0.05) (type default)) (fill none) (layer "B.CrtYd"))
    (fp_rect (start -0.5 0.25) (end 0.5 -0.25)
      (stroke (width 0.15) (type solid)) (fill none) (layer "B.Fab"))
    (pad "1" smd roundrect (at -0.48 0 270) (size 0.59 0.64) (layers "B.Cu" "B.Paste" "B.Mask") (roundrect_rratio 0.25)
      (net 2 "3V3_SYS") (pintype "passive"))
    (pad "2" smd roundrect (at 0.48 0 270) (size 0.59 0.64) (layers "B.Cu" "B.Paste" "B.Mask") (roundrect_rratio 0.25)
      (net 178 "Net-(U4D-TDI)") (pintype "passive"))
  )

  (footprint "antmicro-footprints:R_0402_1005Metric" (layer "B.Cu")
    (at 136.75 76.925)
    (descr "Resistor SMD 0402")
    (tags "resistor SMD 0402")
    (property "Author" "Antmicro")
    (property "License" "Apache-2.0")
    (property "MPN" "ERJ-H2RD4751X")
    (property "Manufacturer" "Panasonic")
    (property "Sheetfile" "tb.kicad_sch")
    (property "Sheetname" "TB Controller")
    (property "Tolerance" "0.5%")
    (property "Val" "4k75")
    (property "ki_description" "SMD Chip Resistor, 4.75 kohm, ± 0.5%, 100 mW, 0402 [1005 Metric], Thick Film, High Temperature")
    (property "ki_keywords" "0402, SMT, RESISTOR, PASSIVE")
    (attr smd)
    (fp_text reference "R69" (at 17.682 7.657 180) (layer "B.SilkS")
        (effects (font (size 0.7 0.7) (thickness 0.15)) (justify left bottom mirror))
    )
    (fp_text value "R_4k75_0.5%_0402" (at -1.011843 -1.772047 180) (layer "B.Fab")
        (effects (font (size 0.7 0.7) (thickness 0.15)) (justify left bottom mirror))
    )
    (fp_text user "License: Apache-2.0" (at -0.95 -5.169 180) (layer "B.Fab") hide
        (effects (font (size 0.7 0.7) (thickness 0.15)) (justify left bottom mirror))
    )
    (fp_text user "${REFERENCE}" (at -0.95 -3.168 180) (layer "B.Fab") hide
        (effects (font (size 0.7 0.7) (thickness 0.15)) (justify left bottom mirror))
    )
    (fp_text user "Author: Antmicro" (at -0.95 -4.169 180) (layer "B.Fab") hide
        (effects (font (size 0.7 0.7) (thickness 0.15)) (justify left bottom mirror))
    )
    (fp_rect (start -0.925 0.47) (end 0.925 -0.47)
      (stroke (width 0.05) (type default)) (fill none) (layer "B.CrtYd"))
    (fp_rect (start -0.5 0.25) (end 0.5 -0.25)
      (stroke (width 0.15) (type solid)) (fill none) (layer "B.Fab"))
    (pad "1" smd roundrect (at -0.48 0) (size 0.59 0.64) (layers "B.Cu" "B.Paste" "B.Mask") (roundrect_rratio 0.25)
      (net 183 "Net-(U4D-RSENSE)") (pintype "passive"))
    (pad "2" smd roundrect (at 0.48 0) (size 0.59 0.64) (layers "B.Cu" "B.Paste" "B.Mask") (roundrect_rratio 0.25)
      (net 184 "Net-(U4D-RBIAS)") (pintype "passive"))
  )

  (footprint "antmicro-footprints:R_0402_1005Metric" (layer "B.Cu")
    (at 130.7 82.13 180)
    (descr "Resistor SMD 0402")
    (tags "resistor SMD 0402")
    (property "Author" "Antmicro")
    (property "License" "Apache-2.0")
    (property "MPN" "CR0402-FX-3011GLF")
    (property "Manufacturer" "Bourns")
    (property "Sheetfile" "tb.kicad_sch")
    (property "Sheetname" "TB Controller")
    (property "Tolerance" "1%")
    (property "Val" "3k01")
    (property "ki_description" "SMD Chip Resistor, 3.01 kohm, ± 1%, 62.5 mW, 0402 [1005 Metric], Thick Film, General Purpose")
    (property "ki_keywords" "0402, SMT, RESISTOR, PASSIVE")
    (attr smd)
    (fp_text reference "R74" (at -17.509 -7.405) (layer "B.SilkS")
        (effects (font (size 0.7 0.7) (thickness 0.15)) (justify left bottom mirror))
    )
    (fp_text value "R_3k01_0402" (at -1.011843 -1.772047) (layer "B.Fab")
        (effects (font (size 0.7 0.7) (thickness 0.15)) (justify left bottom mirror))
    )
    (fp_text user "Author: Antmicro" (at -0.95 -4.169) (layer "B.Fab") hide
        (effects (font (size 0.7 0.7) (thickness 0.15)) (justify left bottom mirror))
    )
    (fp_text user "${REFERENCE}" (at -0.95 -3.168) (layer "B.Fab") hide
        (effects (font (size 0.7 0.7) (thickness 0.15)) (justify left bottom mirror))
    )
    (fp_text user "License: Apache-2.0" (at -0.95 -5.169) (layer "B.Fab") hide
        (effects (font (size 0.7 0.7) (thickness 0.15)) (justify left bottom mirror))
    )
    (fp_rect (start -0.925 0.47) (end 0.925 -0.47)
      (stroke (width 0.05) (type default)) (fill none) (layer "B.CrtYd"))
    (fp_rect (start -0.5 0.25) (end 0.5 -0.25)
      (stroke (width 0.15) (type solid)) (fill none) (layer "B.Fab"))
    (pad "1" smd roundrect (at -0.48 0 180) (size 0.59 0.64) (layers "B.Cu" "B.Paste" "B.Mask") (roundrect_rratio 0.25)
      (net 189 "Net-(U4B-PCIE_RBIAS)") (pintype "passive"))
    (pad "2" smd roundrect (at 0.48 0 180) (size 0.59 0.64) (layers "B.Cu" "B.Paste" "B.Mask") (roundrect_rratio 0.25)
      (net 1 "GND") (pintype "passive"))
  )

  (footprint "antmicro-footprints:R_0402_1005Metric" (layer "B.Cu")
    (at 107.425 81.15 90)
    (descr "Resistor SMD 0402")
    (tags "resistor SMD 0402")
    (property "Author" "Antmicro")
    (property "License" "Apache-2.0")
    (property "MPN" "CR0402-FX-2402GLF")
    (property "Manufacturer" "Bourns")
    (property "Sheetfile" "power.kicad_sch")
    (property "Sheetname" "Power")
    (property "Tolerance" "1%")
    (property "Val" "24k")
    (property "ki_description" "SMD Chip Resistor, 24 kohm, ± 1%, 100 mW, 0402 [1005 Metric], Thick Film, Precision")
    (property "ki_keywords" "0402, SMT, RESISTOR, PASSIVE")
    (attr smd)
    (fp_text reference "R7" (at 0.632 -0.745 270) (layer "B.SilkS")
        (effects (font (size 0.7 0.7) (thickness 0.15)) (justify left bottom mirror))
    )
    (fp_text value "R_24k_0402" (at -1.011843 -1.772047 270) (layer "B.Fab")
        (effects (font (size 0.7 0.7) (thickness 0.15)) (justify left bottom mirror))
    )
    (fp_text user "Author: Antmicro" (at -0.95 -4.169 270) (layer "B.Fab") hide
        (effects (font (size 0.7 0.7) (thickness 0.15)) (justify left bottom mirror))
    )
    (fp_text user "${REFERENCE}" (at -0.95 -3.168 270) (layer "B.Fab") hide
        (effects (font (size 0.7 0.7) (thickness 0.15)) (justify left bottom mirror))
    )
    (fp_text user "License: Apache-2.0" (at -0.95 -5.169 270) (layer "B.Fab") hide
        (effects (font (size 0.7 0.7) (thickness 0.15)) (justify left bottom mirror))
    )
    (fp_rect (start -0.925 0.47) (end 0.925 -0.47)
      (stroke (width 0.05) (type default)) (fill none) (layer "B.CrtYd"))
    (fp_rect (start -0.5 0.25) (end 0.5 -0.25)
      (stroke (width 0.15) (type solid)) (fill none) (layer "B.Fab"))
    (pad "1" smd roundrect (at -0.48 0 90) (size 0.59 0.64) (layers "B.Cu" "B.Paste" "B.Mask") (roundrect_rratio 0.25)
      (net 88 "/Power/DCDC_EN") (pintype "passive"))
    (pad "2" smd roundrect (at 0.48 0 90) (size 0.59 0.64) (layers "B.Cu" "B.Paste" "B.Mask") (roundrect_rratio 0.25)
      (net 74 "Net-(C10-Pad2)") (pintype "passive"))
  )

  (footprint "antmicro-footprints:R_0402_1005Metric" (layer "B.Cu")
    (at 158.91 59.47 -90)
    (descr "Resistor SMD 0402")
    (tags "resistor SMD 0402")
    (property "Author" "Antmicro")
    (property "License" "Apache-2.0")
    (property "MPN" "CR0402-FX-1002GLF")
    (property "Manufacturer" "Bourns")
    (property "Sheetfile" "power.kicad_sch")
    (property "Sheetname" "Power")
    (property "Tolerance" "1%")
    (property "Val" "10k")
    (property "ki_description" "SMD Chip Resistor, 10 kohm, ± 1%, 62.5 mW, 0402 [1005 Metric], Thick Film, General Purpose")
    (property "ki_keywords" "0402, SMT, RESISTOR, PASSIVE")
    (attr smd)
    (fp_text reference "R20" (at -3.082 -0.348 90) (layer "B.SilkS")
        (effects (font (size 0.7 0.7) (thickness 0.15)) (justify left bottom mirror))
    )
    (fp_text value "R_10k_0402" (at -1.011843 -1.772047 90) (layer "B.Fab")
        (effects (font (size 0.7 0.7) (thickness 0.15)) (justify left bottom mirror))
    )
    (fp_text user "${REFERENCE}" (at -0.95 -3.168 90) (layer "B.Fab") hide
        (effects (font (size 0.7 0.7) (thickness 0.15)) (justify left bottom mirror))
    )
    (fp_text user "Author: Antmicro" (at -0.95 -4.169 90) (layer "B.Fab") hide
        (effects (font (size 0.7 0.7) (thickness 0.15)) (justify left bottom mirror))
    )
    (fp_text user "License: Apache-2.0" (at -0.95 -5.169 90) (layer "B.Fab") hide
        (effects (font (size 0.7 0.7) (thickness 0.15)) (justify left bottom mirror))
    )
    (fp_rect (start -0.925 0.47) (end 0.925 -0.47)
      (stroke (width 0.05) (type default)) (fill none) (layer "B.CrtYd"))
    (fp_rect (start -0.5 0.25) (end 0.5 -0.25)
      (stroke (width 0.15) (type solid)) (fill none) (layer "B.Fab"))
    (pad "1" smd roundrect (at -0.48 0 270) (size 0.59 0.64) (layers "B.Cu" "B.Paste" "B.Mask") (roundrect_rratio 0.25)
      (net 9 "/Power/TPS_3V3") (pintype "passive"))
    (pad "2" smd roundrect (at 0.48 0 270) (size 0.59 0.64) (layers "B.Cu" "B.Paste" "B.Mask") (roundrect_rratio 0.25)
      (net 155 "Net-(U3-GPIO7)") (pintype "passive"))
  )

  (footprint "antmicro-footprints:R_0402_1005Metric" (layer "B.Cu")
    (at 135.115 61.665)
    (descr "Resistor SMD 0402")
    (tags "resistor SMD 0402")
    (property "Author" "Antmicro")
    (property "License" "Apache-2.0")
    (property "MPN" "CR0402-FX-3301GLF")
    (property "Manufacturer" "Bourns")
    (property "Sheetfile" "tb.kicad_sch")
    (property "Sheetname" "TB Controller")
    (property "Tolerance" "1%")
    (property "Val" "3k3")
    (property "ki_description" "SMD Chip Resistor, 3.3 kohm, ± 1%, 63 mW, 0402 [1005 Metric], Thick Film, General Purpose")
    (property "ki_keywords" "0402, SMT, RESISTOR, PASSIVE")
    (attr smd)
    (fp_text reference "R50" (at -1.003 0.311 180) (layer "B.SilkS")
        (effects (font (size 0.7 0.7) (thickness 0.15)) (justify left bottom mirror))
    )
    (fp_text value "R_3k3_0402" (at -1.011843 -1.772047 180) (layer "B.Fab")
        (effects (font (size 0.7 0.7) (thickness 0.15)) (justify left bottom mirror))
    )
    (fp_text user "Author: Antmicro" (at -0.95 -4.169 180) (layer "B.Fab") hide
        (effects (font (size 0.7 0.7) (thickness 0.15)) (justify left bottom mirror))
    )
    (fp_text user "License: Apache-2.0" (at -0.95 -5.169 180) (layer "B.Fab") hide
        (effects (font (size 0.7 0.7) (thickness 0.15)) (justify left bottom mirror))
    )
    (fp_text user "${REFERENCE}" (at -0.95 -3.168 180) (layer "B.Fab") hide
        (effects (font (size 0.7 0.7) (thickness 0.15)) (justify left bottom mirror))
    )
    (fp_rect (start -0.925 0.47) (end 0.925 -0.47)
      (stroke (width 0.05) (type default)) (fill none) (layer "B.CrtYd"))
    (fp_rect (start -0.5 0.25) (end 0.5 -0.25)
      (stroke (width 0.15) (type solid)) (fill none) (layer "B.Fab"))
    (pad "1" smd roundrect (at -0.48 0) (size 0.59 0.64) (layers "B.Cu" "B.Paste" "B.Mask") (roundrect_rratio 0.25)
      (net 63 "SPI_MISO") (pintype "passive"))
    (pad "2" smd roundrect (at 0.48 0) (size 0.59 0.64) (layers "B.Cu" "B.Paste" "B.Mask") (roundrect_rratio 0.25)
      (net 2 "3V3_SYS") (pintype "passive"))
  )

  (footprint "antmicro-footprints:Fiducial_1mm_Mask3mm" (layer "B.Cu")
    (at 108.7 52 180)
    (descr "Circular Fiducial, 1.5mm bare copper, 3mm soldermask opening")
    (tags "fiducial")
    (property "Author" "Antmicro")
    (property "License" "Apache-2.0")
    (property "Sheetfile" "thunderbolt-pcie-adapter.kicad_sch")
    (property "Sheetname" "")
    (property "exclude_from_bom" "")
    (property "ki_description" "Fiducial mask")
    (attr through_hole exclude_from_bom)
    (fp_text reference "FID6" (at -1.155 -2.61) (layer "B.SilkS")
        (effects (font (size 0.7 0.7) (thickness 0.15)) (justify left bottom mirror))
    )
    (fp_text value "Fiducial_1mm_Mask3mm" (at 0 -2.603) (layer "B.Fab")
        (effects (font (size 0.7 0.7) (thickness 0.15)) (justify left bottom mirror))
    )
    (fp_text user "License: Apache-2.0" (at -1.25 -7.003) (layer "B.Fab") hide
        (effects (font (size 0.7 0.7) (thickness 0.15)) (justify left bottom mirror))
    )
    (fp_text user "Author: Antmicro" (at -1.25 -5.803) (layer "B.Fab") hide
        (effects (font (size 0.7 0.7) (thickness 0.15)) (justify left bottom mirror))
    )
    (fp_text user "${REFERENCE}" (at -1.25 -4.603) (layer "B.Fab") hide
        (effects (font (size 0.7 0.7) (thickness 0.15)) (justify left bottom mirror))
    )
    (fp_circle (center 0 0) (end 1.5 0)
      (stroke (width 0.05) (type solid)) (fill none) (layer "B.CrtYd"))
    (fp_circle (center 0 0) (end 1.5 0)
      (stroke (width 0.15) (type solid)) (fill none) (layer "B.Fab"))
    (pad "" smd circle (at 0 0 180) (size 1 1) (layers "B.Cu" "B.Mask")
      (solder_mask_margin 1) (clearance 1))
  )

  (footprint "antmicro-footprints:R_0402_1005Metric" (layer "B.Cu")
    (at 137.225 68.77 90)
    (descr "Resistor SMD 0402")
    (tags "resistor SMD 0402")
    (property "Author" "Antmicro")
    (property "License" "Apache-2.0")
    (property "MPN" "CR0402-FX-1000GLF")
    (property "Manufacturer" "Bourns")
    (property "Sheetfile" "tb.kicad_sch")
    (property "Sheetname" "TB Controller")
    (property "Tolerance" "1%")
    (property "Val" "100R")
    (property "ki_description" "SMD Chip Resistor, 100 ohm, ± 1%, 62.5 mW, 0402 [1005 Metric], Thick Film, General Purpose")
    (property "ki_keywords" "0402, SMT, RESISTOR, PASSIVE")
    (attr smd)
    (fp_text reference "R88" (at 1.124 3.736 270) (layer "B.SilkS")
        (effects (font (size 0.7 0.7) (thickness 0.15)) (justify left bottom mirror))
    )
    (fp_text value "R_100R_0402" (at -1.011843 -1.772047 270) (layer "B.Fab")
        (effects (font (size 0.7 0.7) (thickness 0.15)) (justify left bottom mirror))
    )
    (fp_text user "Author: Antmicro" (at -0.95 -4.169 270) (layer "B.Fab") hide
        (effects (font (size 0.7 0.7) (thickness 0.15)) (justify left bottom mirror))
    )
    (fp_text user "License: Apache-2.0" (at -0.95 -5.169 270) (layer "B.Fab") hide
        (effects (font (size 0.7 0.7) (thickness 0.15)) (justify left bottom mirror))
    )
    (fp_text user "${REFERENCE}" (at -0.95 -3.168 270) (layer "B.Fab") hide
        (effects (font (size 0.7 0.7) (thickness 0.15)) (justify left bottom mirror))
    )
    (fp_rect (start -0.925 0.47) (end 0.925 -0.47)
      (stroke (width 0.05) (type default)) (fill none) (layer "B.CrtYd"))
    (fp_rect (start -0.5 0.25) (end 0.5 -0.25)
      (stroke (width 0.15) (type solid)) (fill none) (layer "B.Fab"))
    (pad "1" smd roundrect (at -0.48 0 90) (size 0.59 0.64) (layers "B.Cu" "B.Paste" "B.Mask") (roundrect_rratio 0.25)
      (net 203 "Net-(U4D-TEST_EN)") (pintype "passive"))
    (pad "2" smd roundrect (at 0.48 0 90) (size 0.59 0.64) (layers "B.Cu" "B.Paste" "B.Mask") (roundrect_rratio 0.25)
      (net 1 "GND") (pintype "passive"))
  )

  (footprint "antmicro-footprints:R_0402_1005Metric" (layer "B.Cu")
    (at 136.2 68.77 90)
    (descr "Resistor SMD 0402")
    (tags "resistor SMD 0402")
    (property "Author" "Antmicro")
    (property "License" "Apache-2.0")
    (property "MPN" "CR0402-FX-1003GLF")
    (property "Manufacturer" "Bourns")
    (property "Sheetfile" "tb.kicad_sch")
    (property "Sheetname" "TB Controller")
    (property "Tolerance" "1%")
    (property "Val" "100k")
    (property "ki_description" "SMD Chip Resistor, 100 kohm, ± 1%, 62.5 mW, 0402 [1005 Metric], Thick Film, General Purpose")
    (property "ki_keywords" "0402, SMT, RESISTOR, PASSIVE")
    (attr smd)
    (fp_text reference "R87" (at 1.124 3.736 270) (layer "B.SilkS")
        (effects (font (size 0.7 0.7) (thickness 0.15)) (justify left bottom mirror))
    )
    (fp_text value "R_100k_0402" (at -1.011843 -1.772047 270) (layer "B.Fab")
        (effects (font (size 0.7 0.7) (thickness 0.15)) (justify left bottom mirror))
    )
    (fp_text user "${REFERENCE}" (at -0.95 -3.168 270) (layer "B.Fab") hide
        (effects (font (size 0.7 0.7) (thickness 0.15)) (justify left bottom mirror))
    )
    (fp_text user "License: Apache-2.0" (at -0.95 -5.169 270) (layer "B.Fab") hide
        (effects (font (size 0.7 0.7) (thickness 0.15)) (justify left bottom mirror))
    )
    (fp_text user "Author: Antmicro" (at -0.95 -4.169 270) (layer "B.Fab") hide
        (effects (font (size 0.7 0.7) (thickness 0.15)) (justify left bottom mirror))
    )
    (fp_rect (start -0.925 0.47) (end 0.925 -0.47)
      (stroke (width 0.05) (type default)) (fill none) (layer "B.CrtYd"))
    (fp_rect (start -0.5 0.25) (end 0.5 -0.25)
      (stroke (width 0.15) (type solid)) (fill none) (layer "B.Fab"))
    (pad "1" smd roundrect (at -0.48 0 90) (size 0.59 0.64) (layers "B.Cu" "B.Paste" "B.Mask") (roundrect_rratio 0.25)
      (net 202 "Net-(U4C-POC_GPIO_6)") (pintype "passive"))
    (pad "2" smd roundrect (at 0.48 0 90) (size 0.59 0.64) (layers "B.Cu" "B.Paste" "B.Mask") (roundrect_rratio 0.25)
      (net 1 "GND") (pintype "passive"))
  )

  (footprint "antmicro-footprints:C_0402_1005Metric" (layer "B.Cu")
    (at 155.085 78.42 180)
    (descr "Capacitor SMD 0402")
    (tags "capacitor SMD 0402")
    (property "Author" "Antmicro")
    (property "Dielectric" "")
    (property "License" "Apache-2.0")
    (property "MPN" "CC0402KRX5R6BB224")
    (property "Manufacturer" "YAGEO")
    (property "Sheetfile" "tb.kicad_sch")
    (property "Sheetname" "TB Controller")
    (property "Val" "220n")
    (property "Voltage" "")
    (property "ki_description" "SMD Multilayer Ceramic Capacitor, 0.22 µF, 10 V, 0402 [1005 Metric], ± 10%, X5R, CC Series")
    (property "ki_keywords" "0402, SMT, CAPACITOR, PASSIVE, MLCC, CERAMIC")
    (attr smd)
    (fp_text reference "C103" (at 1.034 -0.431) (layer "B.SilkS")
        (effects (font (size 0.7 0.7) (thickness 0.15)) (justify left bottom mirror))
    )
    (fp_text value "C_220n_0402" (at -1.022927 -2.155213) (layer "B.Fab")
        (effects (font (size 0.7 0.7) (thickness 0.15)) (justify left bottom mirror))
    )
    (fp_text user "License: Apache-2.0" (at -0.939 -5.799) (layer "B.Fab") hide
        (effects (font (size 0.7 0.7) (thickness 0.15)) (justify left bottom mirror))
    )
    (fp_text user "Author: Antmicro" (at -0.939 -3.399) (layer "B.Fab") hide
        (effects (font (size 0.7 0.7) (thickness 0.15)) (justify left bottom mirror))
    )
    (fp_text user "${REFERENCE}" (at -0.939 -4.599) (layer "B.Fab") hide
        (effects (font (size 0.7 0.7) (thickness 0.15)) (justify left bottom mirror))
    )
    (fp_rect (start -0.925 0.47) (end 0.925 -0.47)
      (stroke (width 0.05) (type default)) (fill none) (layer "B.CrtYd"))
    (fp_line (start -0.494 -0.248) (end -0.494 0.25)
      (stroke (width 0.15) (type solid)) (layer "B.Fab"))
    (fp_line (start -0.494 0.25) (end 0.504 0.25)
      (stroke (width 0.15) (type solid)) (layer "B.Fab"))
    (fp_line (start 0.504 -0.248) (end -0.494 -0.248)
      (stroke (width 0.15) (type solid)) (layer "B.Fab"))
    (fp_line (start 0.504 0.25) (end 0.504 -0.248)
      (stroke (width 0.15) (type solid)) (layer "B.Fab"))
    (pad "1" smd roundrect (at -0.48 0 180) (size 0.59 0.64) (layers "B.Cu" "B.Paste" "B.Mask") (roundrect_rratio 0.25)
      (net 21 "TB_TX1_N") (pintype "passive"))
    (pad "2" smd roundrect (at 0.48 0 180) (size 0.59 0.64) (layers "B.Cu" "B.Paste" "B.Mask") (roundrect_rratio 0.25)
      (net 22 "/TB Controller/PA_TX1_N") (pintype "passive"))
  )

  (footprint "antmicro-footprints:C_0402_1005Metric" (layer "B.Cu")
    (at 132.85 78.875)
    (descr "Capacitor SMD 0402")
    (tags "capacitor SMD 0402")
    (property "Author" "Antmicro")
    (property "Dielectric" "")
    (property "License" "Apache-2.0")
    (property "MPN" "C1005X6S1A105K050BC")
    (property "Manufacturer" "TDK")
    (property "Sheetfile" "tb-power.kicad_sch")
    (property "Sheetname" "Thunderbolt Controller - Power")
    (property "Val" "1u")
    (property "Voltage" "")
    (property "ki_description" "SMD Multilayer Ceramic Capacitor, 1 µF, 10 V, 0402 [1005 Metric], ± 10%, X6S, C")
    (property "ki_keywords" "0402, SMT, CAPACITOR, PASSIVE, CERAMIC, MLCC")
    (attr smd)
    (fp_text reference "C57" (at 17.518 7.612 180) (layer "B.SilkS")
        (effects (font (size 0.7 0.7) (thickness 0.15)) (justify left bottom mirror))
    )
    (fp_text value "C_1u_0402" (at -1.022927 -2.155213 180) (layer "B.Fab")
        (effects (font (size 0.7 0.7) (thickness 0.15)) (justify left bottom mirror))
    )
    (fp_text user "${REFERENCE}" (at -0.939 -4.599 180) (layer "B.Fab") hide
        (effects (font (size 0.7 0.7) (thickness 0.15)) (justify left bottom mirror))
    )
    (fp_text user "Author: Antmicro" (at -0.939 -3.399 180) (layer "B.Fab") hide
        (effects (font (size 0.7 0.7) (thickness 0.15)) (justify left bottom mirror))
    )
    (fp_text user "License: Apache-2.0" (at -0.939 -5.799 180) (layer "B.Fab") hide
        (effects (font (size 0.7 0.7) (thickness 0.15)) (justify left bottom mirror))
    )
    (fp_rect (start -0.925 0.47) (end 0.925 -0.47)
      (stroke (width 0.05) (type default)) (fill none) (layer "B.CrtYd"))
    (fp_line (start -0.494 -0.248) (end -0.494 0.25)
      (stroke (width 0.15) (type solid)) (layer "B.Fab"))
    (fp_line (start -0.494 0.25) (end 0.504 0.25)
      (stroke (width 0.15) (type solid)) (layer "B.Fab"))
    (fp_line (start 0.504 -0.248) (end -0.494 -0.248)
      (stroke (width 0.15) (type solid)) (layer "B.Fab"))
    (fp_line (start 0.504 0.25) (end 0.504 -0.248)
      (stroke (width 0.15) (type solid)) (layer "B.Fab"))
    (pad "1" smd roundrect (at -0.48 0) (size 0.59 0.64) (layers "B.Cu" "B.Paste" "B.Mask") (roundrect_rratio 0.25)
      (net 1 "GND") (pintype "passive"))
    (pad "2" smd roundrect (at 0.48 0) (size 0.59 0.64) (layers "B.Cu" "B.Paste" "B.Mask") (roundrect_rratio 0.25)
      (net 107 "Net-(C54-Pad2)") (pintype "passive"))
  )

  (footprint "antmicro-footprints:R_0402_1005Metric" (layer "B.Cu")
    (at 113.125 86.17 90)
    (descr "Resistor SMD 0402")
    (tags "resistor SMD 0402")
    (property "Author" "Antmicro")
    (property "License" "Apache-2.0")
    (property "MPN" "CR0402-FX-1002GLF")
    (property "Manufacturer" "Bourns")
    (property "Sheetfile" "power.kicad_sch")
    (property "Sheetname" "Power")
    (property "Tolerance" "1%")
    (property "Val" "10k")
    (property "ki_description" "SMD Chip Resistor, 10 kohm, ± 1%, 62.5 mW, 0402 [1005 Metric], Thick Film, General Purpose")
    (property "ki_keywords" "0402, SMT, RESISTOR, PASSIVE")
    (attr smd)
    (fp_text reference "R44" (at -0.825 0.413 270) (layer "B.SilkS")
        (effects (font (size 0.7 0.7) (thickness 0.15)) (justify left bottom mirror))
    )
    (fp_text value "R_10k_0402" (at -1.011843 -1.772047 270) (layer "B.Fab")
        (effects (font (size 0.7 0.7) (thickness 0.15)) (justify left bottom mirror))
    )
    (fp_text user "${REFERENCE}" (at -0.95 -3.168 270) (layer "B.Fab") hide
        (effects (font (size 0.7 0.7) (thickness 0.15)) (justify left bottom mirror))
    )
    (fp_text user "License: Apache-2.0" (at -0.95 -5.169 270) (layer "B.Fab") hide
        (effects (font (size 0.7 0.7) (thickness 0.15)) (justify left bottom mirror))
    )
    (fp_text user "Author: Antmicro" (at -0.95 -4.169 270) (layer "B.Fab") hide
        (effects (font (size 0.7 0.7) (thickness 0.15)) (justify left bottom mirror))
    )
    (fp_rect (start -0.925 0.47) (end 0.925 -0.47)
      (stroke (width 0.05) (type default)) (fill none) (layer "B.CrtYd"))
    (fp_rect (start -0.5 0.25) (end 0.5 -0.25)
      (stroke (width 0.15) (type solid)) (fill none) (layer "B.Fab"))
    (pad "1" smd roundrect (at -0.48 0 90) (size 0.59 0.64) (layers "B.Cu" "B.Paste" "B.Mask") (roundrect_rratio 0.25)
      (net 1 "GND") (pintype "passive"))
    (pad "2" smd roundrect (at 0.48 0 90) (size 0.59 0.64) (layers "B.Cu" "B.Paste" "B.Mask") (roundrect_rratio 0.25)
      (net 169 "Net-(U1-FB)") (pintype "passive"))
  )

  (footprint "antmicro-footprints:C_0402_1005Metric" (layer "B.Cu")
    (at 137.725 82.725 180)
    (descr "Capacitor SMD 0402")
    (tags "capacitor SMD 0402")
    (property "Author" "Antmicro")
    (property "Dielectric" "")
    (property "License" "Apache-2.0")
    (property "MPN" "C1005X6S1A105K050BC")
    (property "Manufacturer" "TDK")
    (property "Sheetfile" "tb-power.kicad_sch")
    (property "Sheetname" "Thunderbolt Controller - Power")
    (property "Val" "1u")
    (property "Voltage" "")
    (property "ki_description" "SMD Multilayer Ceramic Capacitor, 1 µF, 10 V, 0402 [1005 Metric], ± 10%, X6S, C")
    (property "ki_keywords" "0402, SMT, CAPACITOR, PASSIVE, CERAMIC, MLCC")
    (attr smd)
    (fp_text reference "C90" (at -17.596 -8.334) (layer "B.SilkS")
        (effects (font (size 0.7 0.7) (thickness 0.15)) (justify left bottom mirror))
    )
    (fp_text value "C_1u_0402" (at -1.022927 -2.155213) (layer "B.Fab")
        (effects (font (size 0.7 0.7) (thickness 0.15)) (justify left bottom mirror))
    )
    (fp_text user "Author: Antmicro" (at -0.939 -3.399) (layer "B.Fab") hide
        (effects (font (size 0.7 0.7) (thickness 0.15)) (justify left bottom mirror))
    )
    (fp_text user "License: Apache-2.0" (at -0.939 -5.799) (layer "B.Fab") hide
        (effects (font (size 0.7 0.7) (thickness 0.15)) (justify left bottom mirror))
    )
    (fp_text user "${REFERENCE}" (at -0.939 -4.599) (layer "B.Fab") hide
        (effects (font (size 0.7 0.7) (thickness 0.15)) (justify left bottom mirror))
    )
    (fp_rect (start -0.925 0.47) (end 0.925 -0.47)
      (stroke (width 0.05) (type default)) (fill none) (layer "B.CrtYd"))
    (fp_line (start -0.494 -0.248) (end -0.494 0.25)
      (stroke (width 0.15) (type solid)) (layer "B.Fab"))
    (fp_line (start -0.494 0.25) (end 0.504 0.25)
      (stroke (width 0.15) (type solid)) (layer "B.Fab"))
    (fp_line (start 0.504 -0.248) (end -0.494 -0.248)
      (stroke (width 0.15) (type solid)) (layer "B.Fab"))
    (fp_line (start 0.504 0.25) (end 0.504 -0.248)
      (stroke (width 0.15) (type solid)) (layer "B.Fab"))
    (pad "1" smd roundrect (at -0.48 0 180) (size 0.59 0.64) (layers "B.Cu" "B.Paste" "B.Mask") (roundrect_rratio 0.25)
      (net 1 "GND") (pintype "passive"))
    (pad "2" smd roundrect (at 0.48 0 180) (size 0.59 0.64) (layers "B.Cu" "B.Paste" "B.Mask") (roundrect_rratio 0.25)
      (net 113 "Net-(U4A-VCC0P9_LVR_SENSE)") (pintype "passive"))
  )

  (footprint "antmicro-footprints:C_0402_1005Metric" (layer "B.Cu")
    (at 132.5 92.65 -90)
    (descr "Capacitor SMD 0402")
    (tags "capacitor SMD 0402")
    (property "Author" "Antmicro")
    (property "Dielectric" "")
    (property "License" "Apache-2.0")
    (property "MPN" "CC0402KRX5R6BB224")
    (property "Manufacturer" "YAGEO")
    (property "Sheetfile" "tb.kicad_sch")
    (property "Sheetname" "TB Controller")
    (property "Val" "220n")
    (property "Voltage" "")
    (property "ki_description" "SMD Multilayer Ceramic Capacitor, 0.22 µF, 10 V, 0402 [1005 Metric], ± 10%, X5R, CC Series")
    (property "ki_keywords" "0402, SMT, CAPACITOR, PASSIVE, MLCC, CERAMIC")
    (attr smd)
    (fp_text reference "C106" (at -3.877 -0.47 90) (layer "B.SilkS")
        (effects (font (size 0.7 0.7) (thickness 0.15)) (justify left bottom mirror))
    )
    (fp_text value "C_220n_0402" (at -1.022927 -2.155213 90) (layer "B.Fab")
        (effects (font (size 0.7 0.7) (thickness 0.15)) (justify left bottom mirror))
    )
    (fp_text user "License: Apache-2.0" (at -0.939 -5.799 90) (layer "B.Fab") hide
        (effects (font (size 0.7 0.7) (thickness 0.15)) (justify left bottom mirror))
    )
    (fp_text user "${REFERENCE}" (at -0.939 -4.599 90) (layer "B.Fab") hide
        (effects (font (size 0.7 0.7) (thickness 0.15)) (justify left bottom mirror))
    )
    (fp_text user "Author: Antmicro" (at -0.939 -3.399 90) (layer "B.Fab") hide
        (effects (font (size 0.7 0.7) (thickness 0.15)) (justify left bottom mirror))
    )
    (fp_rect (start -0.925 0.47) (end 0.925 -0.47)
      (stroke (width 0.05) (type default)) (fill none) (layer "B.CrtYd"))
    (fp_line (start -0.494 -0.248) (end -0.494 0.25)
      (stroke (width 0.15) (type solid)) (layer "B.Fab"))
    (fp_line (start -0.494 0.25) (end 0.504 0.25)
      (stroke (width 0.15) (type solid)) (layer "B.Fab"))
    (fp_line (start 0.504 -0.248) (end -0.494 -0.248)
      (stroke (width 0.15) (type solid)) (layer "B.Fab"))
    (fp_line (start 0.504 0.25) (end 0.504 -0.248)
      (stroke (width 0.15) (type solid)) (layer "B.Fab"))
    (pad "1" smd roundrect (at -0.48 0 270) (size 0.59 0.64) (layers "B.Cu" "B.Paste" "B.Mask") (roundrect_rratio 0.25)
      (net 77 "/TB Controller/TX1_N") (pintype "passive"))
    (pad "2" smd roundrect (at 0.48 0 270) (size 0.59 0.64) (layers "B.Cu" "B.Paste" "B.Mask") (roundrect_rratio 0.25)
      (net 25 "PCIE_TX1_N") (pintype "passive"))
  )

  (footprint "antmicro-footprints:C_0402_1005Metric" (layer "B.Cu")
    (at 127.5 92.65 -90)
    (descr "Capacitor SMD 0402")
    (tags "capacitor SMD 0402")
    (property "Author" "Antmicro")
    (property "Dielectric" "")
    (property "License" "Apache-2.0")
    (property "MPN" "CC0402KRX5R6BB224")
    (property "Manufacturer" "YAGEO")
    (property "Sheetfile" "tb.kicad_sch")
    (property "Sheetname" "TB Controller")
    (property "Val" "220n")
    (property "Voltage" "")
    (property "ki_description" "SMD Multilayer Ceramic Capacitor, 0.22 µF, 10 V, 0402 [1005 Metric], ± 10%, X5R, CC Series")
    (property "ki_keywords" "0402, SMT, CAPACITOR, PASSIVE, MLCC, CERAMIC")
    (attr smd)
    (fp_text reference "C105" (at -3.877 -0.47 90) (layer "B.SilkS")
        (effects (font (size 0.7 0.7) (thickness 0.15)) (justify left bottom mirror))
    )
    (fp_text value "C_220n_0402" (at -1.022927 -2.155213 90) (layer "B.Fab")
        (effects (font (size 0.7 0.7) (thickness 0.15)) (justify left bottom mirror))
    )
    (fp_text user "License: Apache-2.0" (at -0.939 -5.799 90) (layer "B.Fab") hide
        (effects (font (size 0.7 0.7) (thickness 0.15)) (justify left bottom mirror))
    )
    (fp_text user "Author: Antmicro" (at -0.939 -3.399 90) (layer "B.Fab") hide
        (effects (font (size 0.7 0.7) (thickness 0.15)) (justify left bottom mirror))
    )
    (fp_text user "${REFERENCE}" (at -0.939 -4.599 90) (layer "B.Fab") hide
        (effects (font (size 0.7 0.7) (thickness 0.15)) (justify left bottom mirror))
    )
    (fp_rect (start -0.925 0.47) (end 0.925 -0.47)
      (stroke (width 0.05) (type default)) (fill none) (layer "B.CrtYd"))
    (fp_line (start -0.494 -0.248) (end -0.494 0.25)
      (stroke (width 0.15) (type solid)) (layer "B.Fab"))
    (fp_line (start -0.494 0.25) (end 0.504 0.25)
      (stroke (width 0.15) (type solid)) (layer "B.Fab"))
    (fp_line (start 0.504 -0.248) (end -0.494 -0.248)
      (stroke (width 0.15) (type solid)) (layer "B.Fab"))
    (fp_line (start 0.504 0.25) (end 0.504 -0.248)
      (stroke (width 0.15) (type solid)) (layer "B.Fab"))
    (pad "1" smd roundrect (at -0.48 0 270) (size 0.59 0.64) (layers "B.Cu" "B.Paste" "B.Mask") (roundrect_rratio 0.25)
      (net 76 "/TB Controller/TX0_N") (pintype "passive"))
    (pad "2" smd roundrect (at 0.48 0 270) (size 0.59 0.64) (layers "B.Cu" "B.Paste" "B.Mask") (roundrect_rratio 0.25)
      (net 24 "PCIE_TX0_N") (pintype "passive"))
  )

  (footprint "antmicro-footprints:R_0402_1005Metric" (layer "B.Cu")
    (at 146.5 70.94 -90)
    (descr "Resistor SMD 0402")
    (tags "resistor SMD 0402")
    (property "Author" "Antmicro")
    (property "License" "Apache-2.0")
    (property "MPN" "CR0402-FX-1001GLF")
    (property "Manufacturer" "Bourns")
    (property "Sheetfile" "tb-power.kicad_sch")
    (property "Sheetname" "Thunderbolt Controller - Power")
    (property "Tolerance" "1%")
    (property "Val" "1k")
    (property "ki_description" "SMD Chip Resistor, 1 kohm, ± 1%, 63 mW, 0402 [1005 Metric], Thick Film, General Purpose")
    (property "ki_keywords" "0402, SMT, RESISTOR, PASSIVE")
    (attr smd)
    (fp_text reference "R47" (at -3.122 -0.439 90) (layer "B.SilkS")
        (effects (font (size 0.7 0.7) (thickness 0.15)) (justify left bottom mirror))
    )
    (fp_text value "R_1k_0402" (at -1.011843 -1.772047 90) (layer "B.Fab")
        (effects (font (size 0.7 0.7) (thickness 0.15)) (justify left bottom mirror))
    )
    (fp_text user "${REFERENCE}" (at -0.95 -3.168 90) (layer "B.Fab") hide
        (effects (font (size 0.7 0.7) (thickness 0.15)) (justify left bottom mirror))
    )
    (fp_text user "Author: Antmicro" (at -0.95 -4.169 90) (layer "B.Fab") hide
        (effects (font (size 0.7 0.7) (thickness 0.15)) (justify left bottom mirror))
    )
    (fp_text user "License: Apache-2.0" (at -0.95 -5.169 90) (layer "B.Fab") hide
        (effects (font (size 0.7 0.7) (thickness 0.15)) (justify left bottom mirror))
    )
    (fp_rect (start -0.925 0.47) (end 0.925 -0.47)
      (stroke (width 0.05) (type default)) (fill none) (layer "B.CrtYd"))
    (fp_rect (start -0.5 0.25) (end 0.5 -0.25)
      (stroke (width 0.15) (type solid)) (fill none) (layer "B.Fab"))
    (pad "1" smd roundrect (at -0.48 0 270) (size 0.59 0.64) (layers "B.Cu" "B.Paste" "B.Mask") (roundrect_rratio 0.25)
      (net 112 "Net-(U4A-VCC0P9_SVR_SENSE)") (pintype "passive"))
    (pad "2" smd roundrect (at 0.48 0 270) (size 0.59 0.64) (layers "B.Cu" "B.Paste" "B.Mask") (roundrect_rratio 0.25)
      (net 138 "Net-(Q1-B)") (pintype "passive"))
  )

  (footprint "antmicro-footprints:C_0402_1005Metric" (layer "B.Cu")
    (at 136.275 83.275 90)
    (descr "Capacitor SMD 0402")
    (tags "capacitor SMD 0402")
    (property "Author" "Antmicro")
    (property "Dielectric" "")
    (property "License" "Apache-2.0")
    (property "MPN" "C1005X6S1A105K050BC")
    (property "Manufacturer" "TDK")
    (property "Sheetfile" "tb-power.kicad_sch")
    (property "Sheetname" "Thunderbolt Controller - Power")
    (property "Val" "1u")
    (property "Voltage" "")
    (property "ki_description" "SMD Multilayer Ceramic Capacitor, 1 µF, 10 V, 0402 [1005 Metric], ± 10%, X6S, C")
    (property "ki_keywords" "0402, SMT, CAPACITOR, PASSIVE, CERAMIC, MLCC")
    (attr smd)
    (fp_text reference "C69" (at -6.895 16.887 270) (layer "B.SilkS")
        (effects (font (size 0.7 0.7) (thickness 0.15)) (justify left bottom mirror))
    )
    (fp_text value "C_1u_0402" (at -1.022927 -2.155213 270) (layer "B.Fab")
        (effects (font (size 0.7 0.7) (thickness 0.15)) (justify left bottom mirror))
    )
    (fp_text user "Author: Antmicro" (at -0.939 -3.399 270) (layer "B.Fab") hide
        (effects (font (size 0.7 0.7) (thickness 0.15)) (justify left bottom mirror))
    )
    (fp_text user "License: Apache-2.0" (at -0.939 -5.799 270) (layer "B.Fab") hide
        (effects (font (size 0.7 0.7) (thickness 0.15)) (justify left bottom mirror))
    )
    (fp_text user "${REFERENCE}" (at -0.939 -4.599 270) (layer "B.Fab") hide
        (effects (font (size 0.7 0.7) (thickness 0.15)) (justify left bottom mirror))
    )
    (fp_rect (start -0.925 0.47) (end 0.925 -0.47)
      (stroke (width 0.05) (type default)) (fill none) (layer "B.CrtYd"))
    (fp_line (start -0.494 -0.248) (end -0.494 0.25)
      (stroke (width 0.15) (type solid)) (layer "B.Fab"))
    (fp_line (start -0.494 0.25) (end 0.504 0.25)
      (stroke (width 0.15) (type solid)) (layer "B.Fab"))
    (fp_line (start 0.504 -0.248) (end -0.494 -0.248)
      (stroke (width 0.15) (type solid)) (layer "B.Fab"))
    (fp_line (start 0.504 0.25) (end 0.504 -0.248)
      (stroke (width 0.15) (type solid)) (layer "B.Fab"))
    (pad "1" smd roundrect (at -0.48 0 90) (size 0.59 0.64) (layers "B.Cu" "B.Paste" "B.Mask") (roundrect_rratio 0.25)
      (net 1 "GND") (pintype "passive"))
    (pad "2" smd roundrect (at 0.48 0 90) (size 0.59 0.64) (layers "B.Cu" "B.Paste" "B.Mask") (roundrect_rratio 0.25)
      (net 110 "Net-(U4A-VCC3P3_ANA_USB2)") (pintype "passive"))
  )

  (footprint "antmicro-footprints:C_0402_1005Metric" (layer "B.Cu")
    (at 158.91 65.47 -90)
    (descr "Capacitor SMD 0402")
    (tags "capacitor SMD 0402")
    (property "Author" "Antmicro")
    (property "Dielectric" "")
    (property "License" "Apache-2.0")
    (property "MPN" "04025C221JAT2A")
    (property "Manufacturer" "KYOCERA AVX")
    (property "Sheetfile" "power.kicad_sch")
    (property "Sheetname" "Power")
    (property "Val" "220p")
    (property "Voltage" "")
    (property "ki_description" "SMD Multilayer Ceramic Capacitor, 220 pF, 50 V, 0402 [1005 Metric], ± 10%, X7R, MC")
    (property "ki_keywords" "0402, SMT, CAPACITOR, PASSIVE")
    (attr smd)
    (fp_text reference "C49" (at -1.030251 -2.369062 90) (layer "B.SilkS")
        (effects (font (size 0.7 0.7) (thickness 0.15)) (justify left bottom mirror))
    )
    (fp_text value "C_220p_0402" (at -1.022927 -2.155213 90) (layer "B.Fab")
        (effects (font (size 0.7 0.7) (thickness 0.15)) (justify left bottom mirror))
    )
    (fp_text user "Author: Antmicro" (at -0.939 -3.399 90) (layer "B.Fab") hide
        (effects (font (size 0.7 0.7) (thickness 0.15)) (justify left bottom mirror))
    )
    (fp_text user "License: Apache-2.0" (at -0.939 -5.799 90) (layer "B.Fab") hide
        (effects (font (size 0.7 0.7) (thickness 0.15)) (justify left bottom mirror))
    )
    (fp_text user "${REFERENCE}" (at -0.939 -4.599 90) (layer "B.Fab") hide
        (effects (font (size 0.7 0.7) (thickness 0.15)) (justify left bottom mirror))
    )
    (fp_rect (start -0.925 0.47) (end 0.925 -0.47)
      (stroke (width 0.05) (type default)) (fill none) (layer "B.CrtYd"))
    (fp_line (start -0.494 -0.248) (end -0.494 0.25)
      (stroke (width 0.15) (type solid)) (layer "B.Fab"))
    (fp_line (start -0.494 0.25) (end 0.504 0.25)
      (stroke (width 0.15) (type solid)) (layer "B.Fab"))
    (fp_line (start 0.504 -0.248) (end -0.494 -0.248)
      (stroke (width 0.15) (type solid)) (layer "B.Fab"))
    (fp_line (start 0.504 0.25) (end 0.504 -0.248)
      (stroke (width 0.15) (type solid)) (layer "B.Fab"))
    (pad "1" smd roundrect (at -0.48 0 270) (size 0.59 0.64) (layers "B.Cu" "B.Paste" "B.Mask") (roundrect_rratio 0.25)
      (net 1 "GND") (pintype "passive"))
    (pad "2" smd roundrect (at 0.48 0 270) (size 0.59 0.64) (layers "B.Cu" "B.Paste" "B.Mask") (roundrect_rratio 0.25)
      (net 11 "CC1") (pintype "passive"))
  )

  (footprint "antmicro-footprints:R_0402_1005Metric" (layer "B.Cu")
    (at 147.5 70.94 90)
    (descr "Resistor SMD 0402")
    (tags "resistor SMD 0402")
    (property "Author" "Antmicro")
    (property "License" "Apache-2.0")
    (property "MPN" "CR0402-FX-1003GLF")
    (property "Manufacturer" "Bourns")
    (property "Sheetfile" "tb-power.kicad_sch")
    (property "Sheetname" "Thunderbolt Controller - Power")
    (property "Tolerance" "1%")
    (property "Val" "100k")
    (property "ki_description" "SMD Chip Resistor, 100 kohm, ± 1%, 62.5 mW, 0402 [1005 Metric], Thick Film, General Purpose")
    (property "ki_keywords" "0402, SMT, RESISTOR, PASSIVE")
    (attr smd)
    (fp_text reference "R48" (at 3.122 0.455 270) (layer "B.SilkS")
        (effects (font (size 0.7 0.7) (thickness 0.15)) (justify left bottom mirror))
    )
    (fp_text value "R_100k_0402" (at -1.011843 -1.772047 270) (layer "B.Fab")
        (effects (font (size 0.7 0.7) (thickness 0.15)) (justify left bottom mirror))
    )
    (fp_text user "${REFERENCE}" (at -0.95 -3.168 270) (layer "B.Fab") hide
        (effects (font (size 0.7 0.7) (thickness 0.15)) (justify left bottom mirror))
    )
    (fp_text user "License: Apache-2.0" (at -0.95 -5.169 270) (layer "B.Fab") hide
        (effects (font (size 0.7 0.7) (thickness 0.15)) (justify left bottom mirror))
    )
    (fp_text user "Author: Antmicro" (at -0.95 -4.169 270) (layer "B.Fab") hide
        (effects (font (size 0.7 0.7) (thickness 0.15)) (justify left bottom mirror))
    )
    (fp_rect (start -0.925 0.47) (end 0.925 -0.47)
      (stroke (width 0.05) (type default)) (fill none) (layer "B.CrtYd"))
    (fp_rect (start -0.5 0.25) (end 0.5 -0.25)
      (stroke (width 0.15) (type solid)) (fill none) (layer "B.Fab"))
    (pad "1" smd roundrect (at -0.48 0 90) (size 0.59 0.64) (layers "B.Cu" "B.Paste" "B.Mask") (roundrect_rratio 0.25)
      (net 1 "GND") (pintype "passive"))
    (pad "2" smd roundrect (at 0.48 0 90) (size 0.59 0.64) (layers "B.Cu" "B.Paste" "B.Mask") (roundrect_rratio 0.25)
      (net 138 "Net-(Q1-B)") (pintype "passive"))
  )

  (footprint "antmicro-footprints:R_0402_1005Metric" (layer "B.Cu")
    (at 116.45 64.675 90)
    (descr "Resistor SMD 0402")
    (tags "resistor SMD 0402")
    (property "Author" "Antmicro")
    (property "License" "Apache-2.0")
    (property "MPN" "CR0402-FX-1003GLF")
    (property "Manufacturer" "Bourns")
    (property "Sheetfile" "power.kicad_sch")
    (property "Sheetname" "Power")
    (property "Tolerance" "1%")
    (property "Val" "100k")
    (property "ki_description" "SMD Chip Resistor, 100 kohm, ± 1%, 62.5 mW, 0402 [1005 Metric], Thick Film, General Purpose")
    (property "ki_keywords" "0402, SMT, RESISTOR, PASSIVE")
    (attr smd)
    (fp_text reference "R23" (at -0.984 0.39 270) (layer "B.SilkS")
        (effects (font (size 0.7 0.7) (thickness 0.15)) (justify left bottom mirror))
    )
    (fp_text value "R_100k_0402" (at -1.011843 -1.772047 270) (layer "B.Fab")
        (effects (font (size 0.7 0.7) (thickness 0.15)) (justify left bottom mirror))
    )
    (fp_text user "Author: Antmicro" (at -0.95 -4.169 270) (layer "B.Fab") hide
        (effects (font (size 0.7 0.7) (thickness 0.15)) (justify left bottom mirror))
    )
    (fp_text user "${REFERENCE}" (at -0.95 -3.168 270) (layer "B.Fab") hide
        (effects (font (size 0.7 0.7) (thickness 0.15)) (justify left bottom mirror))
    )
    (fp_text user "License: Apache-2.0" (at -0.95 -5.169 270) (layer "B.Fab") hide
        (effects (font (size 0.7 0.7) (thickness 0.15)) (justify left bottom mirror))
    )
    (fp_rect (start -0.925 0.47) (end 0.925 -0.47)
      (stroke (width 0.05) (type default)) (fill none) (layer "B.CrtYd"))
    (fp_rect (start -0.5 0.25) (end 0.5 -0.25)
      (stroke (width 0.15) (type solid)) (fill none) (layer "B.Fab"))
    (pad "1" smd roundrect (at -0.48 0 90) (size 0.59 0.64) (layers "B.Cu" "B.Paste" "B.Mask") (roundrect_rratio 0.25)
      (net 158 "Net-(U2-PG)") (pintype "passive"))
    (pad "2" smd roundrect (at 0.48 0 90) (size 0.59 0.64) (layers "B.Cu" "B.Paste" "B.Mask") (roundrect_rratio 0.25)
      (net 6 "/Power/SMPS_LDO") (pintype "passive"))
  )

  (footprint "antmicro-footprints:R_0402_1005Metric" (layer "B.Cu")
    (at 140.3 66.82 -90)
    (descr "Resistor SMD 0402")
    (tags "resistor SMD 0402")
    (property "Author" "Antmicro")
    (property "License" "Apache-2.0")
    (property "MPN" "CR0402-FX-3301GLF")
    (property "Manufacturer" "Bourns")
    (property "Sheetfile" "connectors.kicad_sch")
    (property "Sheetname" "Connectors")
    (property "Tolerance" "1%")
    (property "Val" "3k3")
    (property "ki_description" "SMD Chip Resistor, 3.3 kohm, ± 1%, 63 mW, 0402 [1005 Metric], Thick Film, General Purpose")
    (property "ki_keywords" "0402, SMT, RESISTOR, PASSIVE")
    (attr smd)
    (fp_text reference "R1" (at -3.066 -0.416 90) (layer "B.SilkS")
        (effects (font (size 0.7 0.7) (thickness 0.15)) (justify left bottom mirror))
    )
    (fp_text value "R_3k3_0402" (at -1.011843 -1.772047 90) (layer "B.Fab")
        (effects (font (size 0.7 0.7) (thickness 0.15)) (justify left bottom mirror))
    )
    (fp_text user "${REFERENCE}" (at -0.95 -3.168 90) (layer "B.Fab") hide
        (effects (font (size 0.7 0.7) (thickness 0.15)) (justify left bottom mirror))
    )
    (fp_text user "Author: Antmicro" (at -0.95 -4.169 90) (layer "B.Fab") hide
        (effects (font (size 0.7 0.7) (thickness 0.15)) (justify left bottom mirror))
    )
    (fp_text user "License: Apache-2.0" (at -0.95 -5.169 90) (layer "B.Fab") hide
        (effects (font (size 0.7 0.7) (thickness 0.15)) (justify left bottom mirror))
    )
    (fp_rect (start -0.925 0.47) (end 0.925 -0.47)
      (stroke (width 0.05) (type default)) (fill none) (layer "B.CrtYd"))
    (fp_rect (start -0.5 0.25) (end 0.5 -0.25)
      (stroke (width 0.15) (type solid)) (fill none) (layer "B.Fab"))
    (pad "1" smd roundrect (at -0.48 0 270) (size 0.59 0.64) (layers "B.Cu" "B.Paste" "B.Mask") (roundrect_rratio 0.25)
      (net 1 "GND") (pintype "passive"))
    (pad "2" smd roundrect (at 0.48 0 270) (size 0.59 0.64) (layers "B.Cu" "B.Paste" "B.Mask") (roundrect_rratio 0.25)
      (net 43 "PCIE_PWRGD") (pintype "passive"))
  )

  (footprint "antmicro-footprints:C_0402_1005Metric" (layer "B.Cu")
    (at 155.41 63.97)
    (descr "Capacitor SMD 0402")
    (tags "capacitor SMD 0402")
    (property "Author" "Antmicro")
    (property "Dielectric" "")
    (property "License" "Apache-2.0")
    (property "MPN" "C1005X6S1A105K050BC")
    (property "Manufacturer" "TDK")
    (property "Sheetfile" "power.kicad_sch")
    (property "Sheetname" "Power")
    (property "Val" "1u")
    (property "Voltage" "")
    (property "ki_description" "SMD Multilayer Ceramic Capacitor, 1 µF, 10 V, 0402 [1005 Metric], ± 10%, X6S, C")
    (property "ki_keywords" "0402, SMT, CAPACITOR, PASSIVE, CERAMIC, MLCC")
    (attr smd)
    (fp_text reference "C34" (at 1.152793 1.433548 180) (layer "B.SilkS")
        (effects (font (size 0.7 0.7) (thickness 0.15)) (justify left bottom mirror))
    )
    (fp_text value "C_1u_0402" (at -1.022927 -2.155213 180) (layer "B.Fab")
        (effects (font (size 0.7 0.7) (thickness 0.15)) (justify left bottom mirror))
    )
    (fp_text user "${REFERENCE}" (at -0.939 -4.599 180) (layer "B.Fab") hide
        (effects (font (size 0.7 0.7) (thickness 0.15)) (justify left bottom mirror))
    )
    (fp_text user "Author: Antmicro" (at -0.939 -3.399 180) (layer "B.Fab") hide
        (effects (font (size 0.7 0.7) (thickness 0.15)) (justify left bottom mirror))
    )
    (fp_text user "License: Apache-2.0" (at -0.939 -5.799 180) (layer "B.Fab") hide
        (effects (font (size 0.7 0.7) (thickness 0.15)) (justify left bottom mirror))
    )
    (fp_rect (start -0.925 0.47) (end 0.925 -0.47)
      (stroke (width 0.05) (type default)) (fill none) (layer "B.CrtYd"))
    (fp_line (start -0.494 -0.248) (end -0.494 0.25)
      (stroke (width 0.15) (type solid)) (layer "B.Fab"))
    (fp_line (start -0.494 0.25) (end 0.504 0.25)
      (stroke (width 0.15) (type solid)) (layer "B.Fab"))
    (fp_line (start 0.504 -0.248) (end -0.494 -0.248)
      (stroke (width 0.15) (type solid)) (layer "B.Fab"))
    (fp_line (start 0.504 0.25) (end 0.504 -0.248)
      (stroke (width 0.15) (type solid)) (layer "B.Fab"))
    (pad "1" smd roundrect (at -0.48 0) (size 0.59 0.64) (layers "B.Cu" "B.Paste" "B.Mask") (roundrect_rratio 0.25)
      (net 101 "Net-(U3-VOUT_3V3)") (pintype "passive"))
    (pad "2" smd roundrect (at 0.48 0) (size 0.59 0.64) (layers "B.Cu" "B.Paste" "B.Mask") (roundrect_rratio 0.25)
      (net 1 "GND") (pintype "passive"))
  )

  (footprint "antmicro-footprints:R_0402_1005Metric" (layer "B.Cu")
    (at 155.41 61.97 180)
    (descr "Resistor SMD 0402")
    (tags "resistor SMD 0402")
    (property "Author" "Antmicro")
    (property "License" "Apache-2.0")
    (property "MPN" "CR0402-FX-1004GLF")
    (property "Manufacturer" "Bourns")
    (property "Sheetfile" "power.kicad_sch")
    (property "Sheetname" "Power")
    (property "Tolerance" "1%")
    (property "Val" "1M")
    (property "ki_description" "SMD Chip Resistor, 1 Mohm, ± 1%, 62.5 mW, 0402 [1005 Metric], Thick Film, General Purpose")
    (property "ki_keywords" "0402, SMT, RESISTOR, PASSIVE")
    (attr smd)
    (fp_text reference "R21" (at -2.832 -0.4505) (layer "B.SilkS")
        (effects (font (size 0.7 0.7) (thickness 0.15)) (justify left bottom mirror))
    )
    (fp_text value "R_1M_0402" (at -1.011843 -1.772047) (layer "B.Fab")
        (effects (font (size 0.7 0.7) (thickness 0.15)) (justify left bottom mirror))
    )
    (fp_text user "${REFERENCE}" (at -0.95 -3.168) (layer "B.Fab") hide
        (effects (font (size 0.7 0.7) (thickness 0.15)) (justify left bottom mirror))
    )
    (fp_text user "License: Apache-2.0" (at -0.95 -5.169) (layer "B.Fab") hide
        (effects (font (size 0.7 0.7) (thickness 0.15)) (justify left bottom mirror))
    )
    (fp_text user "Author: Antmicro" (at -0.95 -4.169) (layer "B.Fab") hide
        (effects (font (size 0.7 0.7) (thickness 0.15)) (justify left bottom mirror))
    )
    (fp_rect (start -0.925 0.47) (end 0.925 -0.47)
      (stroke (width 0.05) (type default)) (fill none) (layer "B.CrtYd"))
    (fp_rect (start -0.5 0.25) (end 0.5 -0.25)
      (stroke (width 0.15) (type solid)) (fill none) (layer "B.Fab"))
    (pad "1" smd roundrect (at -0.48 0 180) (size 0.59 0.64) (layers "B.Cu" "B.Paste" "B.Mask") (roundrect_rratio 0.25)
      (net 1 "GND") (pintype "passive"))
    (pad "2" smd roundrect (at 0.48 0 180) (size 0.59 0.64) (layers "B.Cu" "B.Paste" "B.Mask") (roundrect_rratio 0.25)
      (net 156 "Net-(U3-UART_RX)") (pintype "passive"))
  )

  (footprint "antmicro-footprints:C_0402_1005Metric" (layer "B.Cu")
    (at 136.5 92.65 -90)
    (descr "Capacitor SMD 0402")
    (tags "capacitor SMD 0402")
    (property "Author" "Antmicro")
    (property "Dielectric" "")
    (property "License" "Apache-2.0")
    (property "MPN" "CC0402KRX5R6BB224")
    (property "Manufacturer" "YAGEO")
    (property "Sheetfile" "tb.kicad_sch")
    (property "Sheetname" "TB Controller")
    (property "Val" "220n")
    (property "Voltage" "")
    (property "ki_description" "SMD Multilayer Ceramic Capacitor, 0.22 µF, 10 V, 0402 [1005 Metric], ± 10%, X5R, CC Series")
    (property "ki_keywords" "0402, SMT, CAPACITOR, PASSIVE, MLCC, CERAMIC")
    (attr smd)
    (fp_text reference "C107" (at -3.877 -0.47 90) (layer "B.SilkS")
        (effects (font (size 0.7 0.7) (thickness 0.15)) (justify left bottom mirror))
    )
    (fp_text value "C_220n_0402" (at -1.022927 -2.155213 90) (layer "B.Fab")
        (effects (font (size 0.7 0.7) (thickness 0.15)) (justify left bottom mirror))
    )
    (fp_text user "${REFERENCE}" (at -0.939 -4.599 90) (layer "B.Fab") hide
        (effects (font (size 0.7 0.7) (thickness 0.15)) (justify left bottom mirror))
    )
    (fp_text user "Author: Antmicro" (at -0.939 -3.399 90) (layer "B.Fab") hide
        (effects (font (size 0.7 0.7) (thickness 0.15)) (justify left bottom mirror))
    )
    (fp_text user "License: Apache-2.0" (at -0.939 -5.799 90) (layer "B.Fab") hide
        (effects (font (size 0.7 0.7) (thickness 0.15)) (justify left bottom mirror))
    )
    (fp_rect (start -0.925 0.47) (end 0.925 -0.47)
      (stroke (width 0.05) (type default)) (fill none) (layer "B.CrtYd"))
    (fp_line (start -0.494 -0.248) (end -0.494 0.25)
      (stroke (width 0.15) (type solid)) (layer "B.Fab"))
    (fp_line (start -0.494 0.25) (end 0.504 0.25)
      (stroke (width 0.15) (type solid)) (layer "B.Fab"))
    (fp_line (start 0.504 -0.248) (end -0.494 -0.248)
      (stroke (width 0.15) (type solid)) (layer "B.Fab"))
    (fp_line (start 0.504 0.25) (end 0.504 -0.248)
      (stroke (width 0.15) (type solid)) (layer "B.Fab"))
    (pad "1" smd roundrect (at -0.48 0 270) (size 0.59 0.64) (layers "B.Cu" "B.Paste" "B.Mask") (roundrect_rratio 0.25)
      (net 78 "/TB Controller/TX2_N") (pintype "passive"))
    (pad "2" smd roundrect (at 0.48 0 270) (size 0.59 0.64) (layers "B.Cu" "B.Paste" "B.Mask") (roundrect_rratio 0.25)
      (net 26 "PCIE_TX2_N") (pintype "passive"))
  )

  (footprint "antmicro-footprints:R_0402_1005Metric" (layer "B.Cu")
    (at 160.91 59.47 -90)
    (descr "Resistor SMD 0402")
    (tags "resistor SMD 0402")
    (property "Author" "Antmicro")
    (property "License" "Apache-2.0")
    (property "MPN" "CR0402-FX-1003GLF")
    (property "Manufacturer" "Bourns")
    (property "Sheetfile" "power.kicad_sch")
    (property "Sheetname" "Power")
    (property "Tolerance" "1%")
    (property "Val" "100k")
    (property "ki_description" "SMD Chip Resistor, 100 kohm, ± 1%, 62.5 mW, 0402 [1005 Metric], Thick Film, General Purpose")
    (property "ki_keywords" "0402, SMT, RESISTOR, PASSIVE")
    (attr smd)
    (fp_text reference "R4" (at -3.082 -0.507 90) (layer "B.SilkS")
        (effects (font (size 0.7 0.7) (thickness 0.15)) (justify left bottom mirror))
    )
    (fp_text value "R_100k_0402" (at -1.011843 -1.772047 90) (layer "B.Fab")
        (effects (font (size 0.7 0.7) (thickness 0.15)) (justify left bottom mirror))
    )
    (fp_text user "Author: Antmicro" (at -0.95 -4.169 90) (layer "B.Fab") hide
        (effects (font (size 0.7 0.7) (thickness 0.15)) (justify left bottom mirror))
    )
    (fp_text user "${REFERENCE}" (at -0.95 -3.168 90) (layer "B.Fab") hide
        (effects (font (size 0.7 0.7) (thickness 0.15)) (justify left bottom mirror))
    )
    (fp_text user "License: Apache-2.0" (at -0.95 -5.169 90) (layer "B.Fab") hide
        (effects (font (size 0.7 0.7) (thickness 0.15)) (justify left bottom mirror))
    )
    (fp_rect (start -0.925 0.47) (end 0.925 -0.47)
      (stroke (width 0.05) (type default)) (fill none) (layer "B.CrtYd"))
    (fp_rect (start -0.5 0.25) (end 0.5 -0.25)
      (stroke (width 0.15) (type solid)) (fill none) (layer "B.Fab"))
    (pad "1" smd roundrect (at -0.48 0 270) (size 0.59 0.64) (layers "B.Cu" "B.Paste" "B.Mask") (roundrect_rratio 0.25)
      (net 1 "GND") (pintype "passive"))
    (pad "2" smd roundrect (at 0.48 0 270) (size 0.59 0.64) (layers "B.Cu" "B.Paste" "B.Mask") (roundrect_rratio 0.25)
      (net 58 "HPD") (pintype "passive"))
  )

  (footprint "antmicro-footprints:R_0402_1005Metric" (layer "B.Cu")
    (at 116.19 91.63 90)
    (descr "Resistor SMD 0402")
    (tags "resistor SMD 0402")
    (property "Author" "Antmicro")
    (property "License" "Apache-2.0")
    (property "MPN" "CR0402-FX-2201GLF")
    (property "Manufacturer" "Bourns")
    (property "Sheetfile" "power.kicad_sch")
    (property "Sheetname" "Power")
    (property "Tolerance" "1%")
    (property "Val" "2k2")
    (property "ki_description" "SMD Chip Resistor, 2.2 kohm, ± 1%, 62.5 mW, 0402 [1005 Metric], Thick Film, General Purpose")
    (property "ki_keywords" "0402, SMT, RESISTOR, PASSIVE")
    (attr smd)
    (fp_text reference "R46" (at 1.079 3.515 270) (layer "B.SilkS")
        (effects (font (size 0.7 0.7) (thickness 0.15)) (justify left bottom mirror))
    )
    (fp_text value "R_2k2_0402" (at -1.011843 -1.772047 270) (layer "B.Fab")
        (effects (font (size 0.7 0.7) (thickness 0.15)) (justify left bottom mirror))
    )
    (fp_text user "Author: Antmicro" (at -0.95 -4.169 270) (layer "B.Fab") hide
        (effects (font (size 0.7 0.7) (thickness 0.15)) (justify left bottom mirror))
    )
    (fp_text user "${REFERENCE}" (at -0.95 -3.168 270) (layer "B.Fab") hide
        (effects (font (size 0.7 0.7) (thickness 0.15)) (justify left bottom mirror))
    )
    (fp_text user "License: Apache-2.0" (at -0.95 -5.169 270) (layer "B.Fab") hide
        (effects (font (size 0.7 0.7) (thickness 0.15)) (justify left bottom mirror))
    )
    (fp_rect (start -0.925 0.47) (end 0.925 -0.47)
      (stroke (width 0.05) (type default)) (fill none) (layer "B.CrtYd"))
    (fp_rect (start -0.5 0.25) (end 0.5 -0.25)
      (stroke (width 0.15) (type solid)) (fill none) (layer "B.Fab"))
    (pad "1" smd roundrect (at -0.48 0 90) (size 0.59 0.64) (layers "B.Cu" "B.Paste" "B.Mask") (roundrect_rratio 0.25)
      (net 1 "GND") (pintype "passive"))
    (pad "2" smd roundrect (at 0.48 0 90) (size 0.59 0.64) (layers "B.Cu" "B.Paste" "B.Mask") (roundrect_rratio 0.25)
      (net 121 "Net-(D3-C)") (pintype "passive"))
  )

  (footprint "antmicro-footprints:R_0402_1005Metric" (layer "B.Cu")
    (at 141.325 66.82 90)
    (descr "Resistor SMD 0402")
    (tags "resistor SMD 0402")
    (property "Author" "Antmicro")
    (property "License" "Apache-2.0")
    (property "MPN" "CR0402-FX-1002GLF")
    (property "Manufacturer" "Bourns")
    (property "Sheetfile" "tb.kicad_sch")
    (property "Sheetname" "TB Controller")
    (property "Tolerance" "1%")
    (property "Val" "10k")
    (property "ki_description" "SMD Chip Resistor, 10 kohm, ± 1%, 62.5 mW, 0402 [1005 Metric], Thick Film, General Purpose")
    (property "ki_keywords" "0402, SMT, RESISTOR, PASSIVE")
    (attr smd)
    (fp_text reference "R85" (at 3.066 0.398 270) (layer "B.SilkS")
        (effects (font (size 0.7 0.7) (thickness 0.15)) (justify left bottom mirror))
    )
    (fp_text value "R_10k_0402" (at -1.011843 -1.772047 270) (layer "B.Fab")
        (effects (font (size 0.7 0.7) (thickness 0.15)) (justify left bottom mirror))
    )
    (fp_text user "License: Apache-2.0" (at -0.95 -5.169 270) (layer "B.Fab") hide
        (effects (font (size 0.7 0.7) (thickness 0.15)) (justify left bottom mirror))
    )
    (fp_text user "Author: Antmicro" (at -0.95 -4.169 270) (layer "B.Fab") hide
        (effects (font (size 0.7 0.7) (thickness 0.15)) (justify left bottom mirror))
    )
    (fp_text user "${REFERENCE}" (at -0.95 -3.168 270) (layer "B.Fab") hide
        (effects (font (size 0.7 0.7) (thickness 0.15)) (justify left bottom mirror))
    )
    (fp_rect (start -0.925 0.47) (end 0.925 -0.47)
      (stroke (width 0.05) (type default)) (fill none) (layer "B.CrtYd"))
    (fp_rect (start -0.5 0.25) (end 0.5 -0.25)
      (stroke (width 0.15) (type solid)) (fill none) (layer "B.Fab"))
    (pad "1" smd roundrect (at -0.48 0 90) (size 0.59 0.64) (layers "B.Cu" "B.Paste" "B.Mask") (roundrect_rratio 0.25)
      (net 200 "Net-(U4C-POC_GPIO_3)") (pintype "passive"))
    (pad "2" smd roundrect (at 0.48 0 90) (size 0.59 0.64) (layers "B.Cu" "B.Paste" "B.Mask") (roundrect_rratio 0.25)
      (net 1 "GND") (pintype "passive"))
  )

  (footprint "antmicro-footprints:R_0402_1005Metric" (layer "B.Cu")
    (at 106.83 91.765 -90)
    (descr "Resistor SMD 0402")
    (tags "resistor SMD 0402")
    (property "Author" "Antmicro")
    (property "License" "Apache-2.0")
    (property "MPN" "CR0402-FX-1002GLF")
    (property "Manufacturer" "Bourns")
    (property "Sheetfile" "power.kicad_sch")
    (property "Sheetname" "Power")
    (property "Tolerance" "1%")
    (property "Val" "10k")
    (property "ki_description" "SMD Chip Resistor, 10 kohm, ± 1%, 62.5 mW, 0402 [1005 Metric], Thick Film, General Purpose")
    (property "ki_keywords" "0402, SMT, RESISTOR, PASSIVE")
    (attr smd)
    (fp_text reference "R93" (at -1.087 0.658 90) (layer "B.SilkS")
        (effects (font (size 0.7 0.7) (thickness 0.15)) (justify left bottom mirror))
    )
    (fp_text value "R_10k_0402" (at -1.011843 -1.772047 90) (layer "B.Fab")
        (effects (font (size 0.7 0.7) (thickness 0.15)) (justify left bottom mirror))
    )
    (fp_text user "License: Apache-2.0" (at -0.95 -5.169 90) (layer "B.Fab") hide
        (effects (font (size 0.7 0.7) (thickness 0.15)) (justify left bottom mirror))
    )
    (fp_text user "${REFERENCE}" (at -0.95 -3.168 90) (layer "B.Fab") hide
        (effects (font (size 0.7 0.7) (thickness 0.15)) (justify left bottom mirror))
    )
    (fp_text user "Author: Antmicro" (at -0.95 -4.169 90) (layer "B.Fab") hide
        (effects (font (size 0.7 0.7) (thickness 0.15)) (justify left bottom mirror))
    )
    (fp_rect (start -0.925 0.47) (end 0.925 -0.47)
      (stroke (width 0.05) (type default)) (fill none) (layer "B.CrtYd"))
    (fp_rect (start -0.5 0.25) (end 0.5 -0.25)
      (stroke (width 0.15) (type solid)) (fill none) (layer "B.Fab"))
    (pad "1" smd roundrect (at -0.48 0 270) (size 0.59 0.64) (layers "B.Cu" "B.Paste" "B.Mask") (roundrect_rratio 0.25)
      (net 1 "GND") (pintype "passive"))
    (pad "2" smd roundrect (at 0.48 0 270) (size 0.59 0.64) (layers "B.Cu" "B.Paste" "B.Mask") (roundrect_rratio 0.25)
      (net 141 "Net-(Q3-REF)") (pintype "passive"))
  )

  (footprint "antmicro-footprints:C_0402_1005Metric" (layer "B.Cu")
    (at 113.675 84.69 180)
    (descr "Capacitor SMD 0402")
    (tags "capacitor SMD 0402")
    (property "Author" "Antmicro")
    (property "Dielectric" "")
    (property "License" "Apache-2.0")
    (property "MPN" "GCM155R71H223MA55D")
    (property "Manufacturer" "Murata")
    (property "Sheetfile" "power.kicad_sch")
    (property "Sheetname" "Power")
    (property "Val" "22n")
    (property "Voltage" "")
    (property "ki_description" "SMD Multilayer Ceramic Capacitors, 0.022 µF, 50 V, 20%, 0402 [1005 Metric], X7R")
    (property "ki_keywords" "0402, SMT, CAPACITOR, PASSIVE, CERAMIC, MLCC")
    (attr smd)
    (fp_text reference "C19" (at -3.038 -0.4) (layer "B.SilkS")
        (effects (font (size 0.7 0.7) (thickness 0.15)) (justify left bottom mirror))
    )
    (fp_text value "C_22n_0402" (at -1.022927 -2.155213) (layer "B.Fab")
        (effects (font (size 0.7 0.7) (thickness 0.15)) (justify left bottom mirror))
    )
    (fp_text user "${REFERENCE}" (at -0.939 -4.599) (layer "B.Fab") hide
        (effects (font (size 0.7 0.7) (thickness 0.15)) (justify left bottom mirror))
    )
    (fp_text user "Author: Antmicro" (at -0.939 -3.399) (layer "B.Fab") hide
        (effects (font (size 0.7 0.7) (thickness 0.15)) (justify left bottom mirror))
    )
    (fp_text user "License: Apache-2.0" (at -0.939 -5.799) (layer "B.Fab") hide
        (effects (font (size 0.7 0.7) (thickness 0.15)) (justify left bottom mirror))
    )
    (fp_rect (start -0.925 0.47) (end 0.925 -0.47)
      (stroke (width 0.05) (type default)) (fill none) (layer "B.CrtYd"))
    (fp_line (start -0.494 -0.248) (end -0.494 0.25)
      (stroke (width 0.15) (type solid)) (layer "B.Fab"))
    (fp_line (start -0.494 0.25) (end 0.504 0.25)
      (stroke (width 0.15) (type solid)) (layer "B.Fab"))
    (fp_line (start 0.504 -0.248) (end -0.494 -0.248)
      (stroke (width 0.15) (type solid)) (layer "B.Fab"))
    (fp_line (start 0.504 0.25) (end 0.504 -0.248)
      (stroke (width 0.15) (type solid)) (layer "B.Fab"))
    (pad "1" smd roundrect (at -0.48 0 180) (size 0.59 0.64) (layers "B.Cu" "B.Paste" "B.Mask") (roundrect_rratio 0.25)
      (net 1 "GND") (pintype "passive"))
    (pad "2" smd roundrect (at 0.48 0 180) (size 0.59 0.64) (layers "B.Cu" "B.Paste" "B.Mask") (roundrect_rratio 0.25)
      (net 92 "Net-(U1-SS)") (pintype "passive"))
  )

  (footprint "antmicro-footprints:R_0402_1005Metric" (layer "B.Cu")
    (at 158.91 67.47 90)
    (descr "Resistor SMD 0402")
    (tags "resistor SMD 0402")
    (property "Author" "Antmicro")
    (property "License" "Apache-2.0")
    (property "MPN" "CR0402-FX-5101GLF")
    (property "Manufacturer" "Bourns")
    (property "Sheetfile" "power.kicad_sch")
    (property "Sheetname" "Power")
    (property "Tolerance" "1%")
    (property "Val" "5k1")
    (property "ki_description" "SMD Chip Resistor, 5.1 kohm, ± 1%, 63 mW, 0402 [1005 Metric], Thick Film, General Purpose")
    (property "ki_keywords" "0402, SMT, RESISTOR, PASSIVE")
    (attr smd)
    (fp_text reference "R40" (at -0.983 0.491 270) (layer "B.SilkS")
        (effects (font (size 0.7 0.7) (thickness 0.15)) (justify left bottom mirror))
    )
    (fp_text value "R_5k1_0402" (at -1.011843 -1.772047 270) (layer "B.Fab")
        (effects (font (size 0.7 0.7) (thickness 0.15)) (justify left bottom mirror))
    )
    (fp_text user "Author: Antmicro" (at -0.95 -4.169 270) (layer "B.Fab") hide
        (effects (font (size 0.7 0.7) (thickness 0.15)) (justify left bottom mirror))
    )
    (fp_text user "${REFERENCE}" (at -0.95 -3.168 270) (layer "B.Fab") hide
        (effects (font (size 0.7 0.7) (thickness 0.15)) (justify left bottom mirror))
    )
    (fp_text user "License: Apache-2.0" (at -0.95 -5.169 270) (layer "B.Fab") hide
        (effects (font (size 0.7 0.7) (thickness 0.15)) (justify left bottom mirror))
    )
    (fp_rect (start -0.925 0.47) (end 0.925 -0.47)
      (stroke (width 0.05) (type default)) (fill none) (layer "B.CrtYd"))
    (fp_rect (start -0.5 0.25) (end 0.5 -0.25)
      (stroke (width 0.15) (type solid)) (fill none) (layer "B.Fab"))
    (pad "1" smd roundrect (at -0.48 0 90) (size 0.59 0.64) (layers "B.Cu" "B.Paste" "B.Mask") (roundrect_rratio 0.25)
      (net 1 "GND") (pintype "passive"))
    (pad "2" smd roundrect (at 0.48 0 90) (size 0.59 0.64) (layers "B.Cu" "B.Paste" "B.Mask") (roundrect_rratio 0.25)
      (net 11 "CC1") (pintype "passive"))
  )

  (footprint "antmicro-footprints:R_0402_1005Metric" (layer "B.Cu")
    (at 159.91 67.47 90)
    (descr "Resistor SMD 0402")
    (tags "resistor SMD 0402")
    (property "Author" "Antmicro")
    (property "License" "Apache-2.0")
    (property "MPN" "CR0402-FX-5101GLF")
    (property "Manufacturer" "Bourns")
    (property "Sheetfile" "power.kicad_sch")
    (property "Sheetname" "Power")
    (property "Tolerance" "1%")
    (property "Val" "5k1")
    (property "ki_description" "SMD Chip Resistor, 5.1 kohm, ± 1%, 63 mW, 0402 [1005 Metric], Thick Film, General Purpose")
    (property "ki_keywords" "0402, SMT, RESISTOR, PASSIVE")
    (attr smd)
    (fp_text reference "R38" (at -0.983 0.491 270) (layer "B.SilkS")
        (effects (font (size 0.7 0.7) (thickness 0.15)) (justify left bottom mirror))
    )
    (fp_text value "R_5k1_0402" (at -1.011843 -1.772047 270) (layer "B.Fab")
        (effects (font (size 0.7 0.7) (thickness 0.15)) (justify left bottom mirror))
    )
    (fp_text user "License: Apache-2.0" (at -0.95 -5.169 270) (layer "B.Fab") hide
        (effects (font (size 0.7 0.7) (thickness 0.15)) (justify left bottom mirror))
    )
    (fp_text user "${REFERENCE}" (at -0.95 -3.168 270) (layer "B.Fab") hide
        (effects (font (size 0.7 0.7) (thickness 0.15)) (justify left bottom mirror))
    )
    (fp_text user "Author: Antmicro" (at -0.95 -4.169 270) (layer "B.Fab") hide
        (effects (font (size 0.7 0.7) (thickness 0.15)) (justify left bottom mirror))
    )
    (fp_rect (start -0.925 0.47) (end 0.925 -0.47)
      (stroke (width 0.05) (type default)) (fill none) (layer "B.CrtYd"))
    (fp_rect (start -0.5 0.25) (end 0.5 -0.25)
      (stroke (width 0.15) (type solid)) (fill none) (layer "B.Fab"))
    (pad "1" smd roundrect (at -0.48 0 90) (size 0.59 0.64) (layers "B.Cu" "B.Paste" "B.Mask") (roundrect_rratio 0.25)
      (net 1 "GND") (pintype "passive"))
    (pad "2" smd roundrect (at 0.48 0 90) (size 0.59 0.64) (layers "B.Cu" "B.Paste" "B.Mask") (roundrect_rratio 0.25)
      (net 10 "CC2") (pintype "passive"))
  )

  (footprint "antmicro-footprints:C_0402_1005Metric" (layer "B.Cu")
    (at 111.725 82.67 180)
    (descr "Capacitor SMD 0402")
    (tags "capacitor SMD 0402")
    (property "Author" "Antmicro")
    (property "Dielectric" "X5R")
    (property "License" "Apache-2.0")
    (property "MPN" "GRM155R61H104KE14D")
    (property "Manufacturer" "Murata")
    (property "Sheetfile" "power.kicad_sch")
    (property "Sheetname" "Power")
    (property "Val" "100n")
    (property "Voltage" "50V")
    (property "ki_description" "SMD Multilayer Ceramic Capacitor, 0.1 µF, 50 V, 0402 [1005 Metric], ± 10%, X5R, GRM Series")
    (property "ki_keywords" "0402, SMT, CAPACITOR, PASSIVE, CERAMIC, MLCC")
    (attr smd)
    (fp_text reference "C29" (at -1.051 4.692) (layer "B.SilkS")
        (effects (font (size 0.7 0.7) (thickness 0.15)) (justify left bottom mirror))
    )
    (fp_text value "C_100n_0402" (at -1.022927 -2.155213) (layer "B.Fab")
        (effects (font (size 0.7 0.7) (thickness 0.15)) (justify left bottom mirror))
    )
    (fp_text user "License: Apache-2.0" (at -0.939 -5.799) (layer "B.Fab") hide
        (effects (font (size 0.7 0.7) (thickness 0.15)) (justify left bottom mirror))
    )
    (fp_text user "Author: Antmicro" (at -0.939 -3.399) (layer "B.Fab") hide
        (effects (font (size 0.7 0.7) (thickness 0.15)) (justify left bottom mirror))
    )
    (fp_text user "${REFERENCE}" (at -0.939 -4.599) (layer "B.Fab") hide
        (effects (font (size 0.7 0.7) (thickness 0.15)) (justify left bottom mirror))
    )
    (fp_rect (start -0.925 0.47) (end 0.925 -0.47)
      (stroke (width 0.05) (type default)) (fill none) (layer "B.CrtYd"))
    (fp_line (start -0.494 -0.248) (end -0.494 0.25)
      (stroke (width 0.15) (type solid)) (layer "B.Fab"))
    (fp_line (start -0.494 0.25) (end 0.504 0.25)
      (stroke (width 0.15) (type solid)) (layer "B.Fab"))
    (fp_line (start 0.504 -0.248) (end -0.494 -0.248)
      (stroke (width 0.15) (type solid)) (layer "B.Fab"))
    (fp_line (start 0.504 0.25) (end 0.504 -0.248)
      (stroke (width 0.15) (type solid)) (layer "B.Fab"))
    (pad "1" smd roundrect (at -0.48 0 180) (size 0.59 0.64) (layers "B.Cu" "B.Paste" "B.Mask") (roundrect_rratio 0.25)
      (net 97 "Net-(U1-EXTVCC)") (pintype "passive"))
    (pad "2" smd roundrect (at 0.48 0 180) (size 0.59 0.64) (layers "B.Cu" "B.Paste" "B.Mask") (roundrect_rratio 0.25)
      (net 1 "GND") (pintype "passive"))
  )

  (footprint "antmicro-footprints:R_0402_1005Metric" (layer "B.Cu")
    (at 161.41 62.97 180)
    (descr "Resistor SMD 0402")
    (tags "resistor SMD 0402")
    (property "Author" "Antmicro")
    (property "License" "Apache-2.0")
    (property "MPN" "CR0402-FX-1002GLF")
    (property "Manufacturer" "Bourns")
    (property "Sheetfile" "power.kicad_sch")
    (property "Sheetname" "Power")
    (property "Tolerance" "1%")
    (property "Val" "10k")
    (property "ki_description" "SMD Chip Resistor, 10 kohm, ± 1%, 62.5 mW, 0402 [1005 Metric], Thick Film, General Purpose")
    (property "ki_keywords" "0402, SMT, RESISTOR, PASSIVE")
    (attr smd)
    (fp_text reference "R19" (at -3.182 -0.403) (layer "B.SilkS")
        (effects (font (size 0.7 0.7) (thickness 0.15)) (justify left bottom mirror))
    )
    (fp_text value "R_10k_0402" (at -1.011843 -1.772047) (layer "B.Fab")
        (effects (font (size 0.7 0.7) (thickness 0.15)) (justify left bottom mirror))
    )
    (fp_text user "${REFERENCE}" (at -0.95 -3.168) (layer "B.Fab") hide
        (effects (font (size 0.7 0.7) (thickness 0.15)) (justify left bottom mirror))
    )
    (fp_text user "License: Apache-2.0" (at -0.95 -5.169) (layer "B.Fab") hide
        (effects (font (size 0.7 0.7) (thickness 0.15)) (justify left bottom mirror))
    )
    (fp_text user "Author: Antmicro" (at -0.95 -4.169) (layer "B.Fab") hide
        (effects (font (size 0.7 0.7) (thickness 0.15)) (justify left bottom mirror))
    )
    (fp_rect (start -0.925 0.47) (end 0.925 -0.47)
      (stroke (width 0.05) (type default)) (fill none) (layer "B.CrtYd"))
    (fp_rect (start -0.5 0.25) (end 0.5 -0.25)
      (stroke (width 0.15) (type solid)) (fill none) (layer "B.Fab"))
    (pad "1" smd roundrect (at -0.48 0 180) (size 0.59 0.64) (layers "B.Cu" "B.Paste" "B.Mask") (roundrect_rratio 0.25)
      (net 9 "/Power/TPS_3V3") (pintype "passive"))
    (pad "2" smd roundrect (at 0.48 0 180) (size 0.59 0.64) (layers "B.Cu" "B.Paste" "B.Mask") (roundrect_rratio 0.25)
      (net 154 "Net-(U3-GPIO6)") (pintype "passive"))
  )

  (footprint "antmicro-footprints:C_0402_1005Metric" (layer "B.Cu")
    (at 129.46 80.34 -90)
    (descr "Capacitor SMD 0402")
    (tags "capacitor SMD 0402")
    (property "Author" "Antmicro")
    (property "Dielectric" "X5R")
    (property "License" "Apache-2.0")
    (property "MPN" "GRM155R61H104KE14D")
    (property "Manufacturer" "Murata")
    (property "Sheetfile" "tb-power.kicad_sch")
    (property "Sheetname" "Thunderbolt Controller - Power")
    (property "Val" "100n")
    (property "Voltage" "50V")
    (property "ki_description" "SMD Multilayer Ceramic Capacitor, 0.1 µF, 50 V, 0402 [1005 Metric], ± 10%, X5R, GRM Series")
    (property "ki_keywords" "0402, SMT, CAPACITOR, PASSIVE, CERAMIC, MLCC")
    (attr smd)
    (fp_text reference "C97" (at -0.965 2.537 90) (layer "B.SilkS")
        (effects (font (size 0.7 0.7) (thickness 0.15)) (justify left bottom mirror))
    )
    (fp_text value "C_100n_0402" (at -1.022927 -2.155213 90) (layer "B.Fab")
        (effects (font (size 0.7 0.7) (thickness 0.15)) (justify left bottom mirror))
    )
    (fp_text user "License: Apache-2.0" (at -0.939 -5.799 90) (layer "B.Fab") hide
        (effects (font (size 0.7 0.7) (thickness 0.15)) (justify left bottom mirror))
    )
    (fp_text user "${REFERENCE}" (at -0.939 -4.599 90) (layer "B.Fab") hide
        (effects (font (size 0.7 0.7) (thickness 0.15)) (justify left bottom mirror))
    )
    (fp_text user "Author: Antmicro" (at -0.939 -3.399 90) (layer "B.Fab") hide
        (effects (font (size 0.7 0.7) (thickness 0.15)) (justify left bottom mirror))
    )
    (fp_rect (start -0.925 0.47) (end 0.925 -0.47)
      (stroke (width 0.05) (type default)) (fill none) (layer "B.CrtYd"))
    (fp_line (start -0.494 -0.248) (end -0.494 0.25)
      (stroke (width 0.15) (type solid)) (layer "B.Fab"))
    (fp_line (start -0.494 0.25) (end 0.504 0.25)
      (stroke (width 0.15) (type solid)) (layer "B.Fab"))
    (fp_line (start 0.504 -0.248) (end -0.494 -0.248)
      (stroke (width 0.15) (type solid)) (layer "B.Fab"))
    (fp_line (start 0.504 0.25) (end 0.504 -0.248)
      (stroke (width 0.15) (type solid)) (layer "B.Fab"))
    (pad "1" smd roundrect (at -0.48 0 270) (size 0.59 0.64) (layers "B.Cu" "B.Paste" "B.Mask") (roundrect_rratio 0.25)
      (net 1 "GND") (pintype "passive"))
    (pad "2" smd roundrect (at 0.48 0 270) (size 0.59 0.64) (layers "B.Cu" "B.Paste" "B.Mask") (roundrect_rratio 0.25)
      (net 2 "3V3_SYS") (pintype "passive"))
  )

  (footprint "antmicro-footprints:R_0402_1005Metric" (layer "B.Cu")
    (at 107.425 84.17 90)
    (descr "Resistor SMD 0402")
    (tags "resistor SMD 0402")
    (property "Author" "Antmicro")
    (property "Current" "1A")
    (property "License" "Apache-2.0")
    (property "MPN" "ERJ2GE0R00X")
    (property "Manufacturer" "Panasonic")
    (property "Sheetfile" "power.kicad_sch")
    (property "Sheetname" "Power")
    (property "Tolerance" "")
    (property "Val" "0R")
    (property "ki_description" "SMD Chip Resistor, Jumper, 0 ohm, 100 mW, 0402 [1005 Metric], Thick Film, General Purpose")
    (property "ki_keywords" "0402, SMT, RESISTOR, PASSIVE")
    (attr smd)
    (fp_text reference "R13" (at 0.985 -0.618 270) (layer "B.SilkS")
        (effects (font (size 0.7 0.7) (thickness 0.15)) (justify left bottom mirror))
    )
    (fp_text value "R_0R_0402" (at -1.011843 -1.772047 270) (layer "B.Fab")
        (effects (font (size 0.7 0.7) (thickness 0.15)) (justify left bottom mirror))
    )
    (fp_text user "Author: Antmicro" (at -0.95 -4.169 270) (layer "B.Fab") hide
        (effects (font (size 0.7 0.7) (thickness 0.15)) (justify left bottom mirror))
    )
    (fp_text user "License: Apache-2.0" (at -0.95 -5.169 270) (layer "B.Fab") hide
        (effects (font (size 0.7 0.7) (thickness 0.15)) (justify left bottom mirror))
    )
    (fp_text user "${REFERENCE}" (at -0.95 -3.168 270) (layer "B.Fab") hide
        (effects (font (size 0.7 0.7) (thickness 0.15)) (justify left bottom mirror))
    )
    (fp_rect (start -0.925 0.47) (end 0.925 -0.47)
      (stroke (width 0.05) (type default)) (fill none) (layer "B.CrtYd"))
    (fp_rect (start -0.5 0.25) (end 0.5 -0.25)
      (stroke (width 0.15) (type solid)) (fill none) (layer "B.Fab"))
    (pad "1" smd roundrect (at -0.48 0 90) (size 0.59 0.64) (layers "B.Cu" "B.Paste" "B.Mask") (roundrect_rratio 0.25)
      (net 5 "Net-(U1-VREF)") (pintype "passive"))
    (pad "2" smd roundrect (at 0.48 0 90) (size 0.59 0.64) (layers "B.Cu" "B.Paste" "B.Mask") (roundrect_rratio 0.25)
      (net 148 "Net-(U1-LOADEN)") (pintype "passive"))
  )

  (footprint "antmicro-footprints:R_0402_1005Metric" (layer "B.Cu")
    (at 145.62 76.96)
    (descr "Resistor SMD 0402")
    (tags "resistor SMD 0402")
    (property "Author" "Antmicro")
    (property "License" "Apache-2.0")
    (property "MPN" "CR0402-FX-1004GLF")
    (property "Manufacturer" "Bourns")
    (property "Sheetfile" "tb.kicad_sch")
    (property "Sheetname" "TB Controller")
    (property "Tolerance" "1%")
    (property "Val" "1M")
    (property "ki_description" "SMD Chip Resistor, 1 Mohm, ± 1%, 62.5 mW, 0402 [1005 Metric], Thick Film, General Purpose")
    (property "ki_keywords" "0402, SMT, RESISTOR, PASSIVE")
    (attr smd)
    (fp_text reference "R55" (at 3.097 0.383 180) (layer "B.SilkS")
        (effects (font (size 0.7 0.7) (thickness 0.15)) (justify left bottom mirror))
    )
    (fp_text value "R_1M_0402" (at -1.011843 -1.772047 180) (layer "B.Fab")
        (effects (font (size 0.7 0.7) (thickness 0.15)) (justify left bottom mirror))
    )
    (fp_text user "License: Apache-2.0" (at -0.95 -5.169 180) (layer "B.Fab") hide
        (effects (font (size 0.7 0.7) (thickness 0.15)) (justify left bottom mirror))
    )
    (fp_text user "Author: Antmicro" (at -0.95 -4.169 180) (layer "B.Fab") hide
        (effects (font (size 0.7 0.7) (thickness 0.15)) (justify left bottom mirror))
    )
    (fp_text user "${REFERENCE}" (at -0.95 -3.168 180) (layer "B.Fab") hide
        (effects (font (size 0.7 0.7) (thickness 0.15)) (justify left bottom mirror))
    )
    (fp_rect (start -0.925 0.47) (end 0.925 -0.47)
      (stroke (width 0.05) (type default)) (fill none) (layer "B.CrtYd"))
    (fp_rect (start -0.5 0.25) (end 0.5 -0.25)
      (stroke (width 0.15) (type solid)) (fill none) (layer "B.Fab"))
    (pad "1" smd roundrect (at -0.48 0) (size 0.59 0.64) (layers "B.Cu" "B.Paste" "B.Mask") (roundrect_rratio 0.25)
      (net 1 "GND") (pintype "passive"))
    (pad "2" smd roundrect (at 0.48 0) (size 0.59 0.64) (layers "B.Cu" "B.Paste" "B.Mask") (roundrect_rratio 0.25)
      (net 67 "LSX_R2P") (pintype "passive"))
  )

  (footprint "antmicro-footprints:R_0402_1005Metric" (layer "B.Cu")
    (at 139.275 66.82 -90)
    (descr "Resistor SMD 0402")
    (tags "resistor SMD 0402")
    (property "Author" "Antmicro")
    (property "License" "Apache-2.0")
    (property "MPN" "CR0402-FX-2201GLF")
    (property "Manufacturer" "Bourns")
    (property "Sheetfile" "tb.kicad_sch")
    (property "Sheetname" "TB Controller")
    (property "Tolerance" "1%")
    (property "Val" "2k2")
    (property "ki_description" "SMD Chip Resistor, 2.2 kohm, ± 1%, 62.5 mW, 0402 [1005 Metric], Thick Film, General Purpose")
    (property "ki_keywords" "0402, SMT, RESISTOR, PASSIVE")
    (attr smd)
    (fp_text reference "R62" (at -3.066 -0.416 90) (layer "B.SilkS")
        (effects (font (size 0.7 0.7) (thickness 0.15)) (justify left bottom mirror))
    )
    (fp_text value "R_2k2_0402" (at -1.011843 -1.772047 90) (layer "B.Fab")
        (effects (font (size 0.7 0.7) (thickness 0.15)) (justify left bottom mirror))
    )
    (fp_text user "Author: Antmicro" (at -0.95 -4.169 90) (layer "B.Fab") hide
        (effects (font (size 0.7 0.7) (thickness 0.15)) (justify left bottom mirror))
    )
    (fp_text user "License: Apache-2.0" (at -0.95 -5.169 90) (layer "B.Fab") hide
        (effects (font (size 0.7 0.7) (thickness 0.15)) (justify left bottom mirror))
    )
    (fp_text user "${REFERENCE}" (at -0.95 -3.168 90) (layer "B.Fab") hide
        (effects (font (size 0.7 0.7) (thickness 0.15)) (justify left bottom mirror))
    )
    (fp_rect (start -0.925 0.47) (end 0.925 -0.47)
      (stroke (width 0.05) (type default)) (fill none) (layer "B.CrtYd"))
    (fp_rect (start -0.5 0.25) (end 0.5 -0.25)
      (stroke (width 0.15) (type solid)) (fill none) (layer "B.Fab"))
    (pad "1" smd roundrect (at -0.48 0 270) (size 0.59 0.64) (layers "B.Cu" "B.Paste" "B.Mask") (roundrect_rratio 0.25)
      (net 1 "GND") (pintype "passive"))
    (pad "2" smd roundrect (at 0.48 0 270) (size 0.59 0.64) (layers "B.Cu" "B.Paste" "B.Mask") (roundrect_rratio 0.25)
      (net 176 "Net-(U4C-DPSNK1_DDC_DATA)") (pintype "passive"))
  )

  (footprint "antmicro-footprints:C_0402_1005Metric" (layer "B.Cu")
    (at 142.15 76.43 90)
    (descr "Capacitor SMD 0402")
    (tags "capacitor SMD 0402")
    (property "Author" "Antmicro")
    (property "Dielectric" "X5R")
    (property "License" "Apache-2.0")
    (property "MPN" "GRM155R61H104KE14D")
    (property "Manufacturer" "Murata")
    (property "Sheetfile" "tb-power.kicad_sch")
    (property "Sheetname" "Thunderbolt Controller - Power")
    (property "Val" "100n")
    (property "Voltage" "50V")
    (property "ki_description" "SMD Multilayer Ceramic Capacitor, 0.1 µF, 50 V, 0402 [1005 Metric], ± 10%, X5R, GRM Series")
    (property "ki_keywords" "0402, SMT, CAPACITOR, PASSIVE, CERAMIC, MLCC")
    (attr smd)
    (fp_text reference "C95" (at 5.437 1.487 270) (layer "B.SilkS")
        (effects (font (size 0.7 0.7) (thickness 0.15)) (justify left bottom mirror))
    )
    (fp_text value "C_100n_0402" (at -1.022927 -2.155213 270) (layer "B.Fab")
        (effects (font (size 0.7 0.7) (thickness 0.15)) (justify left bottom mirror))
    )
    (fp_text user "License: Apache-2.0" (at -0.939 -5.799 270) (layer "B.Fab") hide
        (effects (font (size 0.7 0.7) (thickness 0.15)) (justify left bottom mirror))
    )
    (fp_text user "${REFERENCE}" (at -0.939 -4.599 270) (layer "B.Fab") hide
        (effects (font (size 0.7 0.7) (thickness 0.15)) (justify left bottom mirror))
    )
    (fp_text user "Author: Antmicro" (at -0.939 -3.399 270) (layer "B.Fab") hide
        (effects (font (size 0.7 0.7) (thickness 0.15)) (justify left bottom mirror))
    )
    (fp_rect (start -0.925 0.47) (end 0.925 -0.47)
      (stroke (width 0.05) (type default)) (fill none) (layer "B.CrtYd"))
    (fp_line (start -0.494 -0.248) (end -0.494 0.25)
      (stroke (width 0.15) (type solid)) (layer "B.Fab"))
    (fp_line (start -0.494 0.25) (end 0.504 0.25)
      (stroke (width 0.15) (type solid)) (layer "B.Fab"))
    (fp_line (start 0.504 -0.248) (end -0.494 -0.248)
      (stroke (width 0.15) (type solid)) (layer "B.Fab"))
    (fp_line (start 0.504 0.25) (end 0.504 -0.248)
      (stroke (width 0.15) (type solid)) (layer "B.Fab"))
    (pad "1" smd roundrect (at -0.48 0 90) (size 0.59 0.64) (layers "B.Cu" "B.Paste" "B.Mask") (roundrect_rratio 0.25)
      (net 1 "GND") (pintype "passive"))
    (pad "2" smd roundrect (at 0.48 0 90) (size 0.59 0.64) (layers "B.Cu" "B.Paste" "B.Mask") (roundrect_rratio 0.25)
      (net 2 "3V3_SYS") (pintype "passive"))
  )

  (footprint "antmicro-footprints:R_0402_1005Metric" (layer "B.Cu")
    (at 128.19 77.84)
    (descr "Resistor SMD 0402")
    (tags "resistor SMD 0402")
    (property "Author" "Antmicro")
    (property "License" "Apache-2.0")
    (property "MPN" "CR0402-FX-1002GLF")
    (property "Manufacturer" "Bourns")
    (property "Sheetfile" "tb.kicad_sch")
    (property "Sheetname" "TB Controller")
    (property "Tolerance" "1%")
    (property "Val" "10k")
    (property "ki_description" "SMD Chip Resistor, 10 kohm, ± 1%, 62.5 mW, 0402 [1005 Metric], Thick Film, General Purpose")
    (property "ki_keywords" "0402, SMT, RESISTOR, PASSIVE")
    (attr smd)
    (fp_text reference "R56" (at -0.936 0.519 180) (layer "B.SilkS")
        (effects (font (size 0.7 0.7) (thickness 0.15)) (justify left bottom mirror))
    )
    (fp_text value "R_10k_0402" (at -1.011843 -1.772047 180) (layer "B.Fab")
        (effects (font (size 0.7 0.7) (thickness 0.15)) (justify left bottom mirror))
    )
    (fp_text user "${REFERENCE}" (at -0.95 -3.168 180) (layer "B.Fab") hide
        (effects (font (size 0.7 0.7) (thickness 0.15)) (justify left bottom mirror))
    )
    (fp_text user "Author: Antmicro" (at -0.95 -4.169 180) (layer "B.Fab") hide
        (effects (font (size 0.7 0.7) (thickness 0.15)) (justify left bottom mirror))
    )
    (fp_text user "License: Apache-2.0" (at -0.95 -5.169 180) (layer "B.Fab") hide
        (effects (font (size 0.7 0.7) (thickness 0.15)) (justify left bottom mirror))
    )
    (fp_rect (start -0.925 0.47) (end 0.925 -0.47)
      (stroke (width 0.05) (type default)) (fill none) (layer "B.CrtYd"))
    (fp_rect (start -0.5 0.25) (end 0.5 -0.25)
      (stroke (width 0.15) (type solid)) (fill none) (layer "B.Fab"))
    (pad "1" smd roundrect (at -0.48 0) (size 0.59 0.64) (layers "B.Cu" "B.Paste" "B.Mask") (roundrect_rratio 0.25)
      (net 2 "3V3_SYS") (pintype "passive"))
    (pad "2" smd roundrect (at 0.48 0) (size 0.59 0.64) (layers "B.Cu" "B.Paste" "B.Mask") (roundrect_rratio 0.25)
      (net 170 "Net-(U4B-PCIE_CLKREQ_N)") (pintype "passive"))
  )

  (footprint "antmicro-footprints:R_0402_1005Metric" (layer "B.Cu")
    (at 115.440001 63.675 90)
    (descr "Resistor SMD 0402")
    (tags "resistor SMD 0402")
    (property "Author" "Antmicro")
    (property "License" "Apache-2.0")
    (property "MPN" "CR0402-FX-1002GLF")
    (property "Manufacturer" "Bourns")
    (property "Sheetfile" "power.kicad_sch")
    (property "Sheetname" "Power")
    (property "Tolerance" "1%")
    (property "Val" "10k")
    (property "ki_description" "SMD Chip Resistor, 10 kohm, ± 1%, 62.5 mW, 0402 [1005 Metric], Thick Film, General Purpose")
    (property "ki_keywords" "0402, SMT, RESISTOR, PASSIVE")
    (attr smd)
    (fp_text reference "R11" (at 3.223 0.383999 270) (layer "B.SilkS")
        (effects (font (size 0.7 0.7) (thickness 0.15)) (justify left bottom mirror))
    )
    (fp_text value "R_10k_0402" (at -1.011843 -1.772047 270) (layer "B.Fab")
        (effects (font (size 0.7 0.7) (thickness 0.15)) (justify left bottom mirror))
    )
    (fp_text user "License: Apache-2.0" (at -0.95 -5.169 270) (layer "B.Fab") hide
        (effects (font (size 0.7 0.7) (thickness 0.15)) (justify left bottom mirror))
    )
    (fp_text user "${REFERENCE}" (at -0.95 -3.168 270) (layer "B.Fab") hide
        (effects (font (size 0.7 0.7) (thickness 0.15)) (justify left bottom mirror))
    )
    (fp_text user "Author: Antmicro" (at -0.95 -4.169 270) (layer "B.Fab") hide
        (effects (font (size 0.7 0.7) (thickness 0.15)) (justify left bottom mirror))
    )
    (fp_rect (start -0.925 0.47) (end 0.925 -0.47)
      (stroke (width 0.05) (type default)) (fill none) (layer "B.CrtYd"))
    (fp_rect (start -0.5 0.25) (end 0.5 -0.25)
      (stroke (width 0.15) (type solid)) (fill none) (layer "B.Fab"))
    (pad "1" smd roundrect (at -0.48 0 90) (size 0.59 0.64) (layers "B.Cu" "B.Paste" "B.Mask") (roundrect_rratio 0.25)
      (net 1 "GND") (pintype "passive"))
    (pad "2" smd roundrect (at 0.48 0 90) (size 0.59 0.64) (layers "B.Cu" "B.Paste" "B.Mask") (roundrect_rratio 0.25)
      (net 119 "Net-(D1-C)") (pintype "passive"))
  )

  (footprint "antmicro-footprints:C_0402_1005Metric" (layer "B.Cu")
    (at 108.915 79.65 180)
    (descr "Capacitor SMD 0402")
    (tags "capacitor SMD 0402")
    (property "Author" "Antmicro")
    (property "Dielectric" "X5R")
    (property "License" "Apache-2.0")
    (property "MPN" "GRM155R61H104KE14D")
    (property "Manufacturer" "Murata")
    (property "Sheetfile" "power.kicad_sch")
    (property "Sheetname" "Power")
    (property "Val" "100n")
    (property "Voltage" "50V")
    (property "ki_description" "SMD Multilayer Ceramic Capacitor, 0.1 µF, 50 V, 0402 [1005 Metric], ± 10%, X5R, GRM Series")
    (property "ki_keywords" "0402, SMT, CAPACITOR, PASSIVE, CERAMIC, MLCC")
    (attr smd)
    (fp_text reference "C26" (at -1.067 5.736) (layer "B.SilkS")
        (effects (font (size 0.7 0.7) (thickness 0.15)) (justify left bottom mirror))
    )
    (fp_text value "C_100n_0402" (at -1.022927 -2.155213) (layer "B.Fab")
        (effects (font (size 0.7 0.7) (thickness 0.15)) (justify left bottom mirror))
    )
    (fp_text user "Author: Antmicro" (at -0.939 -3.399) (layer "B.Fab") hide
        (effects (font (size 0.7 0.7) (thickness 0.15)) (justify left bottom mirror))
    )
    (fp_text user "${REFERENCE}" (at -0.939 -4.599) (layer "B.Fab") hide
        (effects (font (size 0.7 0.7) (thickness 0.15)) (justify left bottom mirror))
    )
    (fp_text user "License: Apache-2.0" (at -0.939 -5.799) (layer "B.Fab") hide
        (effects (font (size 0.7 0.7) (thickness 0.15)) (justify left bottom mirror))
    )
    (fp_rect (start -0.925 0.47) (end 0.925 -0.47)
      (stroke (width 0.05) (type default)) (fill none) (layer "B.CrtYd"))
    (fp_line (start -0.494 -0.248) (end -0.494 0.25)
      (stroke (width 0.15) (type solid)) (layer "B.Fab"))
    (fp_line (start -0.494 0.25) (end 0.504 0.25)
      (stroke (width 0.15) (type solid)) (layer "B.Fab"))
    (fp_line (start 0.504 -0.248) (end -0.494 -0.248)
      (stroke (width 0.15) (type solid)) (layer "B.Fab"))
    (fp_line (start 0.504 0.25) (end 0.504 -0.248)
      (stroke (width 0.15) (type solid)) (layer "B.Fab"))
    (pad "1" smd roundrect (at -0.48 0 180) (size 0.59 0.64) (layers "B.Cu" "B.Paste" "B.Mask") (roundrect_rratio 0.25)
      (net 93 "Net-(U1-BST1)") (pintype "passive"))
    (pad "2" smd roundrect (at 0.48 0 180) (size 0.59 0.64) (layers "B.Cu" "B.Paste" "B.Mask") (roundrect_rratio 0.25)
      (net 4 "Net-(C26-Pad2)") (pintype "passive"))
  )

  (footprint "antmicro-footprints:C_0402_1005Metric" (layer "B.Cu")
    (at 159.91 65.47 -90)
    (descr "Capacitor SMD 0402")
    (tags "capacitor SMD 0402")
    (property "Author" "Antmicro")
    (property "Dielectric" "")
    (property "License" "Apache-2.0")
    (property "MPN" "04025C221JAT2A")
    (property "Manufacturer" "KYOCERA AVX")
    (property "Sheetfile" "power.kicad_sch")
    (property "Sheetname" "Power")
    (property "Val" "220p")
    (property "Voltage" "")
    (property "ki_description" "SMD Multilayer Ceramic Capacitor, 220 pF, 50 V, 0402 [1005 Metric], ± 10%, X7R, MC")
    (property "ki_keywords" "0402, SMT, CAPACITOR, PASSIVE")
    (attr smd)
    (fp_text reference "C45" (at -1.033214 -2.376506 90) (layer "B.SilkS")
        (effects (font (size 0.7 0.7) (thickness 0.15)) (justify left bottom mirror))
    )
    (fp_text value "C_220p_0402" (at -1.022927 -2.155213 90) (layer "B.Fab")
        (effects (font (size 0.7 0.7) (thickness 0.15)) (justify left bottom mirror))
    )
    (fp_text user "Author: Antmicro" (at -0.939 -3.399 90) (layer "B.Fab") hide
        (effects (font (size 0.7 0.7) (thickness 0.15)) (justify left bottom mirror))
    )
    (fp_text user "${REFERENCE}" (at -0.939 -4.599 90) (layer "B.Fab") hide
        (effects (font (size 0.7 0.7) (thickness 0.15)) (justify left bottom mirror))
    )
    (fp_text user "License: Apache-2.0" (at -0.939 -5.799 90) (layer "B.Fab") hide
        (effects (font (size 0.7 0.7) (thickness 0.15)) (justify left bottom mirror))
    )
    (fp_rect (start -0.925 0.47) (end 0.925 -0.47)
      (stroke (width 0.05) (type default)) (fill none) (layer "B.CrtYd"))
    (fp_line (start -0.494 -0.248) (end -0.494 0.25)
      (stroke (width 0.15) (type solid)) (layer "B.Fab"))
    (fp_line (start -0.494 0.25) (end 0.504 0.25)
      (stroke (width 0.15) (type solid)) (layer "B.Fab"))
    (fp_line (start 0.504 -0.248) (end -0.494 -0.248)
      (stroke (width 0.15) (type solid)) (layer "B.Fab"))
    (fp_line (start 0.504 0.25) (end 0.504 -0.248)
      (stroke (width 0.15) (type solid)) (layer "B.Fab"))
    (pad "1" smd roundrect (at -0.48 0 270) (size 0.59 0.64) (layers "B.Cu" "B.Paste" "B.Mask") (roundrect_rratio 0.25)
      (net 1 "GND") (pintype "passive"))
    (pad "2" smd roundrect (at 0.48 0 270) (size 0.59 0.64) (layers "B.Cu" "B.Paste" "B.Mask") (roundrect_rratio 0.25)
      (net 10 "CC2") (pintype "passive"))
  )

  (footprint "antmicro-footprints:C_0402_1005Metric" (layer "B.Cu")
    (at 130.9 80.825)
    (descr "Capacitor SMD 0402")
    (tags "capacitor SMD 0402")
    (property "Author" "Antmicro")
    (property "Dielectric" "")
    (property "License" "Apache-2.0")
    (property "MPN" "C1005X6S1A105K050BC")
    (property "Manufacturer" "TDK")
    (property "Sheetfile" "tb-power.kicad_sch")
    (property "Sheetname" "Thunderbolt Controller - Power")
    (property "Val" "1u")
    (property "Voltage" "")
    (property "ki_description" "SMD Multilayer Ceramic Capacitor, 1 µF, 10 V, 0402 [1005 Metric], ± 10%, X6S, C")
    (property "ki_keywords" "0402, SMT, CAPACITOR, PASSIVE, CERAMIC, MLCC")
    (attr smd)
    (fp_text reference "C58" (at 17.309 7.567 180) (layer "B.SilkS")
        (effects (font (size 0.7 0.7) (thickness 0.15)) (justify left bottom mirror))
    )
    (fp_text value "C_1u_0402" (at -1.022927 -2.155213 180) (layer "B.Fab")
        (effects (font (size 0.7 0.7) (thickness 0.15)) (justify left bottom mirror))
    )
    (fp_text user "${REFERENCE}" (at -0.939 -4.599 180) (layer "B.Fab") hide
        (effects (font (size 0.7 0.7) (thickness 0.15)) (justify left bottom mirror))
    )
    (fp_text user "License: Apache-2.0" (at -0.939 -5.799 180) (layer "B.Fab") hide
        (effects (font (size 0.7 0.7) (thickness 0.15)) (justify left bottom mirror))
    )
    (fp_text user "Author: Antmicro" (at -0.939 -3.399 180) (layer "B.Fab") hide
        (effects (font (size 0.7 0.7) (thickness 0.15)) (justify left bottom mirror))
    )
    (fp_rect (start -0.925 0.47) (end 0.925 -0.47)
      (stroke (width 0.05) (type default)) (fill none) (layer "B.CrtYd"))
    (fp_line (start -0.494 -0.248) (end -0.494 0.25)
      (stroke (width 0.15) (type solid)) (layer "B.Fab"))
    (fp_line (start -0.494 0.25) (end 0.504 0.25)
      (stroke (width 0.15) (type solid)) (layer "B.Fab"))
    (fp_line (start 0.504 -0.248) (end -0.494 -0.248)
      (stroke (width 0.15) (type solid)) (layer "B.Fab"))
    (fp_line (start 0.504 0.25) (end 0.504 -0.248)
      (stroke (width 0.15) (type solid)) (layer "B.Fab"))
    (pad "1" smd roundrect (at -0.48 0) (size 0.59 0.64) (layers "B.Cu" "B.Paste" "B.Mask") (roundrect_rratio 0.25)
      (net 1 "GND") (pintype "passive"))
    (pad "2" smd roundrect (at 0.48 0) (size 0.59 0.64) (layers "B.Cu" "B.Paste" "B.Mask") (roundrect_rratio 0.25)
      (net 106 "Net-(C53-Pad2)") (pintype "passive"))
  )

  (footprint "antmicro-footprints:C_0402_1005Metric" (layer "B.Cu")
    (at 134.8 83.75)
    (descr "Capacitor SMD 0402")
    (tags "capacitor SMD 0402")
    (property "Author" "Antmicro")
    (property "Dielectric" "")
    (property "License" "Apache-2.0")
    (property "MPN" "C1005X6S1A105K050BC")
    (property "Manufacturer" "TDK")
    (property "Sheetfile" "tb-power.kicad_sch")
    (property "Sheetname" "Thunderbolt Controller - Power")
    (property "Val" "1u")
    (property "Voltage" "")
    (property "ki_description" "SMD Multilayer Ceramic Capacitor, 1 µF, 10 V, 0402 [1005 Metric], ± 10%, X6S, C")
    (property "ki_keywords" "0402, SMT, CAPACITOR, PASSIVE, CERAMIC, MLCC")
    (attr smd)
    (fp_text reference "C65" (at 17.6 7.649 180) (layer "B.SilkS")
        (effects (font (size 0.7 0.7) (thickness 0.15)) (justify left bottom mirror))
    )
    (fp_text value "C_1u_0402" (at -1.022927 -2.155213 180) (layer "B.Fab")
        (effects (font (size 0.7 0.7) (thickness 0.15)) (justify left bottom mirror))
    )
    (fp_text user "Author: Antmicro" (at -0.939 -3.399 180) (layer "B.Fab") hide
        (effects (font (size 0.7 0.7) (thickness 0.15)) (justify left bottom mirror))
    )
    (fp_text user "${REFERENCE}" (at -0.939 -4.599 180) (layer "B.Fab") hide
        (effects (font (size 0.7 0.7) (thickness 0.15)) (justify left bottom mirror))
    )
    (fp_text user "License: Apache-2.0" (at -0.939 -5.799 180) (layer "B.Fab") hide
        (effects (font (size 0.7 0.7) (thickness 0.15)) (justify left bottom mirror))
    )
    (fp_rect (start -0.925 0.47) (end 0.925 -0.47)
      (stroke (width 0.05) (type default)) (fill none) (layer "B.CrtYd"))
    (fp_line (start -0.494 -0.248) (end -0.494 0.25)
      (stroke (width 0.15) (type solid)) (layer "B.Fab"))
    (fp_line (start -0.494 0.25) (end 0.504 0.25)
      (stroke (width 0.15) (type solid)) (layer "B.Fab"))
    (fp_line (start 0.504 -0.248) (end -0.494 -0.248)
      (stroke (width 0.15) (type solid)) (layer "B.Fab"))
    (fp_line (start 0.504 0.25) (end 0.504 -0.248)
      (stroke (width 0.15) (type solid)) (layer "B.Fab"))
    (pad "1" smd roundrect (at -0.48 0) (size 0.59 0.64) (layers "B.Cu" "B.Paste" "B.Mask") (roundrect_rratio 0.25)
      (net 1 "GND") (pintype "passive"))
    (pad "2" smd roundrect (at 0.48 0) (size 0.59 0.64) (layers "B.Cu" "B.Paste" "B.Mask") (roundrect_rratio 0.25)
      (net 108 "Net-(C56-Pad2)") (pintype "passive"))
  )

  (footprint "antmicro-footprints:C_0402_1005Metric" (layer "B.Cu")
    (at 132.85 77.9)
    (descr "Capacitor SMD 0402")
    (tags "capacitor SMD 0402")
    (property "Author" "Antmicro")
    (property "Dielectric" "")
    (property "License" "Apache-2.0")
    (property "MPN" "C1005X6S1A105K050BC")
    (property "Manufacturer" "TDK")
    (property "Sheetfile" "tb-power.kicad_sch")
    (property "Sheetname" "Thunderbolt Controller - Power")
    (property "Val" "1u")
    (property "Voltage" "")
    (property "ki_description" "SMD Multilayer Ceramic Capacitor, 1 µF, 10 V, 0402 [1005 Metric], ± 10%, X6S, C")
    (property "ki_keywords" "0402, SMT, CAPACITOR, PASSIVE, CERAMIC, MLCC")
    (attr smd)
    (fp_text reference "C54" (at 17.518 7.571 180) (layer "B.SilkS")
        (effects (font (size 0.7 0.7) (thickness 0.15)) (justify left bottom mirror))
    )
    (fp_text value "C_1u_0402" (at -1.022927 -2.155213 180) (layer "B.Fab")
        (effects (font (size 0.7 0.7) (thickness 0.15)) (justify left bottom mirror))
    )
    (fp_text user "Author: Antmicro" (at -0.939 -3.399 180) (layer "B.Fab") hide
        (effects (font (size 0.7 0.7) (thickness 0.15)) (justify left bottom mirror))
    )
    (fp_text user "${REFERENCE}" (at -0.939 -4.599 180) (layer "B.Fab") hide
        (effects (font (size 0.7 0.7) (thickness 0.15)) (justify left bottom mirror))
    )
    (fp_text user "License: Apache-2.0" (at -0.939 -5.799 180) (layer "B.Fab") hide
        (effects (font (size 0.7 0.7) (thickness 0.15)) (justify left bottom mirror))
    )
    (fp_rect (start -0.925 0.47) (end 0.925 -0.47)
      (stroke (width 0.05) (type default)) (fill none) (layer "B.CrtYd"))
    (fp_line (start -0.494 -0.248) (end -0.494 0.25)
      (stroke (width 0.15) (type solid)) (layer "B.Fab"))
    (fp_line (start -0.494 0.25) (end 0.504 0.25)
      (stroke (width 0.15) (type solid)) (layer "B.Fab"))
    (fp_line (start 0.504 -0.248) (end -0.494 -0.248)
      (stroke (width 0.15) (type solid)) (layer "B.Fab"))
    (fp_line (start 0.504 0.25) (end 0.504 -0.248)
      (stroke (width 0.15) (type solid)) (layer "B.Fab"))
    (pad "1" smd roundrect (at -0.48 0) (size 0.59 0.64) (layers "B.Cu" "B.Paste" "B.Mask") (roundrect_rratio 0.25)
      (net 1 "GND") (pintype "passive"))
    (pad "2" smd roundrect (at 0.48 0) (size 0.59 0.64) (layers "B.Cu" "B.Paste" "B.Mask") (roundrect_rratio 0.25)
      (net 107 "Net-(C54-Pad2)") (pintype "passive"))
  )

  (footprint "antmicro-footprints:C_0402_1005Metric" (layer "B.Cu")
    (at 138.7 77.9 180)
    (descr "Capacitor SMD 0402")
    (tags "capacitor SMD 0402")
    (property "Author" "Antmicro")
    (property "Dielectric" "")
    (property "License" "Apache-2.0")
    (property "MPN" "C1005X6S1A105K050BC")
    (property "Manufacturer" "TDK")
    (property "Sheetfile" "tb-power.kicad_sch")
    (property "Sheetname" "Thunderbolt Controller - Power")
    (property "Val" "1u")
    (property "Voltage" "")
    (property "ki_description" "SMD Multilayer Ceramic Capacitor, 1 µF, 10 V, 0402 [1005 Metric], ± 10%, X6S, C")
    (property "ki_keywords" "0402, SMT, CAPACITOR, PASSIVE, CERAMIC, MLCC")
    (attr smd)
    (fp_text reference "C73" (at -17.764 -7.952) (layer "B.SilkS")
        (effects (font (size 0.7 0.7) (thickness 0.15)) (justify left bottom mirror))
    )
    (fp_text value "C_1u_0402" (at -1.022927 -2.155213) (layer "B.Fab")
        (effects (font (size 0.7 0.7) (thickness 0.15)) (justify left bottom mirror))
    )
    (fp_text user "${REFERENCE}" (at -0.939 -4.599) (layer "B.Fab") hide
        (effects (font (size 0.7 0.7) (thickness 0.15)) (justify left bottom mirror))
    )
    (fp_text user "License: Apache-2.0" (at -0.939 -5.799) (layer "B.Fab") hide
        (effects (font (size 0.7 0.7) (thickness 0.15)) (justify left bottom mirror))
    )
    (fp_text user "Author: Antmicro" (at -0.939 -3.399) (layer "B.Fab") hide
        (effects (font (size 0.7 0.7) (thickness 0.15)) (justify left bottom mirror))
    )
    (fp_rect (start -0.925 0.47) (end 0.925 -0.47)
      (stroke (width 0.05) (type default)) (fill none) (layer "B.CrtYd"))
    (fp_line (start -0.494 -0.248) (end -0.494 0.25)
      (stroke (width 0.15) (type solid)) (layer "B.Fab"))
    (fp_line (start -0.494 0.25) (end 0.504 0.25)
      (stroke (width 0.15) (type solid)) (layer "B.Fab"))
    (fp_line (start 0.504 -0.248) (end -0.494 -0.248)
      (stroke (width 0.15) (type solid)) (layer "B.Fab"))
    (fp_line (start 0.504 0.25) (end 0.504 -0.248)
      (stroke (width 0.15) (type solid)) (layer "B.Fab"))
    (pad "1" smd roundrect (at -0.48 0 180) (size 0.59 0.64) (layers "B.Cu" "B.Paste" "B.Mask") (roundrect_rratio 0.25)
      (net 1 "GND") (pintype "passive"))
    (pad "2" smd roundrect (at 0.48 0 180) (size 0.59 0.64) (layers "B.Cu" "B.Paste" "B.Mask") (roundrect_rratio 0.25)
      (net 2 "3V3_SYS") (pintype "passive"))
  )

  (footprint "antmicro-footprints:C_0402_1005Metric" (layer "B.Cu")
    (at 134.8 82.775)
    (descr "Capacitor SMD 0402")
    (tags "capacitor SMD 0402")
    (property "Author" "Antmicro")
    (property "Dielectric" "")
    (property "License" "Apache-2.0")
    (property "MPN" "C1005X6S1A105K050BC")
    (property "Manufacturer" "TDK")
    (property "Sheetfile" "tb-power.kicad_sch")
    (property "Sheetname" "Thunderbolt Controller - Power")
    (property "Val" "1u")
    (property "Voltage" "")
    (property "ki_description" "SMD Multilayer Ceramic Capacitor, 1 µF, 10 V, 0402 [1005 Metric], ± 10%, X6S, C")
    (property "ki_keywords" "0402, SMT, CAPACITOR, PASSIVE, CERAMIC, MLCC")
    (attr smd)
    (fp_text reference "C62" (at 17.6 7.649 180) (layer "B.SilkS")
        (effects (font (size 0.7 0.7) (thickness 0.15)) (justify left bottom mirror))
    )
    (fp_text value "C_1u_0402" (at -1.022927 -2.155213 180) (layer "B.Fab")
        (effects (font (size 0.7 0.7) (thickness 0.15)) (justify left bottom mirror))
    )
    (fp_text user "License: Apache-2.0" (at -0.939 -5.799 180) (layer "B.Fab") hide
        (effects (font (size 0.7 0.7) (thickness 0.15)) (justify left bottom mirror))
    )
    (fp_text user "Author: Antmicro" (at -0.939 -3.399 180) (layer "B.Fab") hide
        (effects (font (size 0.7 0.7) (thickness 0.15)) (justify left bottom mirror))
    )
    (fp_text user "${REFERENCE}" (at -0.939 -4.599 180) (layer "B.Fab") hide
        (effects (font (size 0.7 0.7) (thickness 0.15)) (justify left bottom mirror))
    )
    (fp_rect (start -0.925 0.47) (end 0.925 -0.47)
      (stroke (width 0.05) (type default)) (fill none) (layer "B.CrtYd"))
    (fp_line (start -0.494 -0.248) (end -0.494 0.25)
      (stroke (width 0.15) (type solid)) (layer "B.Fab"))
    (fp_line (start -0.494 0.25) (end 0.504 0.25)
      (stroke (width 0.15) (type solid)) (layer "B.Fab"))
    (fp_line (start 0.504 -0.248) (end -0.494 -0.248)
      (stroke (width 0.15) (type solid)) (layer "B.Fab"))
    (fp_line (start 0.504 0.25) (end 0.504 -0.248)
      (stroke (width 0.15) (type solid)) (layer "B.Fab"))
    (pad "1" smd roundrect (at -0.48 0) (size 0.59 0.64) (layers "B.Cu" "B.Paste" "B.Mask") (roundrect_rratio 0.25)
      (net 1 "GND") (pintype "passive"))
    (pad "2" smd roundrect (at 0.48 0) (size 0.59 0.64) (layers "B.Cu" "B.Paste" "B.Mask") (roundrect_rratio 0.25)
      (net 108 "Net-(C56-Pad2)") (pintype "passive"))
  )

  (footprint "antmicro-footprints:C_0402_1005Metric" (layer "B.Cu")
    (at 108.915 83.67 180)
    (descr "Capacitor SMD 0402")
    (tags "capacitor SMD 0402")
    (property "Author" "Antmicro")
    (property "Dielectric" "")
    (property "License" "Apache-2.0")
    (property "MPN" "CC0402KRX5R6BB224")
    (property "Manufacturer" "YAGEO")
    (property "Sheetfile" "power.kicad_sch")
    (property "Sheetname" "Power")
    (property "Val" "220n")
    (property "Voltage" "")
    (property "ki_description" "SMD Multilayer Ceramic Capacitor, 0.22 µF, 10 V, 0402 [1005 Metric], ± 10%, X5R, CC Series")
    (property "ki_keywords" "0402, SMT, CAPACITOR, PASSIVE, MLCC, CERAMIC")
    (attr smd)
    (fp_text reference "C16" (at -1.067 5.692) (layer "B.SilkS")
        (effects (font (size 0.7 0.7) (thickness 0.15)) (justify left bottom mirror))
    )
    (fp_text value "C_220n_0402" (at -1.022927 -2.155213) (layer "B.Fab")
        (effects (font (size 0.7 0.7) (thickness 0.15)) (justify left bottom mirror))
    )
    (fp_text user "${REFERENCE}" (at -0.939 -4.599) (layer "B.Fab") hide
        (effects (font (size 0.7 0.7) (thickness 0.15)) (justify left bottom mirror))
    )
    (fp_text user "License: Apache-2.0" (at -0.939 -5.799) (layer "B.Fab") hide
        (effects (font (size 0.7 0.7) (thickness 0.15)) (justify left bottom mirror))
    )
    (fp_text user "Author: Antmicro" (at -0.939 -3.399) (layer "B.Fab") hide
        (effects (font (size 0.7 0.7) (thickness 0.15)) (justify left bottom mirror))
    )
    (fp_rect (start -0.925 0.47) (end 0.925 -0.47)
      (stroke (width 0.05) (type default)) (fill none) (layer "B.CrtYd"))
    (fp_line (start -0.494 -0.248) (end -0.494 0.25)
      (stroke (width 0.15) (type solid)) (layer "B.Fab"))
    (fp_line (start -0.494 0.25) (end 0.504 0.25)
      (stroke (width 0.15) (type solid)) (layer "B.Fab"))
    (fp_line (start 0.504 -0.248) (end -0.494 -0.248)
      (stroke (width 0.15) (type solid)) (layer "B.Fab"))
    (fp_line (start 0.504 0.25) (end 0.504 -0.248)
      (stroke (width 0.15) (type solid)) (layer "B.Fab"))
    (pad "1" smd roundrect (at -0.48 0 180) (size 0.59 0.64) (layers "B.Cu" "B.Paste" "B.Mask") (roundrect_rratio 0.25)
      (net 1 "GND") (pintype "passive"))
    (pad "2" smd roundrect (at 0.48 0 180) (size 0.59 0.64) (layers "B.Cu" "B.Paste" "B.Mask") (roundrect_rratio 0.25)
      (net 5 "Net-(U1-VREF)") (pintype "passive"))
  )

  (footprint "antmicro-footprints:R_0402_1005Metric" (layer "B.Cu")
    (at 137.225 70.72 90)
    (descr "Resistor SMD 0402")
    (tags "resistor SMD 0402")
    (property "Author" "Antmicro")
    (property "License" "Apache-2.0")
    (property "MPN" "CR0402-FX-1002GLF")
    (property "Manufacturer" "Bourns")
    (property "Sheetfile" "tb.kicad_sch")
    (property "Sheetname" "TB Controller")
    (property "Tolerance" "1%")
    (property "Val" "10k")
    (property "ki_description" "SMD Chip Resistor, 10 kohm, ± 1%, 62.5 mW, 0402 [1005 Metric], Thick Film, General Purpose")
    (property "ki_keywords" "0402, SMT, RESISTOR, PASSIVE")
    (attr smd)
    (fp_text reference "R83" (at -1.035 0.434 270) (layer "B.SilkS")
        (effects (font (size 0.7 0.7) (thickness 0.15)) (justify left bottom mirror))
    )
    (fp_text value "R_10k_0402" (at -1.011843 -1.772047 270) (layer "B.Fab")
        (effects (font (size 0.7 0.7) (thickness 0.15)) (justify left bottom mirror))
    )
    (fp_text user "Author: Antmicro" (at -0.95 -4.169 270) (layer "B.Fab") hide
        (effects (font (size 0.7 0.7) (thickness 0.15)) (justify left bottom mirror))
    )
    (fp_text user "${REFERENCE}" (at -0.95 -3.168 270) (layer "B.Fab") hide
        (effects (font (size 0.7 0.7) (thickness 0.15)) (justify left bottom mirror))
    )
    (fp_text user "License: Apache-2.0" (at -0.95 -5.169 270) (layer "B.Fab") hide
        (effects (font (size 0.7 0.7) (thickness 0.15)) (justify left bottom mirror))
    )
    (fp_rect (start -0.925 0.47) (end 0.925 -0.47)
      (stroke (width 0.05) (type default)) (fill none) (layer "B.CrtYd"))
    (fp_rect (start -0.5 0.25) (end 0.5 -0.25)
      (stroke (width 0.15) (type solid)) (fill none) (layer "B.Fab"))
    (pad "1" smd roundrect (at -0.48 0 90) (size 0.59 0.64) (layers "B.Cu" "B.Paste" "B.Mask") (roundrect_rratio 0.25)
      (net 198 "Net-(U4C-POC_GPIO_1)") (pintype "passive"))
    (pad "2" smd roundrect (at 0.48 0 90) (size 0.59 0.64) (layers "B.Cu" "B.Paste" "B.Mask") (roundrect_rratio 0.25)
      (net 2 "3V3_SYS") (pintype "passive"))
  )

  (footprint "antmicro-footprints:C_0402_1005Metric" (layer "B.Cu")
    (at 134.8 80.825 180)
    (descr "Capacitor SMD 0402")
    (tags "capacitor SMD 0402")
    (property "Author" "Antmicro")
    (property "Dielectric" "")
    (property "License" "Apache-2.0")
    (property "MPN" "C1005X6S1A105K050BC")
    (property "Manufacturer" "TDK")
    (property "Sheetfile" "tb-power.kicad_sch")
    (property "Sheetname" "Thunderbolt Controller - Power")
    (property "Val" "1u")
    (property "Voltage" "")
    (property "ki_description" "SMD Multilayer Ceramic Capacitor, 1 µF, 10 V, 0402 [1005 Metric], ± 10%, X6S, C")
    (property "ki_keywords" "0402, SMT, CAPACITOR, PASSIVE, CERAMIC, MLCC")
    (attr smd)
    (fp_text reference "C56" (at -17.6 -7.694) (layer "B.SilkS")
        (effects (font (size 0.7 0.7) (thickness 0.15)) (justify left bottom mirror))
    )
    (fp_text value "C_1u_0402" (at -1.022927 -2.155213) (layer "B.Fab")
        (effects (font (size 0.7 0.7) (thickness 0.15)) (justify left bottom mirror))
    )
    (fp_text user "License: Apache-2.0" (at -0.939 -5.799) (layer "B.Fab") hide
        (effects (font (size 0.7 0.7) (thickness 0.15)) (justify left bottom mirror))
    )
    (fp_text user "${REFERENCE}" (at -0.939 -4.599) (layer "B.Fab") hide
        (effects (font (size 0.7 0.7) (thickness 0.15)) (justify left bottom mirror))
    )
    (fp_text user "Author: Antmicro" (at -0.939 -3.399) (layer "B.Fab") hide
        (effects (font (size 0.7 0.7) (thickness 0.15)) (justify left bottom mirror))
    )
    (fp_rect (start -0.925 0.47) (end 0.925 -0.47)
      (stroke (width 0.05) (type default)) (fill none) (layer "B.CrtYd"))
    (fp_line (start -0.494 -0.248) (end -0.494 0.25)
      (stroke (width 0.15) (type solid)) (layer "B.Fab"))
    (fp_line (start -0.494 0.25) (end 0.504 0.25)
      (stroke (width 0.15) (type solid)) (layer "B.Fab"))
    (fp_line (start 0.504 -0.248) (end -0.494 -0.248)
      (stroke (width 0.15) (type solid)) (layer "B.Fab"))
    (fp_line (start 0.504 0.25) (end 0.504 -0.248)
      (stroke (width 0.15) (type solid)) (layer "B.Fab"))
    (pad "1" smd roundrect (at -0.48 0 180) (size 0.59 0.64) (layers "B.Cu" "B.Paste" "B.Mask") (roundrect_rratio 0.25)
      (net 1 "GND") (pintype "passive"))
    (pad "2" smd roundrect (at 0.48 0 180) (size 0.59 0.64) (layers "B.Cu" "B.Paste" "B.Mask") (roundrect_rratio 0.25)
      (net 108 "Net-(C56-Pad2)") (pintype "passive"))
  )

  (footprint "antmicro-footprints:C_0402_1005Metric" (layer "B.Cu")
    (at 122.998 75.17)
    (descr "Capacitor SMD 0402")
    (tags "capacitor SMD 0402")
    (property "Author" "Antmicro")
    (property "Dielectric" "C0G")
    (property "License" "Apache-2.0")
    (property "MPN" "GCM1555C1H100GA16D")
    (property "Manufacturer" "Murata")
    (property "Sheetfile" "tb.kicad_sch")
    (property "Sheetname" "TB Controller")
    (property "Val" "10p")
    (property "Voltage" "50V")
    (property "ki_description" "SMD Multilayer Ceramic Capacitor, 10 pF, 50 V, 0402 [1005 Metric], ± 2%, C0G / NP0, GCM")
    (property "ki_keywords" "0402, SMT, CAPACITOR, PASSIVE")
    (attr smd)
    (fp_text reference "C113" (at 1.208 -0.621 180) (layer "B.SilkS")
        (effects (font (size 0.7 0.7) (thickness 0.15)) (justify left bottom mirror))
    )
    (fp_text value "C_10p_0402" (at -1.022927 -2.155213 180) (layer "B.Fab")
        (effects (font (size 0.7 0.7) (thickness 0.15)) (justify left bottom mirror))
    )
    (fp_text user "Author: Antmicro" (at -0.939 -3.399 180) (layer "B.Fab") hide
        (effects (font (size 0.7 0.7) (thickness 0.15)) (justify left bottom mirror))
    )
    (fp_text user "License: Apache-2.0" (at -0.939 -5.799 180) (layer "B.Fab") hide
        (effects (font (size 0.7 0.7) (thickness 0.15)) (justify left bottom mirror))
    )
    (fp_text user "${REFERENCE}" (at -0.939 -4.599 180) (layer "B.Fab") hide
        (effects (font (size 0.7 0.7) (thickness 0.15)) (justify left bottom mirror))
    )
    (fp_rect (start -0.925 0.47) (end 0.925 -0.47)
      (stroke (width 0.05) (type default)) (fill none) (layer "B.CrtYd"))
    (fp_line (start -0.494 -0.248) (end -0.494 0.25)
      (stroke (width 0.15) (type solid)) (layer "B.Fab"))
    (fp_line (start -0.494 0.25) (end 0.504 0.25)
      (stroke (width 0.15) (type solid)) (layer "B.Fab"))
    (fp_line (start 0.504 -0.248) (end -0.494 -0.248)
      (stroke (width 0.15) (type solid)) (layer "B.Fab"))
    (fp_line (start 0.504 0.25) (end 0.504 -0.248)
      (stroke (width 0.15) (type solid)) (layer "B.Fab"))
    (pad "1" smd roundrect (at -0.48 0) (size 0.59 0.64) (layers "B.Cu" "B.Paste" "B.Mask") (roundrect_rratio 0.25)
      (net 1 "GND") (pintype "passive"))
    (pad "2" smd roundrect (at 0.48 0) (size 0.59 0.64) (layers "B.Cu" "B.Paste" "B.Mask") (roundrect_rratio 0.25)
      (net 115 "Net-(U6-XOUT)") (pintype "passive"))
  )

  (footprint "antmicro-footprints:R_0402_1005Metric" (layer "B.Cu")
    (at 161.41 61.97)
    (descr "Resistor SMD 0402")
    (tags "resistor SMD 0402")
    (property "Author" "Antmicro")
    (property "License" "Apache-2.0")
    (property "MPN" "CR0402-FX-1002GLF")
    (property "Manufacturer" "Bourns")
    (property "Sheetfile" "power.kicad_sch")
    (property "Sheetname" "Power")
    (property "Tolerance" "1%")
    (property "Val" "10k")
    (property "ki_description" "SMD Chip Resistor, 10 kohm, ± 1%, 62.5 mW, 0402 [1005 Metric], Thick Film, General Purpose")
    (property "ki_keywords" "0402, SMT, RESISTOR, PASSIVE")
    (attr smd)
    (fp_text reference "R39" (at 3.182 0.387 180) (layer "B.SilkS")
        (effects (font (size 0.7 0.7) (thickness 0.15)) (justify left bottom mirror))
    )
    (fp_text value "R_10k_0402" (at -1.011843 -1.772047 180) (layer "B.Fab")
        (effects (font (size 0.7 0.7) (thickness 0.15)) (justify left bottom mirror))
    )
    (fp_text user "Author: Antmicro" (at -0.95 -4.169 180) (layer "B.Fab") hide
        (effects (font (size 0.7 0.7) (thickness 0.15)) (justify left bottom mirror))
    )
    (fp_text user "${REFERENCE}" (at -0.95 -3.168 180) (layer "B.Fab") hide
        (effects (font (size 0.7 0.7) (thickness 0.15)) (justify left bottom mirror))
    )
    (fp_text user "License: Apache-2.0" (at -0.95 -5.169 180) (layer "B.Fab") hide
        (effects (font (size 0.7 0.7) (thickness 0.15)) (justify left bottom mirror))
    )
    (fp_rect (start -0.925 0.47) (end 0.925 -0.47)
      (stroke (width 0.05) (type default)) (fill none) (layer "B.CrtYd"))
    (fp_rect (start -0.5 0.25) (end 0.5 -0.25)
      (stroke (width 0.15) (type solid)) (fill none) (layer "B.Fab"))
    (pad "1" smd roundrect (at -0.48 0) (size 0.59 0.64) (layers "B.Cu" "B.Paste" "B.Mask") (roundrect_rratio 0.25)
      (net 62 "RESET_N") (pintype "passive"))
    (pad "2" smd roundrect (at 0.48 0) (size 0.59 0.64) (layers "B.Cu" "B.Paste" "B.Mask") (roundrect_rratio 0.25)
      (net 9 "/Power/TPS_3V3") (pintype "passive"))
  )

  (footprint "antmicro-footprints:C_0402_1005Metric" (layer "B.Cu")
    (at 128.48 80.34 -90)
    (descr "Capacitor SMD 0402")
    (tags "capacitor SMD 0402")
    (property "Author" "Antmicro")
    (property "Dielectric" "")
    (property "License" "Apache-2.0")
    (property "MPN" "C1005X6S1A105K050BC")
    (property "Manufacturer" "TDK")
    (property "Sheetfile" "tb-power.kicad_sch")
    (property "Sheetname" "Thunderbolt Controller - Power")
    (property "Val" "1u")
    (property "Voltage" "")
    (property "ki_description" "SMD Multilayer Ceramic Capacitor, 1 µF, 10 V, 0402 [1005 Metric], ± 10%, X6S, C")
    (property "ki_keywords" "0402, SMT, CAPACITOR, PASSIVE, CERAMIC, MLCC")
    (attr smd)
    (fp_text reference "C94" (at -0.965 2.537 90) (layer "B.SilkS")
        (effects (font (size 0.7 0.7) (thickness 0.15)) (justify left bottom mirror))
    )
    (fp_text value "C_1u_0402" (at -1.022927 -2.155213 90) (layer "B.Fab")
        (effects (font (size 0.7 0.7) (thickness 0.15)) (justify left bottom mirror))
    )
    (fp_text user "${REFERENCE}" (at -0.939 -4.599 90) (layer "B.Fab") hide
        (effects (font (size 0.7 0.7) (thickness 0.15)) (justify left bottom mirror))
    )
    (fp_text user "Author: Antmicro" (at -0.939 -3.399 90) (layer "B.Fab") hide
        (effects (font (size 0.7 0.7) (thickness 0.15)) (justify left bottom mirror))
    )
    (fp_text user "License: Apache-2.0" (at -0.939 -5.799 90) (layer "B.Fab") hide
        (effects (font (size 0.7 0.7) (thickness 0.15)) (justify left bottom mirror))
    )
    (fp_rect (start -0.925 0.47) (end 0.925 -0.47)
      (stroke (width 0.05) (type default)) (fill none) (layer "B.CrtYd"))
    (fp_line (start -0.494 -0.248) (end -0.494 0.25)
      (stroke (width 0.15) (type solid)) (layer "B.Fab"))
    (fp_line (start -0.494 0.25) (end 0.504 0.25)
      (stroke (width 0.15) (type solid)) (layer "B.Fab"))
    (fp_line (start 0.504 -0.248) (end -0.494 -0.248)
      (stroke (width 0.15) (type solid)) (layer "B.Fab"))
    (fp_line (start 0.504 0.25) (end 0.504 -0.248)
      (stroke (width 0.15) (type solid)) (layer "B.Fab"))
    (pad "1" smd roundrect (at -0.48 0 270) (size 0.59 0.64) (layers "B.Cu" "B.Paste" "B.Mask") (roundrect_rratio 0.25)
      (net 1 "GND") (pintype "passive"))
    (pad "2" smd roundrect (at 0.48 0 270) (size 0.59 0.64) (layers "B.Cu" "B.Paste" "B.Mask") (roundrect_rratio 0.25)
      (net 114 "Net-(U4A-VCC3P3_S0)") (pintype "passive"))
  )

  (footprint "antmicro-footprints:R_0402_1005Metric" (layer "B.Cu")
    (at 128.19 76.83 180)
    (descr "Resistor SMD 0402")
    (tags "resistor SMD 0402")
    (property "Author" "Antmicro")
    (property "License" "Apache-2.0")
    (property "MPN" "CR0402-FX-1000GLF")
    (property "Manufacturer" "Bourns")
    (property "Sheetfile" "tb.kicad_sch")
    (property "Sheetname" "TB Controller")
    (property "Tolerance" "1%")
    (property "Val" "100R")
    (property "ki_description" "SMD Chip Resistor, 100 ohm, ± 1%, 62.5 mW, 0402 [1005 Metric], Thick Film, General Purpose")
    (property "ki_keywords" "0402, SMT, RESISTOR, PASSIVE")
    (attr smd)
    (fp_text reference "R89" (at 0.936 -0.386) (layer "B.SilkS")
        (effects (font (size 0.7 0.7) (thickness 0.15)) (justify left bottom mirror))
    )
    (fp_text value "R_100R_0402" (at -1.011843 -1.772047) (layer "B.Fab")
        (effects (font (size 0.7 0.7) (thickness 0.15)) (justify left bottom mirror))
    )
    (fp_text user "${REFERENCE}" (at -0.95 -3.168) (layer "B.Fab") hide
        (effects (font (size 0.7 0.7) (thickness 0.15)) (justify left bottom mirror))
    )
    (fp_text user "Author: Antmicro" (at -0.95 -4.169) (layer "B.Fab") hide
        (effects (font (size 0.7 0.7) (thickness 0.15)) (justify left bottom mirror))
    )
    (fp_text user "License: Apache-2.0" (at -0.95 -5.169) (layer "B.Fab") hide
        (effects (font (size 0.7 0.7) (thickness 0.15)) (justify left bottom mirror))
    )
    (fp_rect (start -0.925 0.47) (end 0.925 -0.47)
      (stroke (width 0.05) (type default)) (fill none) (layer "B.CrtYd"))
    (fp_rect (start -0.5 0.25) (end 0.5 -0.25)
      (stroke (width 0.15) (type solid)) (fill none) (layer "B.Fab"))
    (pad "1" smd roundrect (at -0.48 0 180) (size 0.59 0.64) (layers "B.Cu" "B.Paste" "B.Mask") (roundrect_rratio 0.25)
      (net 204 "Net-(U4D-TEST_PWR_GOOD)") (pintype "passive"))
    (pad "2" smd roundrect (at 0.48 0 180) (size 0.59 0.64) (layers "B.Cu" "B.Paste" "B.Mask") (roundrect_rratio 0.25)
      (net 1 "GND") (pintype "passive"))
  )

  (footprint "antmicro-footprints:R_0402_1005Metric" (layer "B.Cu")
    (at 151.41 61.97)
    (descr "Resistor SMD 0402")
    (tags "resistor SMD 0402")
    (property "Author" "Antmicro")
    (property "License" "Apache-2.0")
    (property "MPN" "CR0402-FX-2201GLF")
    (property "Manufacturer" "Bourns")
    (property "Sheetfile" "power.kicad_sch")
    (property "Sheetname" "Power")
    (property "Tolerance" "1%")
    (property "Val" "2k2")
    (property "ki_description" "SMD Chip Resistor, 2.2 kohm, ± 1%, 62.5 mW, 0402 [1005 Metric], Thick Film, General Purpose")
    (property "ki_keywords" "0402, SMT, RESISTOR, PASSIVE")
    (attr smd)
    (fp_text reference "R5" (at -0.915 0.482 180) (layer "B.SilkS")
        (effects (font (size 0.7 0.7) (thickness 0.15)) (justify left bottom mirror))
    )
    (fp_text value "R_2k2_0402" (at -1.011843 -1.772047 180) (layer "B.Fab")
        (effects (font (size 0.7 0.7) (thickness 0.15)) (justify left bottom mirror))
    )
    (fp_text user "Author: Antmicro" (at -0.95 -4.169 180) (layer "B.Fab") hide
        (effects (font (size 0.7 0.7) (thickness 0.15)) (justify left bottom mirror))
    )
    (fp_text user "License: Apache-2.0" (at -0.95 -5.169 180) (layer "B.Fab") hide
        (effects (font (size 0.7 0.7) (thickness 0.15)) (justify left bottom mirror))
    )
    (fp_text user "${REFERENCE}" (at -0.95 -3.168 180) (layer "B.Fab") hide
        (effects (font (size 0.7 0.7) (thickness 0.15)) (justify left bottom mirror))
    )
    (fp_rect (start -0.925 0.47) (end 0.925 -0.47)
      (stroke (width 0.05) (type default)) (fill none) (layer "B.CrtYd"))
    (fp_rect (start -0.5 0.25) (end 0.5 -0.25)
      (stroke (width 0.15) (type solid)) (fill none) (layer "B.Fab"))
    (pad "1" smd roundrect (at -0.48 0) (size 0.59 0.64) (layers "B.Cu" "B.Paste" "B.Mask") (roundrect_rratio 0.25)
      (net 59 "I2C1_SDA") (pintype "passive"))
    (pad "2" smd roundrect (at 0.48 0) (size 0.59 0.64) (layers "B.Cu" "B.Paste" "B.Mask") (roundrect_rratio 0.25)
      (net 2 "3V3_SYS") (pintype "passive"))
  )

  (footprint "antmicro-footprints:R_0402_1005Metric" (layer "B.Cu")
    (at 135.115 62.93)
    (descr "Resistor SMD 0402")
    (tags "resistor SMD 0402")
    (property "Author" "Antmicro")
    (property "License" "Apache-2.0")
    (property "MPN" "CR0402-FX-3301GLF")
    (property "Manufacturer" "Bourns")
    (property "Sheetfile" "tb.kicad_sch")
    (property "Sheetname" "TB Controller")
    (property "Tolerance" "1%")
    (property "Val" "3k3")
    (property "ki_description" "SMD Chip Resistor, 3.3 kohm, ± 1%, 63 mW, 0402 [1005 Metric], Thick Film, General Purpose")
    (property "ki_keywords" "0402, SMT, RESISTOR, PASSIVE")
    (attr smd)
    (fp_text reference "R51" (at -1.003 0.443 180) (layer "B.SilkS")
        (effects (font (size 0.7 0.7) (thickness 0.15)) (justify left bottom mirror))
    )
    (fp_text value "R_3k3_0402" (at -1.011843 -1.772047 180) (layer "B.Fab")
        (effects (font (size 0.7 0.7) (thickness 0.15)) (justify left bottom mirror))
    )
    (fp_text user "Author: Antmicro" (at -0.95 -4.169 180) (layer "B.Fab") hide
        (effects (font (size 0.7 0.7) (thickness 0.15)) (justify left bottom mirror))
    )
    (fp_text user "${REFERENCE}" (at -0.95 -3.168 180) (layer "B.Fab") hide
        (effects (font (size 0.7 0.7) (thickness 0.15)) (justify left bottom mirror))
    )
    (fp_text user "License: Apache-2.0" (at -0.95 -5.169 180) (layer "B.Fab") hide
        (effects (font (size 0.7 0.7) (thickness 0.15)) (justify left bottom mirror))
    )
    (fp_rect (start -0.925 0.47) (end 0.925 -0.47)
      (stroke (width 0.05) (type default)) (fill none) (layer "B.CrtYd"))
    (fp_rect (start -0.5 0.25) (end 0.5 -0.25)
      (stroke (width 0.15) (type solid)) (fill none) (layer "B.Fab"))
    (pad "1" smd roundrect (at -0.48 0) (size 0.59 0.64) (layers "B.Cu" "B.Paste" "B.Mask") (roundrect_rratio 0.25)
      (net 64 "/TB Controller/FLASH_WP") (pintype "passive"))
    (pad "2" smd roundrect (at 0.48 0) (size 0.59 0.64) (layers "B.Cu" "B.Paste" "B.Mask") (roundrect_rratio 0.25)
      (net 2 "3V3_SYS") (pintype "passive"))
  )

  (footprint "antmicro-footprints:R_0402_1005Metric" (layer "B.Cu")
    (at 115.23 91.63 90)
    (descr "Resistor SMD 0402")
    (tags "resistor SMD 0402")
    (property "Author" "Antmicro")
    (property "License" "Apache-2.0")
    (property "MPN" "CR0402-FX-1003GLF")
    (property "Manufacturer" "Bourns")
    (property "Sheetfile" "power.kicad_sch")
    (property "Sheetname" "Power")
    (property "Tolerance" "1%")
    (property "Val" "100k")
    (property "ki_description" "SMD Chip Resistor, 100 kohm, ± 1%, 62.5 mW, 0402 [1005 Metric], Thick Film, General Purpose")
    (property "ki_keywords" "0402, SMT, RESISTOR, PASSIVE")
    (attr smd)
    (fp_text reference "R96" (at 1.079 3.515 270) (layer "B.SilkS")
        (effects (font (size 0.7 0.7) (thickness 0.15)) (justify left bottom mirror))
    )
    (fp_text value "R_100k_0402" (at -1.011843 -1.772047 270) (layer "B.Fab")
        (effects (font (size 0.7 0.7) (thickness 0.15)) (justify left bottom mirror))
    )
    (fp_text user "Author: Antmicro" (at -0.95 -4.169 270) (layer "B.Fab") hide
        (effects (font (size 0.7 0.7) (thickness 0.15)) (justify left bottom mirror))
    )
    (fp_text user "License: Apache-2.0" (at -0.95 -5.169 270) (layer "B.Fab") hide
        (effects (font (size 0.7 0.7) (thickness 0.15)) (justify left bottom mirror))
    )
    (fp_text user "${REFERENCE}" (at -0.95 -3.168 270) (layer "B.Fab") hide
        (effects (font (size 0.7 0.7) (thickness 0.15)) (justify left bottom mirror))
    )
    (fp_rect (start -0.925 0.47) (end 0.925 -0.47)
      (stroke (width 0.05) (type default)) (fill none) (layer "B.CrtYd"))
    (fp_rect (start -0.5 0.25) (end 0.5 -0.25)
      (stroke (width 0.15) (type solid)) (fill none) (layer "B.Fab"))
    (pad "1" smd roundrect (at -0.48 0 90) (size 0.59 0.64) (layers "B.Cu" "B.Paste" "B.Mask") (roundrect_rratio 0.25)
      (net 1 "GND") (pintype "passive"))
    (pad "2" smd roundrect (at 0.48 0 90) (size 0.59 0.64) (layers "B.Cu" "B.Paste" "B.Mask") (roundrect_rratio 0.25)
      (net 145 "Net-(Q4-BIAS)") (pintype "passive"))
  )

  (footprint "antmicro-footprints:R_0402_1005Metric" (layer "B.Cu")
    (at 135.175 66.82 -90)
    (descr "Resistor SMD 0402")
    (tags "resistor SMD 0402")
    (property "Author" "Antmicro")
    (property "License" "Apache-2.0")
    (property "MPN" "CR0402-FX-1002GLF")
    (property "Manufacturer" "Bourns")
    (property "Sheetfile" "tb.kicad_sch")
    (property "Sheetname" "TB Controller")
    (property "Tolerance" "1%")
    (property "Val" "10k")
    (property "ki_description" "SMD Chip Resistor, 10 kohm, ± 1%, 62.5 mW, 0402 [1005 Metric], Thick Film, General Purpose")
    (property "ki_keywords" "0402, SMT, RESISTOR, PASSIVE")
    (attr smd)
    (fp_text reference "R65" (at -3.066 -0.325 90) (layer "B.SilkS")
        (effects (font (size 0.7 0.7) (thickness 0.15)) (justify left bottom mirror))
    )
    (fp_text value "R_10k_0402" (at -1.011843 -1.772047 90) (layer "B.Fab")
        (effects (font (size 0.7 0.7) (thickness 0.15)) (justify left bottom mirror))
    )
    (fp_text user "License: Apache-2.0" (at -0.95 -5.169 90) (layer "B.Fab") hide
        (effects (font (size 0.7 0.7) (thickness 0.15)) (justify left bottom mirror))
    )
    (fp_text user "Author: Antmicro" (at -0.95 -4.169 90) (layer "B.Fab") hide
        (effects (font (size 0.7 0.7) (thickness 0.15)) (justify left bottom mirror))
    )
    (fp_text user "${REFERENCE}" (at -0.95 -3.168 90) (layer "B.Fab") hide
        (effects (font (size 0.7 0.7) (thickness 0.15)) (justify left bottom mirror))
    )
    (fp_rect (start -0.925 0.47) (end 0.925 -0.47)
      (stroke (width 0.05) (type default)) (fill none) (layer "B.CrtYd"))
    (fp_rect (start -0.5 0.25) (end 0.5 -0.25)
      (stroke (width 0.15) (type solid)) (fill none) (layer "B.Fab"))
    (pad "1" smd roundrect (at -0.48 0 270) (size 0.59 0.64) (layers "B.Cu" "B.Paste" "B.Mask") (roundrect_rratio 0.25)
      (net 2 "3V3_SYS") (pintype "passive"))
    (pad "2" smd roundrect (at 0.48 0 270) (size 0.59 0.64) (layers "B.Cu" "B.Paste" "B.Mask") (roundrect_rratio 0.25)
      (net 179 "Net-(U4D-TMS)") (pintype "passive"))
  )

  (footprint "antmicro-footprints:R_0402_1005Metric" (layer "B.Cu")
    (at 130.05 66.82 -90)
    (descr "Resistor SMD 0402")
    (tags "resistor SMD 0402")
    (property "Author" "Antmicro")
    (property "License" "Apache-2.0")
    (property "MPN" "CR0402-FX-1003GLF")
    (property "Manufacturer" "Bourns")
    (property "Sheetfile" "tb.kicad_sch")
    (property "Sheetname" "TB Controller")
    (property "Tolerance" "1%")
    (property "Val" "100k")
    (property "ki_description" "SMD Chip Resistor, 100 kohm, ± 1%, 62.5 mW, 0402 [1005 Metric], Thick Film, General Purpose")
    (property "ki_keywords" "0402, SMT, RESISTOR, PASSIVE")
    (attr smd)
    (fp_text reference "R60" (at -3.066 -0.325 90) (layer "B.SilkS")
        (effects (font (size 0.7 0.7) (thickness 0.15)) (justify left bottom mirror))
    )
    (fp_text value "R_100k_0402" (at -1.011843 -1.772047 90) (layer "B.Fab")
        (effects (font (size 0.7 0.7) (thickness 0.15)) (justify left bottom mirror))
    )
    (fp_text user "Author: Antmicro" (at -0.95 -4.169 90) (layer "B.Fab") hide
        (effects (font (size 0.7 0.7) (thickness 0.15)) (justify left bottom mirror))
    )
    (fp_text user "License: Apache-2.0" (at -0.95 -5.169 90) (layer "B.Fab") hide
        (effects (font (size 0.7 0.7) (thickness 0.15)) (justify left bottom mirror))
    )
    (fp_text user "${REFERENCE}" (at -0.95 -3.168 90) (layer "B.Fab") hide
        (effects (font (size 0.7 0.7) (thickness 0.15)) (justify left bottom mirror))
    )
    (fp_rect (start -0.925 0.47) (end 0.925 -0.47)
      (stroke (width 0.05) (type default)) (fill none) (layer "B.CrtYd"))
    (fp_rect (start -0.5 0.25) (end 0.5 -0.25)
      (stroke (width 0.15) (type solid)) (fill none) (layer "B.Fab"))
    (pad "1" smd roundrect (at -0.48 0 270) (size 0.59 0.64) (layers "B.Cu" "B.Paste" "B.Mask") (roundrect_rratio 0.25)
      (net 1 "GND") (pintype "passive"))
    (pad "2" smd roundrect (at 0.48 0 270) (size 0.59 0.64) (layers "B.Cu" "B.Paste" "B.Mask") (roundrect_rratio 0.25)
      (net 174 "Net-(U4C-DPSNK1_HPD)") (pintype "passive"))
  )

  (footprint "antmicro-footprints:R_0402_1005Metric" (layer "B.Cu")
    (at 157.89 57.39 -90)
    (descr "Resistor SMD 0402")
    (tags "resistor SMD 0402")
    (property "Author" "Antmicro")
    (property "License" "Apache-2.0")
    (property "MPN" "CR0402-FX-1002GLF")
    (property "Manufacturer" "Bourns")
    (property "Sheetfile" "power.kicad_sch")
    (property "Sheetname" "Power")
    (property "Tolerance" "1%")
    (property "Val" "10k")
    (property "ki_description" "SMD Chip Resistor, 10 kohm, ± 1%, 62.5 mW, 0402 [1005 Metric], Thick Film, General Purpose")
    (property "ki_keywords" "0402, SMT, RESISTOR, PASSIVE")
    (attr smd)
    (fp_text reference "R16" (at -3.034 -0.479 90) (layer "B.SilkS")
        (effects (font (size 0.7 0.7) (thickness 0.15)) (justify left bottom mirror))
    )
    (fp_text value "R_10k_0402" (at -1.011843 -1.772047 90) (layer "B.Fab")
        (effects (font (size 0.7 0.7) (thickness 0.15)) (justify left bottom mirror))
    )
    (fp_text user "${REFERENCE}" (at -0.95 -3.168 90) (layer "B.Fab") hide
        (effects (font (size 0.7 0.7) (thickness 0.15)) (justify left bottom mirror))
    )
    (fp_text user "License: Apache-2.0" (at -0.95 -5.169 90) (layer "B.Fab") hide
        (effects (font (size 0.7 0.7) (thickness 0.15)) (justify left bottom mirror))
    )
    (fp_text user "Author: Antmicro" (at -0.95 -4.169 90) (layer "B.Fab") hide
        (effects (font (size 0.7 0.7) (thickness 0.15)) (justify left bottom mirror))
    )
    (fp_rect (start -0.925 0.47) (end 0.925 -0.47)
      (stroke (width 0.05) (type default)) (fill none) (layer "B.CrtYd"))
    (fp_rect (start -0.5 0.25) (end 0.5 -0.25)
      (stroke (width 0.15) (type solid)) (fill none) (layer "B.Fab"))
    (pad "1" smd roundrect (at -0.48 0 270) (size 0.59 0.64) (layers "B.Cu" "B.Paste" "B.Mask") (roundrect_rratio 0.25)
      (net 9 "/Power/TPS_3V3") (pintype "passive"))
    (pad "2" smd roundrect (at 0.48 0 270) (size 0.59 0.64) (layers "B.Cu" "B.Paste" "B.Mask") (roundrect_rratio 0.25)
      (net 151 "Net-(U3-I2C_IRQ2Z)") (pintype "passive"))
  )

  (footprint "antmicro-footprints:C_0402_1005Metric" (layer "B.Cu")
    (at 134.8 76.925)
    (descr "Capacitor SMD 0402")
    (tags "capacitor SMD 0402")
    (property "Author" "Antmicro")
    (property "Dielectric" "")
    (property "License" "Apache-2.0")
    (property "MPN" "C1005X6S1A105K050BC")
    (property "Manufacturer" "TDK")
    (property "Sheetfile" "tb-power.kicad_sch")
    (property "Sheetname" "Thunderbolt Controller - Power")
    (property "Val" "1u")
    (property "Voltage" "")
    (property "ki_description" "SMD Multilayer Ceramic Capacitor, 1 µF, 10 V, 0402 [1005 Metric], ± 10%, X6S, C")
    (property "ki_keywords" "0402, SMT, CAPACITOR, PASSIVE, CERAMIC, MLCC")
    (attr smd)
    (fp_text reference "C61" (at 17.6 7.53 180) (layer "B.SilkS")
        (effects (font (size 0.7 0.7) (thickness 0.15)) (justify left bottom mirror))
    )
    (fp_text value "C_1u_0402" (at -1.022927 -2.155213 180) (layer "B.Fab")
        (effects (font (size 0.7 0.7) (thickness 0.15)) (justify left bottom mirror))
    )
    (fp_text user "${REFERENCE}" (at -0.939 -4.599 180) (layer "B.Fab") hide
        (effects (font (size 0.7 0.7) (thickness 0.15)) (justify left bottom mirror))
    )
    (fp_text user "License: Apache-2.0" (at -0.939 -5.799 180) (layer "B.Fab") hide
        (effects (font (size 0.7 0.7) (thickness 0.15)) (justify left bottom mirror))
    )
    (fp_text user "Author: Antmicro" (at -0.939 -3.399 180) (layer "B.Fab") hide
        (effects (font (size 0.7 0.7) (thickness 0.15)) (justify left bottom mirror))
    )
    (fp_rect (start -0.925 0.47) (end 0.925 -0.47)
      (stroke (width 0.05) (type default)) (fill none) (layer "B.CrtYd"))
    (fp_line (start -0.494 -0.248) (end -0.494 0.25)
      (stroke (width 0.15) (type solid)) (layer "B.Fab"))
    (fp_line (start -0.494 0.25) (end 0.504 0.25)
      (stroke (width 0.15) (type solid)) (layer "B.Fab"))
    (fp_line (start 0.504 -0.248) (end -0.494 -0.248)
      (stroke (width 0.15) (type solid)) (layer "B.Fab"))
    (fp_line (start 0.504 0.25) (end 0.504 -0.248)
      (stroke (width 0.15) (type solid)) (layer "B.Fab"))
    (pad "1" smd roundrect (at -0.48 0) (size 0.59 0.64) (layers "B.Cu" "B.Paste" "B.Mask") (roundrect_rratio 0.25)
      (net 1 "GND") (pintype "passive"))
    (pad "2" smd roundrect (at 0.48 0) (size 0.59 0.64) (layers "B.Cu" "B.Paste" "B.Mask") (roundrect_rratio 0.25)
      (net 106 "Net-(C53-Pad2)") (pintype "passive"))
  )

  (footprint "antmicro-footprints:R_0402_1005Metric" (layer "B.Cu")
    (at 111.725 81.66)
    (descr "Resistor SMD 0402")
    (tags "resistor SMD 0402")
    (property "Author" "Antmicro")
    (property "Current" "1A")
    (property "License" "Apache-2.0")
    (property "MPN" "ERJ2GE0R00X")
    (property "Manufacturer" "Panasonic")
    (property "Sheetfile" "power.kicad_sch")
    (property "Sheetname" "Power")
    (property "Tolerance" "")
    (property "Val" "0R")
    (property "ki_description" "SMD Chip Resistor, Jumper, 0 ohm, 100 mW, 0402 [1005 Metric], Thick Film, General Purpose")
    (property "ki_keywords" "0402, SMT, RESISTOR, PASSIVE")
    (attr smd)
    (fp_text reference "R26" (at 1.051 -4.698 180) (layer "B.SilkS")
        (effects (font (size 0.7 0.7) (thickness 0.15)) (justify left bottom mirror))
    )
    (fp_text value "R_0R_0402" (at -1.011843 -1.772047 180) (layer "B.Fab")
        (effects (font (size 0.7 0.7) (thickness 0.15)) (justify left bottom mirror))
    )
    (fp_text user "License: Apache-2.0" (at -0.95 -5.169 180) (layer "B.Fab") hide
        (effects (font (size 0.7 0.7) (thickness 0.15)) (justify left bottom mirror))
    )
    (fp_text user "${REFERENCE}" (at -0.95 -3.168 180) (layer "B.Fab") hide
        (effects (font (size 0.7 0.7) (thickness 0.15)) (justify left bottom mirror))
    )
    (fp_text user "Author: Antmicro" (at -0.95 -4.169 180) (layer "B.Fab") hide
        (effects (font (size 0.7 0.7) (thickness 0.15)) (justify left bottom mirror))
    )
    (fp_rect (start -0.925 0.47) (end 0.925 -0.47)
      (stroke (width 0.05) (type default)) (fill none) (layer "B.CrtYd"))
    (fp_rect (start -0.5 0.25) (end 0.5 -0.25)
      (stroke (width 0.15) (type solid)) (fill none) (layer "B.Fab"))
    (pad "1" smd roundrect (at -0.48 0) (size 0.59 0.64) (layers "B.Cu" "B.Paste" "B.Mask") (roundrect_rratio 0.25)
      (net 97 "Net-(U1-EXTVCC)") (pintype "passive"))
    (pad "2" smd roundrect (at 0.48 0) (size 0.59 0.64) (layers "B.Cu" "B.Paste" "B.Mask") (roundrect_rratio 0.25)
      (net 75 "Net-(C32-Pad2)") (pintype "passive"))
  )

  (footprint "antmicro-footprints:C_0402_1005Metric" (layer "B.Cu")
    (at 108.915 82.67 180)
    (descr "Capacitor SMD 0402")
    (tags "capacitor SMD 0402")
    (property "Author" "Antmicro")
    (property "Dielectric" "")
    (property "License" "Apache-2.0")
    (property "MPN" "C1005X6S1A105K050BC")
    (property "Manufacturer" "TDK")
    (property "Sheetfile" "power.kicad_sch")
    (property "Sheetname" "Power")
    (property "Val" "1u")
    (property "Voltage" "")
    (property "ki_description" "SMD Multilayer Ceramic Capacitor, 1 µF, 10 V, 0402 [1005 Metric], ± 10%, X6S, C")
    (property "ki_keywords" "0402, SMT, CAPACITOR, PASSIVE, CERAMIC, MLCC")
    (attr smd)
    (fp_text reference "C18" (at -1.067 5.708) (layer "B.SilkS")
        (effects (font (size 0.7 0.7) (thickness 0.15)) (justify left bottom mirror))
    )
    (fp_text value "C_1u_0402" (at -1.022927 -2.155213) (layer "B.Fab")
        (effects (font (size 0.7 0.7) (thickness 0.15)) (justify left bottom mirror))
    )
    (fp_text user "Author: Antmicro" (at -0.939 -3.399) (layer "B.Fab") hide
        (effects (font (size 0.7 0.7) (thickness 0.15)) (justify left bottom mirror))
    )
    (fp_text user "License: Apache-2.0" (at -0.939 -5.799) (layer "B.Fab") hide
        (effects (font (size 0.7 0.7) (thickness 0.15)) (justify left bottom mirror))
    )
    (fp_text user "${REFERENCE}" (at -0.939 -4.599) (layer "B.Fab") hide
        (effects (font (size 0.7 0.7) (thickness 0.15)) (justify left bottom mirror))
    )
    (fp_rect (start -0.925 0.47) (end 0.925 -0.47)
      (stroke (width 0.05) (type default)) (fill none) (layer "B.CrtYd"))
    (fp_line (start -0.494 -0.248) (end -0.494 0.25)
      (stroke (width 0.15) (type solid)) (layer "B.Fab"))
    (fp_line (start -0.494 0.25) (end 0.504 0.25)
      (stroke (width 0.15) (type solid)) (layer "B.Fab"))
    (fp_line (start 0.504 -0.248) (end -0.494 -0.248)
      (stroke (width 0.15) (type solid)) (layer "B.Fab"))
    (fp_line (start 0.504 0.25) (end 0.504 -0.248)
      (stroke (width 0.15) (type solid)) (layer "B.Fab"))
    (pad "1" smd roundrect (at -0.48 0 180) (size 0.59 0.64) (layers "B.Cu" "B.Paste" "B.Mask") (roundrect_rratio 0.25)
      (net 1 "GND") (pintype "passive"))
    (pad "2" smd roundrect (at 0.48 0 180) (size 0.59 0.64) (layers "B.Cu" "B.Paste" "B.Mask") (roundrect_rratio 0.25)
      (net 91 "Net-(U1-INTVCC)") (pintype "passive"))
  )

  (footprint "antmicro-footprints:C_0402_1005Metric" (layer "B.Cu")
    (at 139.5 92.65 -90)
    (descr "Capacitor SMD 0402")
    (tags "capacitor SMD 0402")
    (property "Author" "Antmicro")
    (property "Dielectric" "")
    (property "License" "Apache-2.0")
    (property "MPN" "CC0402KRX5R6BB224")
    (property "Manufacturer" "YAGEO")
    (property "Sheetfile" "tb.kicad_sch")
    (property "Sheetname" "TB Controller")
    (property "Val" "220n")
    (property "Voltage" "")
    (property "ki_description" "SMD Multilayer Ceramic Capacitor, 0.22 µF, 10 V, 0402 [1005 Metric], ± 10%, X5R, CC Series")
    (property "ki_keywords" "0402, SMT, CAPACITOR, PASSIVE, MLCC, CERAMIC")
    (attr smd)
    (fp_text reference "C112" (at -3.877 -0.47 90) (layer "B.SilkS")
        (effects (font (size 0.7 0.7) (thickness 0.15)) (justify left bottom mirror))
    )
    (fp_text value "C_220n_0402" (at -1.022927 -2.155213 90) (layer "B.Fab")
        (effects (font (size 0.7 0.7) (thickness 0.15)) (justify left bottom mirror))
    )
    (fp_text user "Author: Antmicro" (at -0.939 -3.399 90) (layer "B.Fab") hide
        (effects (font (size 0.7 0.7) (thickness 0.15)) (justify left bottom mirror))
    )
    (fp_text user "License: Apache-2.0" (at -0.939 -5.799 90) (layer "B.Fab") hide
        (effects (font (size 0.7 0.7) (thickness 0.15)) (justify left bottom mirror))
    )
    (fp_text user "${REFERENCE}" (at -0.939 -4.599 90) (layer "B.Fab") hide
        (effects (font (size 0.7 0.7) (thickness 0.15)) (justify left bottom mirror))
    )
    (fp_rect (start -0.925 0.47) (end 0.925 -0.47)
      (stroke (width 0.05) (type default)) (fill none) (layer "B.CrtYd"))
    (fp_line (start -0.494 -0.248) (end -0.494 0.25)
      (stroke (width 0.15) (type solid)) (layer "B.Fab"))
    (fp_line (start -0.494 0.25) (end 0.504 0.25)
      (stroke (width 0.15) (type solid)) (layer "B.Fab"))
    (fp_line (start 0.504 -0.248) (end -0.494 -0.248)
      (stroke (width 0.15) (type solid)) (layer "B.Fab"))
    (fp_line (start 0.504 0.25) (end 0.504 -0.248)
      (stroke (width 0.15) (type solid)) (layer "B.Fab"))
    (pad "1" smd roundrect (at -0.48 0 270) (size 0.59 0.64) (layers "B.Cu" "B.Paste" "B.Mask") (roundrect_rratio 0.25)
      (net 83 "/TB Controller/TX3_P") (pintype "passive"))
    (pad "2" smd roundrect (at 0.48 0 270) (size 0.59 0.64) (layers "B.Cu" "B.Paste" "B.Mask") (roundrect_rratio 0.25)
      (net 31 "PCIE_TX3_P") (pintype "passive"))
  )

  (footprint "antmicro-footprints:R_0402_1005Metric" (layer "B.Cu")
    (at 151.41 64.97 180)
    (descr "Resistor SMD 0402")
    (tags "resistor SMD 0402")
    (property "Author" "Antmicro")
    (property "License" "Apache-2.0")
    (property "MPN" "CR0402-FX-1003GLF")
    (property "Manufacturer" "Bourns")
    (property "Sheetfile" "power.kicad_sch")
    (property "Sheetname" "Power")
    (property "Tolerance" "1%")
    (property "Val" "100k")
    (property "ki_description" "SMD Chip Resistor, 100 kohm, ± 1%, 62.5 mW, 0402 [1005 Metric], Thick Film, General Purpose")
    (property "ki_keywords" "0402, SMT, RESISTOR, PASSIVE")
    (attr smd)
    (fp_text reference "R10" (at 0.961516 -0.398303) (layer "B.SilkS")
        (effects (font (size 0.7 0.7) (thickness 0.15)) (justify left bottom mirror))
    )
    (fp_text value "R_100k_0402" (at -1.011843 -1.772047) (layer "B.Fab")
        (effects (font (size 0.7 0.7) (thickness 0.15)) (justify left bottom mirror))
    )
    (fp_text user "${REFERENCE}" (at -0.95 -3.168) (layer "B.Fab") hide
        (effects (font (size 0.7 0.7) (thickness 0.15)) (justify left bottom mirror))
    )
    (fp_text user "License: Apache-2.0" (at -0.95 -5.169) (layer "B.Fab") hide
        (effects (font (size 0.7 0.7) (thickness 0.15)) (justify left bottom mirror))
    )
    (fp_text user "Author: Antmicro" (at -0.95 -4.169) (layer "B.Fab") hide
        (effects (font (size 0.7 0.7) (thickness 0.15)) (justify left bottom mirror))
    )
    (fp_rect (start -0.925 0.47) (end 0.925 -0.47)
      (stroke (width 0.05) (type default)) (fill none) (layer "B.CrtYd"))
    (fp_rect (start -0.5 0.25) (end 0.5 -0.25)
      (stroke (width 0.15) (type solid)) (fill none) (layer "B.Fab"))
    (pad "1" smd roundrect (at -0.48 0 180) (size 0.59 0.64) (layers "B.Cu" "B.Paste" "B.Mask") (roundrect_rratio 0.25)
      (net 9 "/Power/TPS_3V3") (pintype "passive"))
    (pad "2" smd roundrect (at 0.48 0 180) (size 0.59 0.64) (layers "B.Cu" "B.Paste" "B.Mask") (roundrect_rratio 0.25)
      (net 23 "AUX_N") (pintype "passive"))
  )

  (footprint "antmicro-footprints:R_0402_1005Metric" (layer "B.Cu")
    (at 117.15 91.63 90)
    (descr "Resistor SMD 0402")
    (tags "resistor SMD 0402")
    (property "Author" "Antmicro")
    (property "License" "Apache-2.0")
    (property "MPN" "CR0402-FX-1002GLF")
    (property "Manufacturer" "Bourns")
    (property "Sheetfile" "power.kicad_sch")
    (property "Sheetname" "Power")
    (property "Tolerance" "1%")
    (property "Val" "10k")
    (property "ki_description" "SMD Chip Resistor, 10 kohm, ± 1%, 62.5 mW, 0402 [1005 Metric], Thick Film, General Purpose")
    (property "ki_keywords" "0402, SMT, RESISTOR, PASSIVE")
    (attr smd)
    (fp_text reference "R94" (at 1.079 3.515 270) (layer "B.SilkS")
        (effects (font (size 0.7 0.7) (thickness 0.15)) (justify left bottom mirror))
    )
    (fp_text value "R_10k_0402" (at -1.011843 -1.772047 270) (layer "B.Fab")
        (effects (font (size 0.7 0.7) (thickness 0.15)) (justify left bottom mirror))
    )
    (fp_text user "${REFERENCE}" (at -0.95 -3.168 270) (layer "B.Fab") hide
        (effects (font (size 0.7 0.7) (thickness 0.15)) (justify left bottom mirror))
    )
    (fp_text user "License: Apache-2.0" (at -0.95 -5.169 270) (layer "B.Fab") hide
        (effects (font (size 0.7 0.7) (thickness 0.15)) (justify left bottom mirror))
    )
    (fp_text user "Author: Antmicro" (at -0.95 -4.169 270) (layer "B.Fab") hide
        (effects (font (size 0.7 0.7) (thickness 0.15)) (justify left bottom mirror))
    )
    (fp_rect (start -0.925 0.47) (end 0.925 -0.47)
      (stroke (width 0.05) (type default)) (fill none) (layer "B.CrtYd"))
    (fp_rect (start -0.5 0.25) (end 0.5 -0.25)
      (stroke (width 0.15) (type solid)) (fill none) (layer "B.Fab"))
    (pad "1" smd roundrect (at -0.48 0 90) (size 0.59 0.64) (layers "B.Cu" "B.Paste" "B.Mask") (roundrect_rratio 0.25)
      (net 1 "GND") (pintype "passive"))
    (pad "2" smd roundrect (at 0.48 0 90) (size 0.59 0.64) (layers "B.Cu" "B.Paste" "B.Mask") (roundrect_rratio 0.25)
      (net 144 "Net-(Q4-REF)") (pintype "passive"))
  )

  (footprint "antmicro-footprints:R_0402_1005Metric" (layer "B.Cu")
    (at 108.915 81.66)
    (descr "Resistor SMD 0402")
    (tags "resistor SMD 0402")
    (property "Author" "Antmicro")
    (property "License" "Apache-2.0")
    (property "MPN" "CR0402-FX-1003GLF")
    (property "Manufacturer" "Bourns")
    (property "Sheetfile" "power.kicad_sch")
    (property "Sheetname" "Power")
    (property "Tolerance" "1%")
    (property "Val" "100k")
    (property "ki_description" "SMD Chip Resistor, 100 kohm, ± 1%, 62.5 mW, 0402 [1005 Metric], Thick Film, General Purpose")
    (property "ki_keywords" "0402, SMT, RESISTOR, PASSIVE")
    (attr smd)
    (fp_text reference "R22" (at 1.067 -5.714 180) (layer "B.SilkS")
        (effects (font (size 0.7 0.7) (thickness 0.15)) (justify left bottom mirror))
    )
    (fp_text value "R_100k_0402" (at -1.011843 -1.772047 180) (layer "B.Fab")
        (effects (font (size 0.7 0.7) (thickness 0.15)) (justify left bottom mirror))
    )
    (fp_text user "Author: Antmicro" (at -0.95 -4.169 180) (layer "B.Fab") hide
        (effects (font (size 0.7 0.7) (thickness 0.15)) (justify left bottom mirror))
    )
    (fp_text user "License: Apache-2.0" (at -0.95 -5.169 180) (layer "B.Fab") hide
        (effects (font (size 0.7 0.7) (thickness 0.15)) (justify left bottom mirror))
    )
    (fp_text user "${REFERENCE}" (at -0.95 -3.168 180) (layer "B.Fab") hide
        (effects (font (size 0.7 0.7) (thickness 0.15)) (justify left bottom mirror))
    )
    (fp_rect (start -0.925 0.47) (end 0.925 -0.47)
      (stroke (width 0.05) (type default)) (fill none) (layer "B.CrtYd"))
    (fp_rect (start -0.5 0.25) (end 0.5 -0.25)
      (stroke (width 0.15) (type solid)) (fill none) (layer "B.Fab"))
    (pad "1" smd roundrect (at -0.48 0) (size 0.59 0.64) (layers "B.Cu" "B.Paste" "B.Mask") (roundrect_rratio 0.25)
      (net 91 "Net-(U1-INTVCC)") (pintype "passive"))
    (pad "2" smd roundrect (at 0.48 0) (size 0.59 0.64) (layers "B.Cu" "B.Paste" "B.Mask") (roundrect_rratio 0.25)
      (net 157 "Net-(U1-~{PGOOD})") (pintype "passive"))
  )

  (footprint "antmicro-footprints:C_0402_1005Metric" (layer "B.Cu")
    (at 122.998 76.97 180)
    (descr "Capacitor SMD 0402")
    (tags "capacitor SMD 0402")
    (property "Author" "Antmicro")
    (property "Dielectric" "C0G")
    (property "License" "Apache-2.0")
    (property "MPN" "GCM1555C1H100GA16D")
    (property "Manufacturer" "Murata")
    (property "Sheetfile" "tb.kicad_sch")
    (property "Sheetname" "TB Controller")
    (property "Val" "10p")
    (property "Voltage" "50V")
    (property "ki_description" "SMD Multilayer Ceramic Capacitor, 10 pF, 50 V, 0402 [1005 Metric], ± 2%, C0G / NP0, GCM")
    (property "ki_keywords" "0402, SMT, CAPACITOR, PASSIVE")
    (attr smd)
    (fp_text reference "C114" (at -1.081 -1.516) (layer "B.SilkS")
        (effects (font (size 0.7 0.7) (thickness 0.15)) (justify left bottom mirror))
    )
    (fp_text value "C_10p_0402" (at -1.022927 -2.155213) (layer "B.Fab")
        (effects (font (size 0.7 0.7) (thickness 0.15)) (justify left bottom mirror))
    )
    (fp_text user "${REFERENCE}" (at -0.939 -4.599) (layer "B.Fab") hide
        (effects (font (size 0.7 0.7) (thickness 0.15)) (justify left bottom mirror))
    )
    (fp_text user "Author: Antmicro" (at -0.939 -3.399) (layer "B.Fab") hide
        (effects (font (size 0.7 0.7) (thickness 0.15)) (justify left bottom mirror))
    )
    (fp_text user "License: Apache-2.0" (at -0.939 -5.799) (layer "B.Fab") hide
        (effects (font (size 0.7 0.7) (thickness 0.15)) (justify left bottom mirror))
    )
    (fp_rect (start -0.925 0.47) (end 0.925 -0.47)
      (stroke (width 0.05) (type default)) (fill none) (layer "B.CrtYd"))
    (fp_line (start -0.494 -0.248) (end -0.494 0.25)
      (stroke (width 0.15) (type solid)) (layer "B.Fab"))
    (fp_line (start -0.494 0.25) (end 0.504 0.25)
      (stroke (width 0.15) (type solid)) (layer "B.Fab"))
    (fp_line (start 0.504 -0.248) (end -0.494 -0.248)
      (stroke (width 0.15) (type solid)) (layer "B.Fab"))
    (fp_line (start 0.504 0.25) (end 0.504 -0.248)
      (stroke (width 0.15) (type solid)) (layer "B.Fab"))
    (pad "1" smd roundrect (at -0.48 0 180) (size 0.59 0.64) (layers "B.Cu" "B.Paste" "B.Mask") (roundrect_rratio 0.25)
      (net 1 "GND") (pintype "passive"))
    (pad "2" smd roundrect (at 0.48 0 180) (size 0.59 0.64) (layers "B.Cu" "B.Paste" "B.Mask") (roundrect_rratio 0.25)
      (net 116 "Net-(U6-XIN{slash}CLKIN)") (pintype "passive"))
  )

  (footprint "antmicro-footprints:R_0402_1005Metric" (layer "B.Cu")
    (at 116.920001 60.195)
    (descr "Resistor SMD 0402")
    (tags "resistor SMD 0402")
    (property "Author" "Antmicro")
    (property "License" "Apache-2.0")
    (property "MPN" "CR0402-FX-4022GLF")
    (property "Manufacturer" "Bourns")
    (property "Sheetfile" "power.kicad_sch")
    (property "Sheetname" "Power")
    (property "Tolerance" "1%")
    (property "Val" "40k2")
    (property "ki_description" "SMD Chip Resistor, 40.2 kohm, ± 1%, 63 mW, 0402 [1005 Metric], Thick Film, General Purpose")
    (property "ki_keywords" "0402, SMT, RESISTOR, PASSIVE")
    (attr smd)
    (fp_text reference "R36" (at 3.094999 0.384 180) (layer "B.SilkS")
        (effects (font (size 0.7 0.7) (thickness 0.15)) (justify left bottom mirror))
    )
    (fp_text value "R_40k2_0402" (at -1.011843 -1.772047 180) (layer "B.Fab")
        (effects (font (size 0.7 0.7) (thickness 0.15)) (justify left bottom mirror))
    )
    (fp_text user "License: Apache-2.0" (at -0.95 -5.169 180) (layer "B.Fab") hide
        (effects (font (size 0.7 0.7) (thickness 0.15)) (justify left bottom mirror))
    )
    (fp_text user "${REFERENCE}" (at -0.95 -3.168 180) (layer "B.Fab") hide
        (effects (font (size 0.7 0.7) (thickness 0.15)) (justify left bottom mirror))
    )
    (fp_text user "Author: Antmicro" (at -0.95 -4.169 180) (layer "B.Fab") hide
        (effects (font (size 0.7 0.7) (thickness 0.15)) (justify left bottom mirror))
    )
    (fp_rect (start -0.925 0.47) (end 0.925 -0.47)
      (stroke (width 0.05) (type default)) (fill none) (layer "B.CrtYd"))
    (fp_rect (start -0.5 0.25) (end 0.5 -0.25)
      (stroke (width 0.15) (type solid)) (fill none) (layer "B.Fab"))
    (pad "1" smd roundrect (at -0.48 0) (size 0.59 0.64) (layers "B.Cu" "B.Paste" "B.Mask") (roundrect_rratio 0.25)
      (net 99 "Net-(U2-FB)") (pintype "passive"))
    (pad "2" smd roundrect (at 0.48 0) (size 0.59 0.64) (layers "B.Cu" "B.Paste" "B.Mask") (roundrect_rratio 0.25)
      (net 100 "Net-(D2-A)") (pintype "passive"))
  )

  (footprint "antmicro-footprints:R_0402_1005Metric" (layer "B.Cu")
    (at 130.05 70.72 -90)
    (descr "Resistor SMD 0402")
    (tags "resistor SMD 0402")
    (property "Author" "Antmicro")
    (property "License" "Apache-2.0")
    (property "MPN" "CR0402-FX-1003GLF")
    (property "Manufacturer" "Bourns")
    (property "Sheetfile" "tb.kicad_sch")
    (property "Sheetname" "TB Controller")
    (property "Tolerance" "1%")
    (property "Val" "100k")
    (property "ki_description" "SMD Chip Resistor, 100 kohm, ± 1%, 62.5 mW, 0402 [1005 Metric], Thick Film, General Purpose")
    (property "ki_keywords" "0402, SMT, RESISTOR, PASSIVE")
    (attr smd)
    (fp_text reference "R57" (at 0.908 -0.379 90) (layer "B.SilkS")
        (effects (font (size 0.7 0.7) (thickness 0.15)) (justify left bottom mirror))
    )
    (fp_text value "R_100k_0402" (at -1.011843 -1.772047 90) (layer "B.Fab")
        (effects (font (size 0.7 0.7) (thickness 0.15)) (justify left bottom mirror))
    )
    (fp_text user "Author: Antmicro" (at -0.95 -4.169 90) (layer "B.Fab") hide
        (effects (font (size 0.7 0.7) (thickness 0.15)) (justify left bottom mirror))
    )
    (fp_text user "${REFERENCE}" (at -0.95 -3.168 90) (layer "B.Fab") hide
        (effects (font (size 0.7 0.7) (thickness 0.15)) (justify left bottom mirror))
    )
    (fp_text user "License: Apache-2.0" (at -0.95 -5.169 90) (layer "B.Fab") hide
        (effects (font (size 0.7 0.7) (thickness 0.15)) (justify left bottom mirror))
    )
    (fp_rect (start -0.925 0.47) (end 0.925 -0.47)
      (stroke (width 0.05) (type default)) (fill none) (layer "B.CrtYd"))
    (fp_rect (start -0.5 0.25) (end 0.5 -0.25)
      (stroke (width 0.15) (type solid)) (fill none) (layer "B.Fab"))
    (pad "1" smd roundrect (at -0.48 0 270) (size 0.59 0.64) (layers "B.Cu" "B.Paste" "B.Mask") (roundrect_rratio 0.25)
      (net 1 "GND") (pintype "passive"))
    (pad "2" smd roundrect (at 0.48 0 270) (size 0.59 0.64) (layers "B.Cu" "B.Paste" "B.Mask") (roundrect_rratio 0.25)
      (net 171 "Net-(U4C-DPSNK0_HPD)") (pintype "passive"))
  )

  (footprint "antmicro-footprints:C_0402_1005Metric" (layer "B.Cu")
    (at 143.15 74.482 -90)
    (descr "Capacitor SMD 0402")
    (tags "capacitor SMD 0402")
    (property "Author" "Antmicro")
    (property "Dielectric" "")
    (property "License" "Apache-2.0")
    (property "MPN" "CC0402MRX5R5BB106")
    (property "Manufacturer" "YAGEO")
    (property "Sheetfile" "tb-power.kicad_sch")
    (property "Sheetname" "Thunderbolt Controller - Power")
    (property "Val" "10u")
    (property "Voltage" "")
    (property "ki_description" "SMD Multilayer Ceramic Capacitor, 10 µF, 6.3 V, 0402 [1005 Metric], ± 20%, X5R, CC Series")
    (property "ki_keywords" "0402, SMT, CAPACITOR, PASSIVE, MLCC, CERAMIC")
    (attr smd)
    (fp_text reference "C70" (at -5.521 -1.503 90) (layer "B.SilkS")
        (effects (font (size 0.7 0.7) (thickness 0.15)) (justify left bottom mirror))
    )
    (fp_text value "C_10u_0402" (at -1.022927 -2.155213 90) (layer "B.Fab")
        (effects (font (size 0.7 0.7) (thickness 0.15)) (justify left bottom mirror))
    )
    (fp_text user "Author: Antmicro" (at -0.939 -3.399 90) (layer "B.Fab") hide
        (effects (font (size 0.7 0.7) (thickness 0.15)) (justify left bottom mirror))
    )
    (fp_text user "${REFERENCE}" (at -0.939 -4.599 90) (layer "B.Fab") hide
        (effects (font (size 0.7 0.7) (thickness 0.15)) (justify left bottom mirror))
    )
    (fp_text user "License: Apache-2.0" (at -0.939 -5.799 90) (layer "B.Fab") hide
        (effects (font (size 0.7 0.7) (thickness 0.15)) (justify left bottom mirror))
    )
    (fp_rect (start -0.925 0.47) (end 0.925 -0.47)
      (stroke (width 0.05) (type default)) (fill none) (layer "B.CrtYd"))
    (fp_line (start -0.494 -0.248) (end -0.494 0.25)
      (stroke (width 0.15) (type solid)) (layer "B.Fab"))
    (fp_line (start -0.494 0.25) (end 0.504 0.25)
      (stroke (width 0.15) (type solid)) (layer "B.Fab"))
    (fp_line (start 0.504 -0.248) (end -0.494 -0.248)
      (stroke (width 0.15) (type solid)) (layer "B.Fab"))
    (fp_line (start 0.504 0.25) (end 0.504 -0.248)
      (stroke (width 0.15) (type solid)) (layer "B.Fab"))
    (pad "1" smd roundrect (at -0.48 0 270) (size 0.59 0.64) (layers "B.Cu" "B.Paste" "B.Mask") (roundrect_rratio 0.25)
      (net 1 "GND") (pintype "passive"))
    (pad "2" smd roundrect (at 0.48 0 270) (size 0.59 0.64) (layers "B.Cu" "B.Paste" "B.Mask") (roundrect_rratio 0.25)
      (net 2 "3V3_SYS") (pintype "passive"))
  )

  (footprint "antmicro-footprints:C_0402_1005Metric" (layer "B.Cu")
    (at 134.8 79.85)
    (descr "Capacitor SMD 0402")
    (tags "capacitor SMD 0402")
    (property "Author" "Antmicro")
    (property "Dielectric" "")
    (property "License" "Apache-2.0")
    (property "MPN" "C1005X6S1A105K050BC")
    (property "Manufacturer" "TDK")
    (property "Sheetfile" "tb-power.kicad_sch")
    (property "Sheetname" "Thunderbolt Controller - Power")
    (property "Val" "1u")
    (property "Voltage" "")
    (property "ki_description" "SMD Multilayer Ceramic Capacitor, 1 µF, 10 V, 0402 [1005 Metric], ± 10%, X6S, C")
    (property "ki_keywords" "0402, SMT, CAPACITOR, PASSIVE, CERAMIC, MLCC")
    (attr smd)
    (fp_text reference "C67" (at 17.6 7.653 180) (layer "B.SilkS")
        (effects (font (size 0.7 0.7) (thickness 0.15)) (justify left bottom mirror))
    )
    (fp_text value "C_1u_0402" (at -1.022927 -2.155213 180) (layer "B.Fab")
        (effects (font (size 0.7 0.7) (thickness 0.15)) (justify left bottom mirror))
    )
    (fp_text user "${REFERENCE}" (at -0.939 -4.599 180) (layer "B.Fab") hide
        (effects (font (size 0.7 0.7) (thickness 0.15)) (justify left bottom mirror))
    )
    (fp_text user "License: Apache-2.0" (at -0.939 -5.799 180) (layer "B.Fab") hide
        (effects (font (size 0.7 0.7) (thickness 0.15)) (justify left bottom mirror))
    )
    (fp_text user "Author: Antmicro" (at -0.939 -3.399 180) (layer "B.Fab") hide
        (effects (font (size 0.7 0.7) (thickness 0.15)) (justify left bottom mirror))
    )
    (fp_rect (start -0.925 0.47) (end 0.925 -0.47)
      (stroke (width 0.05) (type default)) (fill none) (layer "B.CrtYd"))
    (fp_line (start -0.494 -0.248) (end -0.494 0.25)
      (stroke (width 0.15) (type solid)) (layer "B.Fab"))
    (fp_line (start -0.494 0.25) (end 0.504 0.25)
      (stroke (width 0.15) (type solid)) (layer "B.Fab"))
    (fp_line (start 0.504 -0.248) (end -0.494 -0.248)
      (stroke (width 0.15) (type solid)) (layer "B.Fab"))
    (fp_line (start 0.504 0.25) (end 0.504 -0.248)
      (stroke (width 0.15) (type solid)) (layer "B.Fab"))
    (pad "1" smd roundrect (at -0.48 0) (size 0.59 0.64) (layers "B.Cu" "B.Paste" "B.Mask") (roundrect_rratio 0.25)
      (net 1 "GND") (pintype "passive"))
    (pad "2" smd roundrect (at 0.48 0) (size 0.59 0.64) (layers "B.Cu" "B.Paste" "B.Mask") (roundrect_rratio 0.25)
      (net 106 "Net-(C53-Pad2)") (pintype "passive"))
  )

  (footprint "antmicro-footprints:C_0402_1005Metric" (layer "B.Cu")
    (at 130.9 78.875)
    (descr "Capacitor SMD 0402")
    (tags "capacitor SMD 0402")
    (property "Author" "Antmicro")
    (property "Dielectric" "")
    (property "License" "Apache-2.0")
    (property "MPN" "C1005X6S1A105K050BC")
    (property "Manufacturer" "TDK")
    (property "Sheetfile" "tb-power.kicad_sch")
    (property "Sheetname" "Thunderbolt Controller - Power")
    (property "Val" "1u")
    (property "Voltage" "")
    (property "ki_description" "SMD Multilayer Ceramic Capacitor, 1 µF, 10 V, 0402 [1005 Metric], ± 10%, X6S, C")
    (property "ki_keywords" "0402, SMT, CAPACITOR, PASSIVE, CERAMIC, MLCC")
    (attr smd)
    (fp_text reference "C63" (at 17.309 7.567 180) (layer "B.SilkS")
        (effects (font (size 0.7 0.7) (thickness 0.15)) (justify left bottom mirror))
    )
    (fp_text value "C_1u_0402" (at -1.022927 -2.155213 180) (layer "B.Fab")
        (effects (font (size 0.7 0.7) (thickness 0.15)) (justify left bottom mirror))
    )
    (fp_text user "License: Apache-2.0" (at -0.939 -5.799 180) (layer "B.Fab") hide
        (effects (font (size 0.7 0.7) (thickness 0.15)) (justify left bottom mirror))
    )
    (fp_text user "${REFERENCE}" (at -0.939 -4.599 180) (layer "B.Fab") hide
        (effects (font (size 0.7 0.7) (thickness 0.15)) (justify left bottom mirror))
    )
    (fp_text user "Author: Antmicro" (at -0.939 -3.399 180) (layer "B.Fab") hide
        (effects (font (size 0.7 0.7) (thickness 0.15)) (justify left bottom mirror))
    )
    (fp_rect (start -0.925 0.47) (end 0.925 -0.47)
      (stroke (width 0.05) (type default)) (fill none) (layer "B.CrtYd"))
    (fp_line (start -0.494 -0.248) (end -0.494 0.25)
      (stroke (width 0.15) (type solid)) (layer "B.Fab"))
    (fp_line (start -0.494 0.25) (end 0.504 0.25)
      (stroke (width 0.15) (type solid)) (layer "B.Fab"))
    (fp_line (start 0.504 -0.248) (end -0.494 -0.248)
      (stroke (width 0.15) (type solid)) (layer "B.Fab"))
    (fp_line (start 0.504 0.25) (end 0.504 -0.248)
      (stroke (width 0.15) (type solid)) (layer "B.Fab"))
    (pad "1" smd roundrect (at -0.48 0) (size 0.59 0.64) (layers "B.Cu" "B.Paste" "B.Mask") (roundrect_rratio 0.25)
      (net 1 "GND") (pintype "passive"))
    (pad "2" smd roundrect (at 0.48 0) (size 0.59 0.64) (layers "B.Cu" "B.Paste" "B.Mask") (roundrect_rratio 0.25)
      (net 107 "Net-(C54-Pad2)") (pintype "passive"))
  )

  (footprint "antmicro-footprints:C_0402_1005Metric" (layer "B.Cu")
    (at 131.5 92.65 -90)
    (descr "Capacitor SMD 0402")
    (tags "capacitor SMD 0402")
    (property "Author" "Antmicro")
    (property "Dielectric" "")
    (property "License" "Apache-2.0")
    (property "MPN" "CC0402KRX5R6BB224")
    (property "Manufacturer" "YAGEO")
    (property "Sheetfile" "tb.kicad_sch")
    (property "Sheetname" "TB Controller")
    (property "Val" "220n")
    (property "Voltage" "")
    (property "ki_description" "SMD Multilayer Ceramic Capacitor, 0.22 µF, 10 V, 0402 [1005 Metric], ± 10%, X5R, CC Series")
    (property "ki_keywords" "0402, SMT, CAPACITOR, PASSIVE, MLCC, CERAMIC")
    (attr smd)
    (fp_text reference "C110" (at -3.877 -0.47 90) (layer "B.SilkS")
        (effects (font (size 0.7 0.7) (thickness 0.15)) (justify left bottom mirror))
    )
    (fp_text value "C_220n_0402" (at -1.022927 -2.155213 90) (layer "B.Fab")
        (effects (font (size 0.7 0.7) (thickness 0.15)) (justify left bottom mirror))
    )
    (fp_text user "License: Apache-2.0" (at -0.939 -5.799 90) (layer "B.Fab") hide
        (effects (font (size 0.7 0.7) (thickness 0.15)) (justify left bottom mirror))
    )
    (fp_text user "${REFERENCE}" (at -0.939 -4.599 90) (layer "B.Fab") hide
        (effects (font (size 0.7 0.7) (thickness 0.15)) (justify left bottom mirror))
    )
    (fp_text user "Author: Antmicro" (at -0.939 -3.399 90) (layer "B.Fab") hide
        (effects (font (size 0.7 0.7) (thickness 0.15)) (justify left bottom mirror))
    )
    (fp_rect (start -0.925 0.47) (end 0.925 -0.47)
      (stroke (width 0.05) (type default)) (fill none) (layer "B.CrtYd"))
    (fp_line (start -0.494 -0.248) (end -0.494 0.25)
      (stroke (width 0.15) (type solid)) (layer "B.Fab"))
    (fp_line (start -0.494 0.25) (end 0.504 0.25)
      (stroke (width 0.15) (type solid)) (layer "B.Fab"))
    (fp_line (start 0.504 -0.248) (end -0.494 -0.248)
      (stroke (width 0.15) (type solid)) (layer "B.Fab"))
    (fp_line (start 0.504 0.25) (end 0.504 -0.248)
      (stroke (width 0.15) (type solid)) (layer "B.Fab"))
    (pad "1" smd roundrect (at -0.48 0 270) (size 0.59 0.64) (layers "B.Cu" "B.Paste" "B.Mask") (roundrect_rratio 0.25)
      (net 81 "/TB Controller/TX1_P") (pintype "passive"))
    (pad "2" smd roundrect (at 0.48 0 270) (size 0.59 0.64) (layers "B.Cu" "B.Paste" "B.Mask") (roundrect_rratio 0.25)
      (net 29 "PCIE_TX1_P") (pintype "passive"))
  )

  (footprint "antmicro-footprints:R_0402_1005Metric" (layer "B.Cu")
    (at 110.065001 86.17 -90)
    (descr "Resistor SMD 0402")
    (tags "resistor SMD 0402")
    (property "Author" "Antmicro")
    (property "Current" "1A")
    (property "License" "Apache-2.0")
    (property "MPN" "ERJ2GE0R00X")
    (property "Manufacturer" "Panasonic")
    (property "Sheetfile" "power.kicad_sch")
    (property "Sheetname" "Power")
    (property "Tolerance" "")
    (property "Val" "0R")
    (property "ki_description" "SMD Chip Resistor, Jumper, 0 ohm, 100 mW, 0402 [1005 Metric], Thick Film, General Purpose")
    (property "ki_keywords" "0402, SMT, RESISTOR, PASSIVE")
    (attr smd)
    (fp_text reference "R12" (at 0.825 -0.424999 90) (layer "B.SilkS")
        (effects (font (size 0.7 0.7) (thickness 0.15)) (justify left bottom mirror))
    )
    (fp_text value "R_0R_0402" (at -1.011843 -1.772047 90) (layer "B.Fab")
        (effects (font (size 0.7 0.7) (thickness 0.15)) (justify left bottom mirror))
    )
    (fp_text user "License: Apache-2.0" (at -0.95 -5.169 90) (layer "B.Fab") hide
        (effects (font (size 0.7 0.7) (thickness 0.15)) (justify left bottom mirror))
    )
    (fp_text user "Author: Antmicro" (at -0.95 -4.169 90) (layer "B.Fab") hide
        (effects (font (size 0.7 0.7) (thickness 0.15)) (justify left bottom mirror))
    )
    (fp_text user "${REFERENCE}" (at -0.95 -3.168 90) (layer "B.Fab") hide
        (effects (font (size 0.7 0.7) (thickness 0.15)) (justify left bottom mirror))
    )
    (fp_rect (start -0.925 0.47) (end 0.925 -0.47)
      (stroke (width 0.05) (type default)) (fill none) (layer "B.CrtYd"))
    (fp_rect (start -0.5 0.25) (end 0.5 -0.25)
      (stroke (width 0.15) (type solid)) (fill none) (layer "B.Fab"))
    (pad "1" smd roundrect (at -0.48 0 270) (size 0.59 0.64) (layers "B.Cu" "B.Paste" "B.Mask") (roundrect_rratio 0.25)
      (net 5 "Net-(U1-VREF)") (pintype "passive"))
    (pad "2" smd roundrect (at 0.48 0 270) (size 0.59 0.64) (layers "B.Cu" "B.Paste" "B.Mask") (roundrect_rratio 0.25)
      (net 147 "Net-(U1-CTRL)") (pintype "passive"))
  )

  (footprint "antmicro-footprints:C_0402_1005Metric" (layer "B.Cu")
    (at 134.8 77.9)
    (descr "Capacitor SMD 0402")
    (tags "capacitor SMD 0402")
    (property "Author" "Antmicro")
    (property "Dielectric" "")
    (property "License" "Apache-2.0")
    (property "MPN" "C1005X6S1A105K050BC")
    (property "Manufacturer" "TDK")
    (property "Sheetfile" "tb-power.kicad_sch")
    (property "Sheetname" "Thunderbolt Controller - Power")
    (property "Val" "1u")
    (property "Voltage" "")
    (property "ki_description" "SMD Multilayer Ceramic Capacitor, 1 µF, 10 V, 0402 [1005 Metric], ± 10%, X6S, C")
    (property "ki_keywords" "0402, SMT, CAPACITOR, PASSIVE, CERAMIC, MLCC")
    (attr smd)
    (fp_text reference "C64" (at 17.6 7.571 180) (layer "B.SilkS")
        (effects (font (size 0.7 0.7) (thickness 0.15)) (justify left bottom mirror))
    )
    (fp_text value "C_1u_0402" (at -1.022927 -2.155213 180) (layer "B.Fab")
        (effects (font (size 0.7 0.7) (thickness 0.15)) (justify left bottom mirror))
    )
    (fp_text user "License: Apache-2.0" (at -0.939 -5.799 180) (layer "B.Fab") hide
        (effects (font (size 0.7 0.7) (thickness 0.15)) (justify left bottom mirror))
    )
    (fp_text user "${REFERENCE}" (at -0.939 -4.599 180) (layer "B.Fab") hide
        (effects (font (size 0.7 0.7) (thickness 0.15)) (justify left bottom mirror))
    )
    (fp_text user "Author: Antmicro" (at -0.939 -3.399 180) (layer "B.Fab") hide
        (effects (font (size 0.7 0.7) (thickness 0.15)) (justify left bottom mirror))
    )
    (fp_rect (start -0.925 0.47) (end 0.925 -0.47)
      (stroke (width 0.05) (type default)) (fill none) (layer "B.CrtYd"))
    (fp_line (start -0.494 -0.248) (end -0.494 0.25)
      (stroke (width 0.15) (type solid)) (layer "B.Fab"))
    (fp_line (start -0.494 0.25) (end 0.504 0.25)
      (stroke (width 0.15) (type solid)) (layer "B.Fab"))
    (fp_line (start 0.504 -0.248) (end -0.494 -0.248)
      (stroke (width 0.15) (type solid)) (layer "B.Fab"))
    (fp_line (start 0.504 0.25) (end 0.504 -0.248)
      (stroke (width 0.15) (type solid)) (layer "B.Fab"))
    (pad "1" smd roundrect (at -0.48 0) (size 0.59 0.64) (layers "B.Cu" "B.Paste" "B.Mask") (roundrect_rratio 0.25)
      (net 1 "GND") (pintype "passive"))
    (pad "2" smd roundrect (at 0.48 0) (size 0.59 0.64) (layers "B.Cu" "B.Paste" "B.Mask") (roundrect_rratio 0.25)
      (net 106 "Net-(C53-Pad2)") (pintype "passive"))
  )

  (footprint "antmicro-footprints:C_0402_1005Metric" (layer "B.Cu")
    (at 140.16 78.37 -90)
    (descr "Capacitor SMD 0402")
    (tags "capacitor SMD 0402")
    (property "Author" "Antmicro")
    (property "Dielectric" "")
    (property "License" "Apache-2.0")
    (property "MPN" "CC0402MRX5R5BB106")
    (property "Manufacturer" "YAGEO")
    (property "Sheetfile" "tb-power.kicad_sch")
    (property "Sheetname" "Thunderbolt Controller - Power")
    (property "Val" "10u")
    (property "Voltage" "")
    (property "ki_description" "SMD Multilayer Ceramic Capacitor, 10 µF, 6.3 V, 0402 [1005 Metric], ± 20%, X5R, CC Series")
    (property "ki_keywords" "0402, SMT, CAPACITOR, PASSIVE, MLCC, CERAMIC")
    (attr smd)
    (fp_text reference "C75" (at 6.466 -17.066 90) (layer "B.SilkS")
        (effects (font (size 0.7 0.7) (thickness 0.15)) (justify left bottom mirror))
    )
    (fp_text value "C_10u_0402" (at -1.022927 -2.155213 90) (layer "B.Fab")
        (effects (font (size 0.7 0.7) (thickness 0.15)) (justify left bottom mirror))
    )
    (fp_text user "Author: Antmicro" (at -0.939 -3.399 90) (layer "B.Fab") hide
        (effects (font (size 0.7 0.7) (thickness 0.15)) (justify left bottom mirror))
    )
    (fp_text user "License: Apache-2.0" (at -0.939 -5.799 90) (layer "B.Fab") hide
        (effects (font (size 0.7 0.7) (thickness 0.15)) (justify left bottom mirror))
    )
    (fp_text user "${REFERENCE}" (at -0.939 -4.599 90) (layer "B.Fab") hide
        (effects (font (size 0.7 0.7) (thickness 0.15)) (justify left bottom mirror))
    )
    (fp_rect (start -0.925 0.47) (end 0.925 -0.47)
      (stroke (width 0.05) (type default)) (fill none) (layer "B.CrtYd"))
    (fp_line (start -0.494 -0.248) (end -0.494 0.25)
      (stroke (width 0.15) (type solid)) (layer "B.Fab"))
    (fp_line (start -0.494 0.25) (end 0.504 0.25)
      (stroke (width 0.15) (type solid)) (layer "B.Fab"))
    (fp_line (start 0.504 -0.248) (end -0.494 -0.248)
      (stroke (width 0.15) (type solid)) (layer "B.Fab"))
    (fp_line (start 0.504 0.25) (end 0.504 -0.248)
      (stroke (width 0.15) (type solid)) (layer "B.Fab"))
    (pad "1" smd roundrect (at -0.48 0 270) (size 0.59 0.64) (layers "B.Cu" "B.Paste" "B.Mask") (roundrect_rratio 0.25)
      (net 1 "GND") (pintype "passive"))
    (pad "2" smd roundrect (at 0.48 0 270) (size 0.59 0.64) (layers "B.Cu" "B.Paste" "B.Mask") (roundrect_rratio 0.25)
      (net 113 "Net-(U4A-VCC0P9_LVR_SENSE)") (pintype "passive"))
  )

  (footprint "antmicro-footprints:C_0402_1005Metric" (layer "B.Cu")
    (at 116.910001 63.205001)
    (descr "Capacitor SMD 0402")
    (tags "capacitor SMD 0402")
    (property "Author" "Antmicro")
    (property "Dielectric" "")
    (property "License" "Apache-2.0")
    (property "MPN" "C1005X6S1A105K050BC")
    (property "Manufacturer" "TDK")
    (property "Sheetfile" "power.kicad_sch")
    (property "Sheetname" "Power")
    (property "Val" "1u")
    (property "Voltage" "")
    (property "ki_description" "SMD Multilayer Ceramic Capacitor, 1 µF, 10 V, 0402 [1005 Metric], ± 10%, X6S, C")
    (property "ki_keywords" "0402, SMT, CAPACITOR, PASSIVE, CERAMIC, MLCC")
    (attr smd)
    (fp_text reference "C25" (at 3.104999 0.294999 180) (layer "B.SilkS")
        (effects (font (size 0.7 0.7) (thickness 0.15)) (justify left bottom mirror))
    )
    (fp_text value "C_1u_0402" (at -1.022927 -2.155213 180) (layer "B.Fab")
        (effects (font (size 0.7 0.7) (thickness 0.15)) (justify left bottom mirror))
    )
    (fp_text user "License: Apache-2.0" (at -0.939 -5.799 180) (layer "B.Fab") hide
        (effects (font (size 0.7 0.7) (thickness 0.15)) (justify left bottom mirror))
    )
    (fp_text user "Author: Antmicro" (at -0.939 -3.399 180) (layer "B.Fab") hide
        (effects (font (size 0.7 0.7) (thickness 0.15)) (justify left bottom mirror))
    )
    (fp_text user "${REFERENCE}" (at -0.939 -4.599 180) (layer "B.Fab") hide
        (effects (font (size 0.7 0.7) (thickness 0.15)) (justify left bottom mirror))
    )
    (fp_rect (start -0.925 0.47) (end 0.925 -0.47)
      (stroke (width 0.05) (type default)) (fill none) (layer "B.CrtYd"))
    (fp_line (start -0.494 -0.248) (end -0.494 0.25)
      (stroke (width 0.15) (type solid)) (layer "B.Fab"))
    (fp_line (start -0.494 0.25) (end 0.504 0.25)
      (stroke (width 0.15) (type solid)) (layer "B.Fab"))
    (fp_line (start 0.504 -0.248) (end -0.494 -0.248)
      (stroke (width 0.15) (type solid)) (layer "B.Fab"))
    (fp_line (start 0.504 0.25) (end 0.504 -0.248)
      (stroke (width 0.15) (type solid)) (layer "B.Fab"))
    (pad "1" smd roundrect (at -0.48 0) (size 0.59 0.64) (layers "B.Cu" "B.Paste" "B.Mask") (roundrect_rratio 0.25)
      (net 1 "GND") (pintype "passive"))
    (pad "2" smd roundrect (at 0.48 0) (size 0.59 0.64) (layers "B.Cu" "B.Paste" "B.Mask") (roundrect_rratio 0.25)
      (net 6 "/Power/SMPS_LDO") (pintype "passive"))
  )

  (footprint "antmicro-footprints:C_0402_1005Metric" (layer "B.Cu")
    (at 132.85 76.925)
    (descr "Capacitor SMD 0402")
    (tags "capacitor SMD 0402")
    (property "Author" "Antmicro")
    (property "Dielectric" "")
    (property "License" "Apache-2.0")
    (property "MPN" "C1005X6S1A105K050BC")
    (property "Manufacturer" "TDK")
    (property "Sheetfile" "tb-power.kicad_sch")
    (property "Sheetname" "Thunderbolt Controller - Power")
    (property "Val" "1u")
    (property "Voltage" "")
    (property "ki_description" "SMD Multilayer Ceramic Capacitor, 1 µF, 10 V, 0402 [1005 Metric], ± 10%, X6S, C")
    (property "ki_keywords" "0402, SMT, CAPACITOR, PASSIVE, CERAMIC, MLCC")
    (attr smd)
    (fp_text reference "C71" (at 17.518 7.53 180) (layer "B.SilkS")
        (effects (font (size 0.7 0.7) (thickness 0.15)) (justify left bottom mirror))
    )
    (fp_text value "C_1u_0402" (at -1.022927 -2.155213 180) (layer "B.Fab")
        (effects (font (size 0.7 0.7) (thickness 0.15)) (justify left bottom mirror))
    )
    (fp_text user "Author: Antmicro" (at -0.939 -3.399 180) (layer "B.Fab") hide
        (effects (font (size 0.7 0.7) (thickness 0.15)) (justify left bottom mirror))
    )
    (fp_text user "License: Apache-2.0" (at -0.939 -5.799 180) (layer "B.Fab") hide
        (effects (font (size 0.7 0.7) (thickness 0.15)) (justify left bottom mirror))
    )
    (fp_text user "${REFERENCE}" (at -0.939 -4.599 180) (layer "B.Fab") hide
        (effects (font (size 0.7 0.7) (thickness 0.15)) (justify left bottom mirror))
    )
    (fp_rect (start -0.925 0.47) (end 0.925 -0.47)
      (stroke (width 0.05) (type default)) (fill none) (layer "B.CrtYd"))
    (fp_line (start -0.494 -0.248) (end -0.494 0.25)
      (stroke (width 0.15) (type solid)) (layer "B.Fab"))
    (fp_line (start -0.494 0.25) (end 0.504 0.25)
      (stroke (width 0.15) (type solid)) (layer "B.Fab"))
    (fp_line (start 0.504 -0.248) (end -0.494 -0.248)
      (stroke (width 0.15) (type solid)) (layer "B.Fab"))
    (fp_line (start 0.504 0.25) (end 0.504 -0.248)
      (stroke (width 0.15) (type solid)) (layer "B.Fab"))
    (pad "1" smd roundrect (at -0.48 0) (size 0.59 0.64) (layers "B.Cu" "B.Paste" "B.Mask") (roundrect_rratio 0.25)
      (net 1 "GND") (pintype "passive"))
    (pad "2" smd roundrect (at 0.48 0) (size 0.59 0.64) (layers "B.Cu" "B.Paste" "B.Mask") (roundrect_rratio 0.25)
      (net 111 "Net-(U4A-VCC3P3_LC)") (pintype "passive"))
  )

  (footprint "antmicro-footprints:R_0402_1005Metric" (layer "B.Cu")
    (at 154.89 57.39 90)
    (descr "Resistor SMD 0402")
    (tags "resistor SMD 0402")
    (property "Author" "Antmicro")
    (property "License" "Apache-2.0")
    (property "MPN" "CR0402-FX-1003GLF")
    (property "Manufacturer" "Bourns")
    (property "Sheetfile" "power.kicad_sch")
    (property "Sheetname" "Power")
    (property "Tolerance" "1%")
    (property "Val" "100k")
    (property "ki_description" "SMD Chip Resistor, 100 kohm, ± 1%, 62.5 mW, 0402 [1005 Metric], Thick Film, General Purpose")
    (property "ki_keywords" "0402, SMT, RESISTOR, PASSIVE")
    (attr smd)
    (fp_text reference "R30" (at 3.034 0.431 270) (layer "B.SilkS")
        (effects (font (size 0.7 0.7) (thickness 0.15)) (justify left bottom mirror))
    )
    (fp_text value "R_100k_0402" (at -1.011843 -1.772047 270) (layer "B.Fab")
        (effects (font (size 0.7 0.7) (thickness 0.15)) (justify left bottom mirror))
    )
    (fp_text user "Author: Antmicro" (at -0.95 -4.169 270) (layer "B.Fab") hide
        (effects (font (size 0.7 0.7) (thickness 0.15)) (justify left bottom mirror))
    )
    (fp_text user "License: Apache-2.0" (at -0.95 -5.169 270) (layer "B.Fab") hide
        (effects (font (size 0.7 0.7) (thickness 0.15)) (justify left bottom mirror))
    )
    (fp_text user "${REFERENCE}" (at -0.95 -3.168 270) (layer "B.Fab") hide
        (effects (font (size 0.7 0.7) (thickness 0.15)) (justify left bottom mirror))
    )
    (fp_rect (start -0.925 0.47) (end 0.925 -0.47)
      (stroke (width 0.05) (type default)) (fill none) (layer "B.CrtYd"))
    (fp_rect (start -0.5 0.25) (end 0.5 -0.25)
      (stroke (width 0.15) (type solid)) (fill none) (layer "B.Fab"))
    (pad "1" smd roundrect (at -0.48 0 90) (size 0.59 0.64) (layers "B.Cu" "B.Paste" "B.Mask") (roundrect_rratio 0.25)
      (net 163 "Net-(U3-DEBUG_CTL1(GPIO16,_I2CADDR_B4))") (pintype "passive"))
    (pad "2" smd roundrect (at 0.48 0 90) (size 0.59 0.64) (layers "B.Cu" "B.Paste" "B.Mask") (roundrect_rratio 0.25)
      (net 9 "/Power/TPS_3V3") (pintype "passive"))
  )

  (footprint "antmicro-footprints:C_0603_1608Metric" (layer "B.Cu")
    (at 161.98 89.8 90)
    (descr "Capacitor SMD 0603")
    (tags "capacitor 0603")
    (property "Author" "Antmicro")
    (property "Dielectric" "")
    (property "License" "Apache-2.0")
    (property "MPN" "CL10A226MO7JZNC")
    (property "Manufacturer" "Samsung Electro-Mechanics")
    (property "Sheetfile" "power.kicad_sch")
    (property "Sheetname" "Power")
    (property "Val" "22u")
    (property "Voltage" "16V")
    (property "ki_description" "SMD Multilayer Ceramic Capacitor")
    (property "ki_keywords" "0603, SMT, CAPACITOR, PASSIVE, CERAMIC")
    (attr smd)
    (fp_text reference "C119" (at 4.202 0.4 270) (layer "B.SilkS")
        (effects (font (size 0.7 0.7) (thickness 0.15)) (justify left bottom mirror))
    )
    (fp_text value "C_22u_16V_0603" (at -1.42757 -1.770288 270) (layer "B.Fab")
        (effects (font (size 0.7 0.7) (thickness 0.15)) (justify left bottom mirror))
    )
    (fp_text user "${REFERENCE}" (at -1.682 -3.895 270) (layer "B.Fab") hide
        (effects (font (size 0.7 0.7) (thickness 0.15)) (justify left bottom mirror))
    )
    (fp_text user "License: Apache-2.0" (at -1.682 -5.895 270) (layer "B.Fab") hide
        (effects (font (size 0.7 0.7) (thickness 0.15)) (justify left bottom mirror))
    )
    (fp_text user "Author: Antmicro" (at -1.682 -4.894 270) (layer "B.Fab") hide
        (effects (font (size 0.7 0.7) (thickness 0.15)) (justify left bottom mirror))
    )
    (fp_line (start -0.15 -0.4) (end 0.15 -0.4)
      (stroke (width 0.15) (type solid)) (layer "B.SilkS"))
    (fp_line (start -0.15 0.4) (end 0.15 0.4)
      (stroke (width 0.15) (type solid)) (layer "B.SilkS"))
    (fp_rect (start -1.25 0.65) (end 1.25 -0.65)
      (stroke (width 0.05) (type solid)) (fill none) (layer "B.CrtYd"))
    (fp_rect (start -0.8 0.4) (end 0.8 -0.4)
      (stroke (width 0.15) (type solid)) (fill none) (layer "B.Fab"))
    (pad "1" smd roundrect (at -0.7 0 90) (size 0.8 1) (layers "B.Cu" "B.Paste" "B.Mask") (roundrect_rratio 0.2)
      (net 1 "GND") (pintype "passive"))
    (pad "2" smd roundrect (at 0.7 0 90) (size 0.8 1) (layers "B.Cu" "B.Paste" "B.Mask") (roundrect_rratio 0.2)
      (net 61 "12V0_MOLEX") (pintype "passive"))
  )

  (footprint "antmicro-footprints:C_0402_1005Metric" (layer "B.Cu")
    (at 165.2 74.444922 -90)
    (descr "Capacitor SMD 0402")
    (tags "capacitor SMD 0402")
    (property "Author" "Antmicro")
    (property "Dielectric" "X5R")
    (property "License" "Apache-2.0")
    (property "MPN" "GRM155R61H104KE14D")
    (property "Manufacturer" "Murata")
    (property "Sheetfile" "connectors.kicad_sch")
    (property "Sheetname" "Connectors")
    (property "Val" "100n")
    (property "Voltage" "50V")
    (property "ki_description" "SMD Multilayer Ceramic Capacitor, 0.1 µF, 50 V, 0402 [1005 Metric], ± 10%, X5R, GRM Series")
    (property "ki_keywords" "0402, SMT, CAPACITOR, PASSIVE, CERAMIC, MLCC")
    (attr smd)
    (fp_text reference "C4" (at -0.784922 0.608 90) (layer "B.SilkS")
        (effects (font (size 0.7 0.7) (thickness 0.15)) (justify left bottom mirror))
    )
    (fp_text value "C_100n_0402" (at -1.022927 -2.155213 90) (layer "B.Fab")
        (effects (font (size 0.7 0.7) (thickness 0.15)) (justify left bottom mirror))
    )
    (fp_text user "License: Apache-2.0" (at -0.939 -5.799 90) (layer "B.Fab") hide
        (effects (font (size 0.7 0.7) (thickness 0.15)) (justify left bottom mirror))
    )
    (fp_text user "Author: Antmicro" (at -0.939 -3.399 90) (layer "B.Fab") hide
        (effects (font (size 0.7 0.7) (thickness 0.15)) (justify left bottom mirror))
    )
    (fp_text user "${REFERENCE}" (at -0.939 -4.599 90) (layer "B.Fab") hide
        (effects (font (size 0.7 0.7) (thickness 0.15)) (justify left bottom mirror))
    )
    (fp_rect (start -0.925 0.47) (end 0.925 -0.47)
      (stroke (width 0.05) (type default)) (fill none) (layer "B.CrtYd"))
    (fp_line (start -0.494 -0.248) (end -0.494 0.25)
      (stroke (width 0.15) (type solid)) (layer "B.Fab"))
    (fp_line (start -0.494 0.25) (end 0.504 0.25)
      (stroke (width 0.15) (type solid)) (layer "B.Fab"))
    (fp_line (start 0.504 -0.248) (end -0.494 -0.248)
      (stroke (width 0.15) (type solid)) (layer "B.Fab"))
    (fp_line (start 0.504 0.25) (end 0.504 -0.248)
      (stroke (width 0.15) (type solid)) (layer "B.Fab"))
    (pad "1" smd roundrect (at -0.48 0 270) (size 0.59 0.64) (layers "B.Cu" "B.Paste" "B.Mask") (roundrect_rratio 0.25)
      (net 1 "GND") (pintype "passive"))
    (pad "2" smd roundrect (at 0.48 0 270) (size 0.59 0.64) (layers "B.Cu" "B.Paste" "B.Mask") (roundrect_rratio 0.25)
      (net 3 "5V0_USB") (pintype "passive"))
  )

  (footprint "antmicro-footprints:C_0402_1005Metric" (layer "B.Cu")
    (at 140.5 92.65 -90)
    (descr "Capacitor SMD 0402")
    (tags "capacitor SMD 0402")
    (property "Author" "Antmicro")
    (property "Dielectric" "")
    (property "License" "Apache-2.0")
    (property "MPN" "CC0402KRX5R6BB224")
    (property "Manufacturer" "YAGEO")
    (property "Sheetfile" "tb.kicad_sch")
    (property "Sheetname" "TB Controller")
    (property "Val" "220n")
    (property "Voltage" "")
    (property "ki_description" "SMD Multilayer Ceramic Capacitor, 0.22 µF, 10 V, 0402 [1005 Metric], ± 10%, X5R, CC Series")
    (property "ki_keywords" "0402, SMT, CAPACITOR, PASSIVE, MLCC, CERAMIC")
    (attr smd)
    (fp_text reference "C108" (at -3.877 -0.47 90) (layer "B.SilkS")
        (effects (font (size 0.7 0.7) (thickness 0.15)) (justify left bottom mirror))
    )
    (fp_text value "C_220n_0402" (at -1.022927 -2.155213 90) (layer "B.Fab")
        (effects (font (size 0.7 0.7) (thickness 0.15)) (justify left bottom mirror))
    )
    (fp_text user "License: Apache-2.0" (at -0.939 -5.799 90) (layer "B.Fab") hide
        (effects (font (size 0.7 0.7) (thickness 0.15)) (justify left bottom mirror))
    )
    (fp_text user "Author: Antmicro" (at -0.939 -3.399 90) (layer "B.Fab") hide
        (effects (font (size 0.7 0.7) (thickness 0.15)) (justify left bottom mirror))
    )
    (fp_text user "${REFERENCE}" (at -0.939 -4.599 90) (layer "B.Fab") hide
        (effects (font (size 0.7 0.7) (thickness 0.15)) (justify left bottom mirror))
    )
    (fp_rect (start -0.925 0.47) (end 0.925 -0.47)
      (stroke (width 0.05) (type default)) (fill none) (layer "B.CrtYd"))
    (fp_line (start -0.494 -0.248) (end -0.494 0.25)
      (stroke (width 0.15) (type solid)) (layer "B.Fab"))
    (fp_line (start -0.494 0.25) (end 0.504 0.25)
      (stroke (width 0.15) (type solid)) (layer "B.Fab"))
    (fp_line (start 0.504 -0.248) (end -0.494 -0.248)
      (stroke (width 0.15) (type solid)) (layer "B.Fab"))
    (fp_line (start 0.504 0.25) (end 0.504 -0.248)
      (stroke (width 0.15) (type solid)) (layer "B.Fab"))
    (pad "1" smd roundrect (at -0.48 0 270) (size 0.59 0.64) (layers "B.Cu" "B.Paste" "B.Mask") (roundrect_rratio 0.25)
      (net 79 "/TB Controller/TX3_N") (pintype "passive"))
    (pad "2" smd roundrect (at 0.48 0 270) (size 0.59 0.64) (layers "B.Cu" "B.Paste" "B.Mask") (roundrect_rratio 0.25)
      (net 27 "PCIE_TX3_N") (pintype "passive"))
  )

  (footprint "antmicro-footprints:R_0402_1005Metric" (layer "B.Cu")
    (at 135.115 60.395)
    (descr "Resistor SMD 0402")
    (tags "resistor SMD 0402")
    (property "Author" "Antmicro")
    (property "License" "Apache-2.0")
    (property "MPN" "CR0402-FX-3301GLF")
    (property "Manufacturer" "Bourns")
    (property "Sheetfile" "tb.kicad_sch")
    (property "Sheetname" "TB Controller")
    (property "Tolerance" "1%")
    (property "Val" "3k3")
    (property "ki_description" "SMD Chip Resistor, 3.3 kohm, ± 1%, 63 mW, 0402 [1005 Metric], Thick Film, General Purpose")
    (property "ki_keywords" "0402, SMT, RESISTOR, PASSIVE")
    (attr smd)
    (fp_text reference "R52" (at -1.003 0.438 180) (layer "B.SilkS")
        (effects (font (size 0.7 0.7) (thickness 0.15)) (justify left bottom mirror))
    )
    (fp_text value "R_3k3_0402" (at -1.011843 -1.772047 180) (layer "B.Fab")
        (effects (font (size 0.7 0.7) (thickness 0.15)) (justify left bottom mirror))
    )
    (fp_text user "Author: Antmicro" (at -0.95 -4.169 180) (layer "B.Fab") hide
        (effects (font (size 0.7 0.7) (thickness 0.15)) (justify left bottom mirror))
    )
    (fp_text user "License: Apache-2.0" (at -0.95 -5.169 180) (layer "B.Fab") hide
        (effects (font (size 0.7 0.7) (thickness 0.15)) (justify left bottom mirror))
    )
    (fp_text user "${REFERENCE}" (at -0.95 -3.168 180) (layer "B.Fab") hide
        (effects (font (size 0.7 0.7) (thickness 0.15)) (justify left bottom mirror))
    )
    (fp_rect (start -0.925 0.47) (end 0.925 -0.47)
      (stroke (width 0.05) (type default)) (fill none) (layer "B.CrtYd"))
    (fp_rect (start -0.5 0.25) (end 0.5 -0.25)
      (stroke (width 0.15) (type solid)) (fill none) (layer "B.Fab"))
    (pad "1" smd roundrect (at -0.48 0) (size 0.59 0.64) (layers "B.Cu" "B.Paste" "B.Mask") (roundrect_rratio 0.25)
      (net 65 "SPI_CS") (pintype "passive"))
    (pad "2" smd roundrect (at 0.48 0) (size 0.59 0.64) (layers "B.Cu" "B.Paste" "B.Mask") (roundrect_rratio 0.25)
      (net 2 "3V3_SYS") (pintype "passive"))
  )

  (footprint "antmicro-footprints:C_0402_1005Metric" (layer "B.Cu")
    (at 133.325 83.75 90)
    (descr "Capacitor SMD 0402")
    (tags "capacitor SMD 0402")
    (property "Author" "Antmicro")
    (property "Dielectric" "")
    (property "License" "Apache-2.0")
    (property "MPN" "C1005X6S1A105K050BC")
    (property "Manufacturer" "TDK")
    (property "Sheetfile" "tb-power.kicad_sch")
    (property "Sheetname" "Thunderbolt Controller - Power")
    (property "Val" "1u")
    (property "Voltage" "")
    (property "ki_description" "SMD Multilayer Ceramic Capacitor, 1 µF, 10 V, 0402 [1005 Metric], ± 10%, X6S, C")
    (property "ki_keywords" "0402, SMT, CAPACITOR, PASSIVE, CERAMIC, MLCC")
    (attr smd)
    (fp_text reference "C52" (at -5.912 16.916 270) (layer "B.SilkS")
        (effects (font (size 0.7 0.7) (thickness 0.15)) (justify left bottom mirror))
    )
    (fp_text value "C_1u_0402" (at -1.022927 -2.155213 270) (layer "B.Fab")
        (effects (font (size 0.7 0.7) (thickness 0.15)) (justify left bottom mirror))
    )
    (fp_text user "Author: Antmicro" (at -0.939 -3.399 270) (layer "B.Fab") hide
        (effects (font (size 0.7 0.7) (thickness 0.15)) (justify left bottom mirror))
    )
    (fp_text user "${REFERENCE}" (at -0.939 -4.599 270) (layer "B.Fab") hide
        (effects (font (size 0.7 0.7) (thickness 0.15)) (justify left bottom mirror))
    )
    (fp_text user "License: Apache-2.0" (at -0.939 -5.799 270) (layer "B.Fab") hide
        (effects (font (size 0.7 0.7) (thickness 0.15)) (justify left bottom mirror))
    )
    (fp_rect (start -0.925 0.47) (end 0.925 -0.47)
      (stroke (width 0.05) (type default)) (fill none) (layer "B.CrtYd"))
    (fp_line (start -0.494 -0.248) (end -0.494 0.25)
      (stroke (width 0.15) (type solid)) (layer "B.Fab"))
    (fp_line (start -0.494 0.25) (end 0.504 0.25)
      (stroke (width 0.15) (type solid)) (layer "B.Fab"))
    (fp_line (start 0.504 -0.248) (end -0.494 -0.248)
      (stroke (width 0.15) (type solid)) (layer "B.Fab"))
    (fp_line (start 0.504 0.25) (end 0.504 -0.248)
      (stroke (width 0.15) (type solid)) (layer "B.Fab"))
    (pad "1" smd roundrect (at -0.48 0 90) (size 0.59 0.64) (layers "B.Cu" "B.Paste" "B.Mask") (roundrect_rratio 0.25)
      (net 1 "GND") (pintype "passive"))
    (pad "2" smd roundrect (at 0.48 0 90) (size 0.59 0.64) (layers "B.Cu" "B.Paste" "B.Mask") (roundrect_rratio 0.25)
      (net 105 "Net-(C51-Pad2)") (pintype "passive"))
  )

  (footprint "antmicro-footprints:Fiducial_1mm_Mask3mm" (layer "B.Cu")
    (at 161 98 180)
    (descr "Circular Fiducial, 1.5mm bare copper, 3mm soldermask opening")
    (tags "fiducial")
    (property "Author" "Antmicro")
    (property "License" "Apache-2.0")
    (property "Sheetfile" "thunderbolt-pcie-adapter.kicad_sch")
    (property "Sheetname" "")
    (property "exclude_from_bom" "")
    (property "ki_description" "Fiducial mask")
    (attr through_hole exclude_from_bom)
    (fp_text reference "FID8" (at 1.742 -0.425) (layer "B.SilkS")
        (effects (font (size 0.7 0.7) (thickness 0.15)) (justify left bottom mirror))
    )
    (fp_text value "Fiducial_1mm_Mask3mm" (at 0 -2.603) (layer "B.Fab")
        (effects (font (size 0.7 0.7) (thickness 0.15)) (justify left bottom mirror))
    )
    (fp_text user "License: Apache-2.0" (at -1.25 -7.003) (layer "B.Fab") hide
        (effects (font (size 0.7 0.7) (thickness 0.15)) (justify left bottom mirror))
    )
    (fp_text user "Author: Antmicro" (at -1.25 -5.803) (layer "B.Fab") hide
        (effects (font (size 0.7 0.7) (thickness 0.15)) (justify left bottom mirror))
    )
    (fp_text user "${REFERENCE}" (at -1.25 -4.603) (layer "B.Fab") hide
        (effects (font (size 0.7 0.7) (thickness 0.15)) (justify left bottom mirror))
    )
    (fp_circle (center 0 0) (end 1.5 0)
      (stroke (width 0.05) (type solid)) (fill none) (layer "B.CrtYd"))
    (fp_circle (center 0 0) (end 1.5 0)
      (stroke (width 0.15) (type solid)) (fill none) (layer "B.Fab"))
    (pad "" smd circle (at 0 0 180) (size 1 1) (layers "B.Cu" "B.Mask")
      (solder_mask_margin 1) (clearance 1))
  )

  (footprint "antmicro-footprints:C_0402_1005Metric" (layer "B.Cu")
    (at 140.16 80.336001 90)
    (descr "Capacitor SMD 0402")
    (tags "capacitor SMD 0402")
    (property "Author" "Antmicro")
    (property "Dielectric" "")
    (property "License" "Apache-2.0")
    (property "MPN" "CC0402MRX5R5BB106")
    (property "Manufacturer" "YAGEO")
    (property "Sheetfile" "tb-power.kicad_sch")
    (property "Sheetname" "Thunderbolt Controller - Power")
    (property "Val" "10u")
    (property "Voltage" "")
    (property "ki_description" "SMD Multilayer Ceramic Capacitor, 10 µF, 6.3 V, 0402 [1005 Metric], ± 20%, X5R, CC Series")
    (property "ki_keywords" "0402, SMT, CAPACITOR, PASSIVE, MLCC, CERAMIC")
    (attr smd)
    (fp_text reference "C78" (at -6.658999 17.066 270) (layer "B.SilkS")
        (effects (font (size 0.7 0.7) (thickness 0.15)) (justify left bottom mirror))
    )
    (fp_text value "C_10u_0402" (at -1.022927 -2.155213 270) (layer "B.Fab")
        (effects (font (size 0.7 0.7) (thickness 0.15)) (justify left bottom mirror))
    )
    (fp_text user "${REFERENCE}" (at -0.939 -4.599 270) (layer "B.Fab") hide
        (effects (font (size 0.7 0.7) (thickness 0.15)) (justify left bottom mirror))
    )
    (fp_text user "License: Apache-2.0" (at -0.939 -5.799 270) (layer "B.Fab") hide
        (effects (font (size 0.7 0.7) (thickness 0.15)) (justify left bottom mirror))
    )
    (fp_text user "Author: Antmicro" (at -0.939 -3.399 270) (layer "B.Fab") hide
        (effects (font (size 0.7 0.7) (thickness 0.15)) (justify left bottom mirror))
    )
    (fp_rect (start -0.925 0.47) (end 0.925 -0.47)
      (stroke (width 0.05) (type default)) (fill none) (layer "B.CrtYd"))
    (fp_line (start -0.494 -0.248) (end -0.494 0.25)
      (stroke (width 0.15) (type solid)) (layer "B.Fab"))
    (fp_line (start -0.494 0.25) (end 0.504 0.25)
      (stroke (width 0.15) (type solid)) (layer "B.Fab"))
    (fp_line (start 0.504 -0.248) (end -0.494 -0.248)
      (stroke (width 0.15) (type solid)) (layer "B.Fab"))
    (fp_line (start 0.504 0.25) (end 0.504 -0.248)
      (stroke (width 0.15) (type solid)) (layer "B.Fab"))
    (pad "1" smd roundrect (at -0.48 0 90) (size 0.59 0.64) (layers "B.Cu" "B.Paste" "B.Mask") (roundrect_rratio 0.25)
      (net 1 "GND") (pintype "passive"))
    (pad "2" smd roundrect (at 0.48 0 90) (size 0.59 0.64) (layers "B.Cu" "B.Paste" "B.Mask") (roundrect_rratio 0.25)
      (net 113 "Net-(U4A-VCC0P9_LVR_SENSE)") (pintype "passive"))
  )

  (footprint "antmicro-footprints:C_0402_1005Metric" (layer "B.Cu")
    (at 157.91 59.47 -90)
    (descr "Capacitor SMD 0402")
    (tags "capacitor SMD 0402")
    (property "Author" "Antmicro")
    (property "Dielectric" "X5S")
    (property "License" "Apache-2.0")
    (property "MPN" "GRM155C61E475ME15J")
    (property "Manufacturer" "Murata")
    (property "Sheetfile" "power.kicad_sch")
    (property "Sheetname" "Power")
    (property "Val" "4u7")
    (property "Voltage" "25V")
    (property "dnp" "")
    (property "ki_description" "SMD Multilayer Ceramic Capacitor")
    (property "ki_keywords" "0402, SMT, CAPACITOR, PASSIVE, CERAMIC")
    (attr smd)
    (fp_text reference "C20" (at -4.86 5.51 90) (layer "B.SilkS")
        (effects (font (size 0.7 0.7) (thickness 0.15)) (justify left bottom mirror))
    )
    (fp_text value "C_4u7_25V_0402" (at -1.022927 -2.155213 90) (layer "B.Fab")
        (effects (font (size 0.7 0.7) (thickness 0.15)) (justify left bottom mirror))
    )
    (fp_text user "Author: Antmicro" (at -0.939 -3.399 90) (layer "B.Fab") hide
        (effects (font (size 0.7 0.7) (thickness 0.15)) (justify left bottom mirror))
    )
    (fp_text user "License: Apache-2.0" (at -0.939 -5.799 90) (layer "B.Fab") hide
        (effects (font (size 0.7 0.7) (thickness 0.15)) (justify left bottom mirror))
    )
    (fp_text user "${REFERENCE}" (at -0.939 -4.599 90) (layer "B.Fab") hide
        (effects (font (size 0.7 0.7) (thickness 0.15)) (justify left bottom mirror))
    )
    (fp_rect (start -0.925 0.47) (end 0.925 -0.47)
      (stroke (width 0.05) (type default)) (fill none) (layer "B.CrtYd"))
    (fp_line (start -0.494 -0.248) (end -0.494 0.25)
      (stroke (width 0.15) (type solid)) (layer "B.Fab"))
    (fp_line (start -0.494 0.25) (end 0.504 0.25)
      (stroke (width 0.15) (type solid)) (layer "B.Fab"))
    (fp_line (start 0.504 -0.248) (end -0.494 -0.248)
      (stroke (width 0.15) (type solid)) (layer "B.Fab"))
    (fp_line (start 0.504 0.25) (end 0.504 -0.248)
      (stroke (width 0.15) (type solid)) (layer "B.Fab"))
    (pad "1" smd roundrect (at -0.48 0 270) (size 0.59 0.64) (layers "B.Cu" "B.Paste" "B.Mask") (roundrect_rratio 0.25)
      (net 1 "GND") (pintype "passive"))
    (pad "2" smd roundrect (at 0.48 0 270) (size 0.59 0.64) (layers "B.Cu" "B.Paste" "B.Mask") (roundrect_rratio 0.25)
      (net 19 "PP_HV") (pintype "passive"))
  )

  (footprint "antmicro-footprints:C_0402_1005Metric" (layer "B.Cu")
    (at 136.275 80.35 -90)
    (descr "Capacitor SMD 0402")
    (tags "capacitor SMD 0402")
    (property "Author" "Antmicro")
    (property "Dielectric" "")
    (property "License" "Apache-2.0")
    (property "MPN" "C1005X6S1A105K050BC")
    (property "Manufacturer" "TDK")
    (property "Sheetfile" "tb-power.kicad_sch")
    (property "Sheetname" "Thunderbolt Controller - Power")
    (property "Val" "1u")
    (property "Voltage" "")
    (property "ki_description" "SMD Multilayer Ceramic Capacitor, 1 µF, 10 V, 0402 [1005 Metric], ± 10%, X6S, C")
    (property "ki_keywords" "0402, SMT, CAPACITOR, PASSIVE, CERAMIC, MLCC")
    (attr smd)
    (fp_text reference "C66" (at 6.518 -16.887 90) (layer "B.SilkS")
        (effects (font (size 0.7 0.7) (thickness 0.15)) (justify left bottom mirror))
    )
    (fp_text value "C_1u_0402" (at -1.022927 -2.155213 90) (layer "B.Fab")
        (effects (font (size 0.7 0.7) (thickness 0.15)) (justify left bottom mirror))
    )
    (fp_text user "License: Apache-2.0" (at -0.939 -5.799 90) (layer "B.Fab") hide
        (effects (font (size 0.7 0.7) (thickness 0.15)) (justify left bottom mirror))
    )
    (fp_text user "${REFERENCE}" (at -0.939 -4.599 90) (layer "B.Fab") hide
        (effects (font (size 0.7 0.7) (thickness 0.15)) (justify left bottom mirror))
    )
    (fp_text user "Author: Antmicro" (at -0.939 -3.399 90) (layer "B.Fab") hide
        (effects (font (size 0.7 0.7) (thickness 0.15)) (justify left bottom mirror))
    )
    (fp_rect (start -0.925 0.47) (end 0.925 -0.47)
      (stroke (width 0.05) (type default)) (fill none) (layer "B.CrtYd"))
    (fp_line (start -0.494 -0.248) (end -0.494 0.25)
      (stroke (width 0.15) (type solid)) (layer "B.Fab"))
    (fp_line (start -0.494 0.25) (end 0.504 0.25)
      (stroke (width 0.15) (type solid)) (layer "B.Fab"))
    (fp_line (start 0.504 -0.248) (end -0.494 -0.248)
      (stroke (width 0.15) (type solid)) (layer "B.Fab"))
    (fp_line (start 0.504 0.25) (end 0.504 -0.248)
      (stroke (width 0.15) (type solid)) (layer "B.Fab"))
    (pad "1" smd roundrect (at -0.48 0 270) (size 0.59 0.64) (layers "B.Cu" "B.Paste" "B.Mask") (roundrect_rratio 0.25)
      (net 1 "GND") (pintype "passive"))
    (pad "2" smd roundrect (at 0.48 0 270) (size 0.59 0.64) (layers "B.Cu" "B.Paste" "B.Mask") (roundrect_rratio 0.25)
      (net 109 "Net-(U4A-VCC3P3_ANA_PCIE)") (pintype "passive"))
  )

  (footprint "antmicro-footprints:R_0402_1005Metric" (layer "B.Cu")
    (at 114.430001 63.675 90)
    (descr "Resistor SMD 0402")
    (tags "resistor SMD 0402")
    (property "Author" "Antmicro")
    (property "License" "Apache-2.0")
    (property "MPN" "CR0402-FX-1002GLF")
    (property "Manufacturer" "Bourns")
    (property "Sheetfile" "power.kicad_sch")
    (property "Sheetname" "Power")
    (property "Tolerance" "1%")
    (property "Val" "10k")
    (property "ki_description" "SMD Chip Resistor, 10 kohm, ± 1%, 62.5 mW, 0402 [1005 Metric], Thick Film, General Purpose")
    (property "ki_keywords" "0402, SMT, RESISTOR, PASSIVE")
    (attr smd)
    (fp_text reference "R6" (at -0.435 -0.580001 90) (layer "B.SilkS")
        (effects (font (size 0.7 0.7) (thickness 0.15)) (justify right bottom mirror))
    )
    (fp_text value "R_10k_0402" (at -1.011843 -1.772047 90) (layer "B.Fab")
        (effects (font (size 0.7 0.7) (thickness 0.15)) (justify right bottom mirror))
    )
    (fp_text user "License: Apache-2.0" (at -0.95 -5.169 90) (layer "B.Fab") hide
        (effects (font (size 0.7 0.7) (thickness 0.15)) (justify right bottom mirror))
    )
    (fp_text user "${REFERENCE}" (at -0.95 -3.168 90) (layer "B.Fab") hide
        (effects (font (size 0.7 0.7) (thickness 0.15)) (justify right bottom mirror))
    )
    (fp_text user "Author: Antmicro" (at -0.95 -4.169 90) (layer "B.Fab") hide
        (effects (font (size 0.7 0.7) (thickness 0.15)) (justify right bottom mirror))
    )
    (fp_rect (start -0.925 0.47) (end 0.925 -0.47)
      (stroke (width 0.05) (type default)) (fill none) (layer "B.CrtYd"))
    (fp_rect (start -0.5 0.25) (end 0.5 -0.25)
      (stroke (width 0.15) (type solid)) (fill none) (layer "B.Fab"))
    (pad "1" smd roundrect (at -0.48 0 90) (size 0.59 0.64) (layers "B.Cu" "B.Paste" "B.Mask") (roundrect_rratio 0.25)
      (net 90 "Net-(U2-VIN)") (pintype "passive"))
    (pad "2" smd roundrect (at 0.48 0 90) (size 0.59 0.64) (layers "B.Cu" "B.Paste" "B.Mask") (roundrect_rratio 0.25)
      (net 119 "Net-(D1-C)") (pintype "passive"))
  )

  (footprint "antmicro-footprints:R_0402_1005Metric" (layer "B.Cu")
    (at 142.35 66.82 90)
    (descr "Resistor SMD 0402")
    (tags "resistor SMD 0402")
    (property "Author" "Antmicro")
    (property "License" "Apache-2.0")
    (property "MPN" "CR0402-FX-1003GLF")
    (property "Manufacturer" "Bourns")
    (property "Sheetfile" "tb.kicad_sch")
    (property "Sheetname" "TB Controller")
    (property "Tolerance" "1%")
    (property "Val" "100k")
    (property "ki_description" "SMD Chip Resistor, 100 kohm, ± 1%, 62.5 mW, 0402 [1005 Metric], Thick Film, General Purpose")
    (property "ki_keywords" "0402, SMT, RESISTOR, PASSIVE")
    (attr smd)
    (fp_text reference "R84" (at 3.066 0.398 270) (layer "B.SilkS")
        (effects (font (size 0.7 0.7) (thickness 0.15)) (justify left bottom mirror))
    )
    (fp_text value "R_100k_0402" (at -1.011843 -1.772047 270) (layer "B.Fab")
        (effects (font (size 0.7 0.7) (thickness 0.15)) (justify left bottom mirror))
    )
    (fp_text user "${REFERENCE}" (at -0.95 -3.168 270) (layer "B.Fab") hide
        (effects (font (size 0.7 0.7) (thickness 0.15)) (justify left bottom mirror))
    )
    (fp_text user "Author: Antmicro" (at -0.95 -4.169 270) (layer "B.Fab") hide
        (effects (font (size 0.7 0.7) (thickness 0.15)) (justify left bottom mirror))
    )
    (fp_text user "License: Apache-2.0" (at -0.95 -5.169 270) (layer "B.Fab") hide
        (effects (font (size 0.7 0.7) (thickness 0.15)) (justify left bottom mirror))
    )
    (fp_rect (start -0.925 0.47) (end 0.925 -0.47)
      (stroke (width 0.05) (type default)) (fill none) (layer "B.CrtYd"))
    (fp_rect (start -0.5 0.25) (end 0.5 -0.25)
      (stroke (width 0.15) (type solid)) (fill none) (layer "B.Fab"))
    (pad "1" smd roundrect (at -0.48 0 90) (size 0.59 0.64) (layers "B.Cu" "B.Paste" "B.Mask") (roundrect_rratio 0.25)
      (net 199 "Net-(U4C-POC_GPIO_2)") (pintype "passive"))
    (pad "2" smd roundrect (at 0.48 0 90) (size 0.59 0.64) (layers "B.Cu" "B.Paste" "B.Mask") (roundrect_rratio 0.25)
      (net 1 "GND") (pintype "passive"))
  )

  (footprint "antmicro-footprints:R_0402_1005Metric" (layer "B.Cu")
    (at 106.955 82.660001)
    (descr "Resistor SMD 0402")
    (tags "resistor SMD 0402")
    (property "Author" "Antmicro")
    (property "License" "Apache-2.0")
    (property "MPN" "CR0402-FX-1002GLF")
    (property "Manufacturer" "Bourns")
    (property "Sheetfile" "power.kicad_sch")
    (property "Sheetname" "Power")
    (property "Tolerance" "1%")
    (property "Val" "10k")
    (property "ki_description" "SMD Chip Resistor, 10 kohm, ± 1%, 62.5 mW, 0402 [1005 Metric], Thick Film, General Purpose")
    (property "ki_keywords" "0402, SMT, RESISTOR, PASSIVE")
    (attr smd)
    (fp_text reference "R8" (at -0.91 0.397999 180) (layer "B.SilkS")
        (effects (font (size 0.7 0.7) (thickness 0.15)) (justify left bottom mirror))
    )
    (fp_text value "R_10k_0402" (at -1.011843 -1.772047 180) (layer "B.Fab")
        (effects (font (size 0.7 0.7) (thickness 0.15)) (justify left bottom mirror))
    )
    (fp_text user "${REFERENCE}" (at -0.95 -3.168 180) (layer "B.Fab") hide
        (effects (font (size 0.7 0.7) (thickness 0.15)) (justify left bottom mirror))
    )
    (fp_text user "License: Apache-2.0" (at -0.95 -5.169 180) (layer "B.Fab") hide
        (effects (font (size 0.7 0.7) (thickness 0.15)) (justify left bottom mirror))
    )
    (fp_text user "Author: Antmicro" (at -0.95 -4.169 180) (layer "B.Fab") hide
        (effects (font (size 0.7 0.7) (thickness 0.15)) (justify left bottom mirror))
    )
    (fp_rect (start -0.925 0.47) (end 0.925 -0.47)
      (stroke (width 0.05) (type default)) (fill none) (layer "B.CrtYd"))
    (fp_rect (start -0.5 0.25) (end 0.5 -0.25)
      (stroke (width 0.15) (type solid)) (fill none) (layer "B.Fab"))
    (pad "1" smd roundrect (at -0.48 0) (size 0.59 0.64) (layers "B.Cu" "B.Paste" "B.Mask") (roundrect_rratio 0.25)
      (net 1 "GND") (pintype "passive"))
    (pad "2" smd roundrect (at 0.48 0) (size 0.59 0.64) (layers "B.Cu" "B.Paste" "B.Mask") (roundrect_rratio 0.25)
      (net 88 "/Power/DCDC_EN") (pintype "passive"))
  )

  (footprint "antmicro-footprints:R_0402_1005Metric" (layer "B.Cu")
    (at 116.910001 62.205 180)
    (descr "Resistor SMD 0402")
    (tags "resistor SMD 0402")
    (property "Author" "Antmicro")
    (property "License" "Apache-2.0")
    (property "MPN" "CR0402-FX-8871GLF")
    (property "Manufacturer" "Bourns")
    (property "Sheetfile" "power.kicad_sch")
    (property "Sheetname" "Power")
    (property "Tolerance" "1%")
    (property "Val" "8k87")
    (property "ki_description" "SMD Chip Resistor, 8.87 kohm, ± 1%, 100 mW, 0402 [1005 Metric], Thick Film, Precision")
    (property "ki_keywords" "0402, SMT, RESISTOR, PASSIVE")
    (attr smd)
    (fp_text reference "R37" (at -3.104999 -0.406) (layer "B.SilkS")
        (effects (font (size 0.7 0.7) (thickness 0.15)) (justify left bottom mirror))
    )
    (fp_text value "R_8k87_0402" (at -1.011843 -1.772047) (layer "B.Fab")
        (effects (font (size 0.7 0.7) (thickness 0.15)) (justify left bottom mirror))
    )
    (fp_text user "License: Apache-2.0" (at -0.95 -5.169) (layer "B.Fab") hide
        (effects (font (size 0.7 0.7) (thickness 0.15)) (justify left bottom mirror))
    )
    (fp_text user "Author: Antmicro" (at -0.95 -4.169) (layer "B.Fab") hide
        (effects (font (size 0.7 0.7) (thickness 0.15)) (justify left bottom mirror))
    )
    (fp_text user "${REFERENCE}" (at -0.95 -3.168) (layer "B.Fab") hide
        (effects (font (size 0.7 0.7) (thickness 0.15)) (justify left bottom mirror))
    )
    (fp_rect (start -0.925 0.47) (end 0.925 -0.47)
      (stroke (width 0.05) (type default)) (fill none) (layer "B.CrtYd"))
    (fp_rect (start -0.5 0.25) (end 0.5 -0.25)
      (stroke (width 0.15) (type solid)) (fill none) (layer "B.Fab"))
    (pad "1" smd roundrect (at -0.48 0 180) (size 0.59 0.64) (layers "B.Cu" "B.Paste" "B.Mask") (roundrect_rratio 0.25)
      (net 1 "GND") (pintype "passive"))
    (pad "2" smd roundrect (at 0.48 0 180) (size 0.59 0.64) (layers "B.Cu" "B.Paste" "B.Mask") (roundrect_rratio 0.25)
      (net 99 "Net-(U2-FB)") (pintype "passive"))
  )

  (footprint "antmicro-footprints:C_0402_1005Metric" (layer "B.Cu")
    (at 139.38 61.03 90)
    (descr "Capacitor SMD 0402")
    (tags "capacitor SMD 0402")
    (property "Author" "Antmicro")
    (property "Dielectric" "X5R")
    (property "License" "Apache-2.0")
    (property "MPN" "GRM155R61H104KE14D")
    (property "Manufacturer" "Murata")
    (property "Sheetfile" "tb.kicad_sch")
    (property "Sheetname" "TB Controller")
    (property "Val" "100n")
    (property "Voltage" "50V")
    (property "ki_description" "SMD Multilayer Ceramic Capacitor, 0.1 µF, 50 V, 0402 [1005 Metric], ± 10%, X5R, GRM Series")
    (property "ki_keywords" "0402, SMT, CAPACITOR, PASSIVE, CERAMIC, MLCC")
    (attr smd)
    (fp_text reference "C98" (at 1.086 -0.569 270) (layer "B.SilkS")
        (effects (font (size 0.7 0.7) (thickness 0.15)) (justify left bottom mirror))
    )
    (fp_text value "C_100n_0402" (at -1.022927 -2.155213 270) (layer "B.Fab")
        (effects (font (size 0.7 0.7) (thickness 0.15)) (justify left bottom mirror))
    )
    (fp_text user "License: Apache-2.0" (at -0.939 -5.799 270) (layer "B.Fab") hide
        (effects (font (size 0.7 0.7) (thickness 0.15)) (justify left bottom mirror))
    )
    (fp_text user "Author: Antmicro" (at -0.939 -3.399 270) (layer "B.Fab") hide
        (effects (font (size 0.7 0.7) (thickness 0.15)) (justify left bottom mirror))
    )
    (fp_text user "${REFERENCE}" (at -0.939 -4.599 270) (layer "B.Fab") hide
        (effects (font (size 0.7 0.7) (thickness 0.15)) (justify left bottom mirror))
    )
    (fp_rect (start -0.925 0.47) (end 0.925 -0.47)
      (stroke (width 0.05) (type default)) (fill none) (layer "B.CrtYd"))
    (fp_line (start -0.494 -0.248) (end -0.494 0.25)
      (stroke (width 0.15) (type solid)) (layer "B.Fab"))
    (fp_line (start -0.494 0.25) (end 0.504 0.25)
      (stroke (width 0.15) (type solid)) (layer "B.Fab"))
    (fp_line (start 0.504 -0.248) (end -0.494 -0.248)
      (stroke (width 0.15) (type solid)) (layer "B.Fab"))
    (fp_line (start 0.504 0.25) (end 0.504 -0.248)
      (stroke (width 0.15) (type solid)) (layer "B.Fab"))
    (pad "1" smd roundrect (at -0.48 0 90) (size 0.59 0.64) (layers "B.Cu" "B.Paste" "B.Mask") (roundrect_rratio 0.25)
      (net 1 "GND") (pintype "passive"))
    (pad "2" smd roundrect (at 0.48 0 90) (size 0.59 0.64) (layers "B.Cu" "B.Paste" "B.Mask") (roundrect_rratio 0.25)
      (net 2 "3V3_SYS") (pintype "passive"))
  )

  (footprint "antmicro-footprints:C_0402_1005Metric" (layer "B.Cu")
    (at 117.450001 64.675 -90)
    (descr "Capacitor SMD 0402")
    (tags "capacitor SMD 0402")
    (property "Author" "Antmicro")
    (property "Dielectric" "")
    (property "License" "Apache-2.0")
    (property "MPN" "CC0402KRX5R6BB224")
    (property "Manufacturer" "YAGEO")
    (property "Sheetfile" "power.kicad_sch")
    (property "Sheetname" "Power")
    (property "Val" "220n")
    (property "Voltage" "")
    (property "ki_description" "SMD Multilayer Ceramic Capacitor, 0.22 µF, 10 V, 0402 [1005 Metric], ± 10%, X5R, CC Series")
    (property "ki_keywords" "0402, SMT, CAPACITOR, PASSIVE, MLCC, CERAMIC")
    (attr smd)
    (fp_text reference "C27" (at 0.984 -0.405999 90) (layer "B.SilkS")
        (effects (font (size 0.7 0.7) (thickness 0.15)) (justify left bottom mirror))
    )
    (fp_text value "C_220n_0402" (at -1.022927 -2.155213 90) (layer "B.Fab")
        (effects (font (size 0.7 0.7) (thickness 0.15)) (justify left bottom mirror))
    )
    (fp_text user "Author: Antmicro" (at -0.939 -3.399 90) (layer "B.Fab") hide
        (effects (font (size 0.7 0.7) (thickness 0.15)) (justify left bottom mirror))
    )
    (fp_text user "${REFERENCE}" (at -0.939 -4.599 90) (layer "B.Fab") hide
        (effects (font (size 0.7 0.7) (thickness 0.15)) (justify left bottom mirror))
    )
    (fp_text user "License: Apache-2.0" (at -0.939 -5.799 90) (layer "B.Fab") hide
        (effects (font (size 0.7 0.7) (thickness 0.15)) (justify left bottom mirror))
    )
    (fp_rect (start -0.925 0.47) (end 0.925 -0.47)
      (stroke (width 0.05) (type default)) (fill none) (layer "B.CrtYd"))
    (fp_line (start -0.494 -0.248) (end -0.494 0.25)
      (stroke (width 0.15) (type solid)) (layer "B.Fab"))
    (fp_line (start -0.494 0.25) (end 0.504 0.25)
      (stroke (width 0.15) (type solid)) (layer "B.Fab"))
    (fp_line (start 0.504 -0.248) (end -0.494 -0.248)
      (stroke (width 0.15) (type solid)) (layer "B.Fab"))
    (fp_line (start 0.504 0.25) (end 0.504 -0.248)
      (stroke (width 0.15) (type solid)) (layer "B.Fab"))
    (pad "1" smd roundrect (at -0.48 0 270) (size 0.59 0.64) (layers "B.Cu" "B.Paste" "B.Mask") (roundrect_rratio 0.25)
      (net 94 "Net-(U2-BST)") (pintype "passive"))
    (pad "2" smd roundrect (at 0.48 0 270) (size 0.59 0.64) (layers "B.Cu" "B.Paste" "B.Mask") (roundrect_rratio 0.25)
      (net 95 "Net-(U2-SW)") (pintype "passive"))
  )

  (footprint "antmicro-footprints:R_0603_1608Metric" (layer "B.Cu")
    (at 113.7175 91.1675 -90)
    (descr "Resistor SMD 0603")
    (tags "resistor SMD 0603")
    (property "Author" "Antmicro")
    (property "License" "Apache-2.0")
    (property "MPN" "PMR03EZPJ000")
    (property "Manufacturer" "ROHM Semiconductor")
    (property "Max. Curr." "22.4A")
    (property "Sheetfile" "power.kicad_sch")
    (property "Sheetname" "Power")
    (property "Tolerance" "template_tolerance")
    (property "Val" "0R")
    (property "ki_description" "SMD Chip Resistor")
    (property "ki_keywords" "0603, SMT, RESISTOR, PASSIVE")
    (attr smd)
    (fp_text reference "R99" (at -4.1725 -1.9795 90) (layer "B.SilkS")
        (effects (font (size 0.7 0.7) (thickness 0.15)) (justify left bottom mirror))
    )
    (fp_text value "R_0R_22.4A_0603" (at 0 -1.6 90) (layer "B.Fab")
        (effects (font (size 0.7 0.7) (thickness 0.15)) (justify left bottom mirror))
    )
    (fp_text user "Author: Antmicro" (at -1.25 -4.9 90) (layer "B.Fab") hide
        (effects (font (size 0.7 0.7) (thickness 0.15)) (justify left bottom mirror))
    )
    (fp_text user "${REFERENCE}" (at -1.25 -3.898 90) (layer "B.Fab") hide
        (effects (font (size 0.7 0.7) (thickness 0.15)) (justify left bottom mirror))
    )
    (fp_text user "License: Apache-2.0" (at -1.25 -5.9 90) (layer "B.Fab") hide
        (effects (font (size 0.7 0.7) (thickness 0.15)) (justify left bottom mirror))
    )
    (fp_line (start -0.15 -0.4) (end 0.15 -0.4)
      (stroke (width 0.15) (type solid)) (layer "B.SilkS"))
    (fp_line (start -0.15 0.4) (end 0.15 0.4)
      (stroke (width 0.15) (type solid)) (layer "B.SilkS"))
    (fp_rect (start -1.25 0.65) (end 1.25 -0.65)
      (stroke (width 0.05) (type solid)) (fill none) (layer "B.CrtYd"))
    (fp_rect (start -0.8 0.4) (end 0.8 -0.4)
      (stroke (width 0.15) (type solid)) (fill none) (layer "B.Fab"))
    (pad "1" smd roundrect (at -0.7 0 270) (size 0.8 1) (layers "B.Cu" "B.Paste" "B.Mask") (roundrect_rratio 0.2)
      (net 146 "Net-(Q4-S)") (pintype "passive"))
    (pad "2" smd roundrect (at 0.7 0 270) (size 0.8 1) (layers "B.Cu" "B.Paste" "B.Mask") (roundrect_rratio 0.2)
      (net 8 "12V0_PCIE") (pintype "passive"))
  )

  (footprint "antmicro-footprints:C_0402_1005Metric" (layer "B.Cu")
    (at 115.440001 65.615 90)
    (descr "Capacitor SMD 0402")
    (tags "capacitor SMD 0402")
    (property "Author" "Antmicro")
    (property "Dielectric" "X5R")
    (property "License" "Apache-2.0")
    (property "MPN" "GRM155R61H104KE14D")
    (property "Manufacturer" "Murata")
    (property "Sheetfile" "power.kicad_sch")
    (property "Sheetname" "Power")
    (property "Val" "100n")
    (property "Voltage" "50V")
    (property "ki_description" "SMD Multilayer Ceramic Capacitor, 0.1 µF, 50 V, 0402 [1005 Metric], ± 10%, X5R, GRM Series")
    (property "ki_keywords" "0402, SMT, CAPACITOR, PASSIVE, CERAMIC, MLCC")
    (attr smd)
    (fp_text reference "C24" (at -0.933 0.383999 270) (layer "B.SilkS")
        (effects (font (size 0.7 0.7) (thickness 0.15)) (justify left bottom mirror))
    )
    (fp_text value "C_100n_0402" (at -1.022927 -2.155213 270) (layer "B.Fab")
        (effects (font (size 0.7 0.7) (thickness 0.15)) (justify left bottom mirror))
    )
    (fp_text user "${REFERENCE}" (at -0.939 -4.599 270) (layer "B.Fab") hide
        (effects (font (size 0.7 0.7) (thickness 0.15)) (justify left bottom mirror))
    )
    (fp_text user "License: Apache-2.0" (at -0.939 -5.799 270) (layer "B.Fab") hide
        (effects (font (size 0.7 0.7) (thickness 0.15)) (justify left bottom mirror))
    )
    (fp_text user "Author: Antmicro" (at -0.939 -3.399 270) (layer "B.Fab") hide
        (effects (font (size 0.7 0.7) (thickness 0.15)) (justify left bottom mirror))
    )
    (fp_rect (start -0.925 0.47) (end 0.925 -0.47)
      (stroke (width 0.05) (type default)) (fill none) (layer "B.CrtYd"))
    (fp_line (start -0.494 -0.248) (end -0.494 0.25)
      (stroke (width 0.15) (type solid)) (layer "B.Fab"))
    (fp_line (start -0.494 0.25) (end 0.504 0.25)
      (stroke (width 0.15) (type solid)) (layer "B.Fab"))
    (fp_line (start 0.504 -0.248) (end -0.494 -0.248)
      (stroke (width 0.15) (type solid)) (layer "B.Fab"))
    (fp_line (start 0.504 0.25) (end 0.504 -0.248)
      (stroke (width 0.15) (type solid)) (layer "B.Fab"))
    (pad "1" smd roundrect (at -0.48 0 90) (size 0.59 0.64) (layers "B.Cu" "B.Paste" "B.Mask") (roundrect_rratio 0.25)
      (net 1 "GND") (pintype "passive"))
    (pad "2" smd roundrect (at 0.48 0 90) (size 0.59 0.64) (layers "B.Cu" "B.Paste" "B.Mask") (roundrect_rratio 0.25)
      (net 90 "Net-(U2-VIN)") (pintype "passive"))
  )

  (footprint "antmicro-footprints:R_0402_1005Metric" (layer "B.Cu")
    (at 131.075 68.77 90)
    (descr "Resistor SMD 0402")
    (tags "resistor SMD 0402")
    (property "Author" "Antmicro")
    (property "License" "Apache-2.0")
    (property "MPN" "CR0402-FX-1002GLF")
    (property "Manufacturer" "Bourns")
    (property "Sheetfile" "tb.kicad_sch")
    (property "Sheetname" "TB Controller")
    (property "Tolerance" "1%")
    (property "Val" "10k")
    (property "ki_description" "SMD Chip Resistor, 10 kohm, ± 1%, 62.5 mW, 0402 [1005 Metric], Thick Film, General Purpose")
    (property "ki_keywords" "0402, SMT, RESISTOR, PASSIVE")
    (attr smd)
    (fp_text reference "R80" (at 1.079 -2.678 270) (layer "B.SilkS")
        (effects (font (size 0.7 0.7) (thickness 0.15)) (justify left bottom mirror))
    )
    (fp_text value "R_10k_0402" (at -1.011843 -1.772047 270) (layer "B.Fab")
        (effects (font (size 0.7 0.7) (thickness 0.15)) (justify left bottom mirror))
    )
    (fp_text user "Author: Antmicro" (at -0.95 -4.169 270) (layer "B.Fab") hide
        (effects (font (size 0.7 0.7) (thickness 0.15)) (justify left bottom mirror))
    )
    (fp_text user "${REFERENCE}" (at -0.95 -3.168 270) (layer "B.Fab") hide
        (effects (font (size 0.7 0.7) (thickness 0.15)) (justify left bottom mirror))
    )
    (fp_text user "License: Apache-2.0" (at -0.95 -5.169 270) (layer "B.Fab") hide
        (effects (font (size 0.7 0.7) (thickness 0.15)) (justify left bottom mirror))
    )
    (fp_rect (start -0.925 0.47) (end 0.925 -0.47)
      (stroke (width 0.05) (type default)) (fill none) (layer "B.CrtYd"))
    (fp_rect (start -0.5 0.25) (end 0.5 -0.25)
      (stroke (width 0.15) (type solid)) (fill none) (layer "B.Fab"))
    (pad "1" smd roundrect (at -0.48 0 90) (size 0.59 0.64) (layers "B.Cu" "B.Paste" "B.Mask") (roundrect_rratio 0.25)
      (net 195 "Net-(U4C-GPIO_6)") (pintype "passive"))
    (pad "2" smd roundrect (at 0.48 0 90) (size 0.59 0.64) (layers "B.Cu" "B.Paste" "B.Mask") (roundrect_rratio 0.25)
      (net 1 "GND") (pintype "passive"))
  )

  (footprint "antmicro-footprints:C_0402_1005Metric" (layer "B.Cu")
    (at 161 74.928922)
    (descr "Capacitor SMD 0402")
    (tags "capacitor SMD 0402")
    (property "Author" "Antmicro")
    (property "Dielectric" "X5R")
    (property "License" "Apache-2.0")
    (property "MPN" "GRM155R61H104KE14D")
    (property "Manufacturer" "Murata")
    (property "Sheetfile" "connectors.kicad_sch")
    (property "Sheetname" "Connectors")
    (property "Val" "100n")
    (property "Voltage" "50V")
    (property "ki_description" "SMD Multilayer Ceramic Capacitor, 0.1 µF, 50 V, 0402 [1005 Metric], ± 10%, X5R, GRM Series")
    (property "ki_keywords" "0402, SMT, CAPACITOR, PASSIVE, CERAMIC, MLCC")
    (attr smd)
    (fp_text reference "C2" (at -0.98 0.509078 180) (layer "B.SilkS")
        (effects (font (size 0.7 0.7) (thickness 0.15)) (justify left bottom mirror))
    )
    (fp_text value "C_100n_0402" (at -1.022927 -2.155213 180) (layer "B.Fab")
        (effects (font (size 0.7 0.7) (thickness 0.15)) (justify left bottom mirror))
    )
    (fp_text user "${REFERENCE}" (at -0.939 -4.599 180) (layer "B.Fab") hide
        (effects (font (size 0.7 0.7) (thickness 0.15)) (justify left bottom mirror))
    )
    (fp_text user "Author: Antmicro" (at -0.939 -3.399 180) (layer "B.Fab") hide
        (effects (font (size 0.7 0.7) (thickness 0.15)) (justify left bottom mirror))
    )
    (fp_text user "License: Apache-2.0" (at -0.939 -5.799 180) (layer "B.Fab") hide
        (effects (font (size 0.7 0.7) (thickness 0.15)) (justify left bottom mirror))
    )
    (fp_rect (start -0.925 0.47) (end 0.925 -0.47)
      (stroke (width 0.05) (type default)) (fill none) (layer "B.CrtYd"))
    (fp_line (start -0.494 -0.248) (end -0.494 0.25)
      (stroke (width 0.15) (type solid)) (layer "B.Fab"))
    (fp_line (start -0.494 0.25) (end 0.504 0.25)
      (stroke (width 0.15) (type solid)) (layer "B.Fab"))
    (fp_line (start 0.504 -0.248) (end -0.494 -0.248)
      (stroke (width 0.15) (type solid)) (layer "B.Fab"))
    (fp_line (start 0.504 0.25) (end 0.504 -0.248)
      (stroke (width 0.15) (type solid)) (layer "B.Fab"))
    (pad "1" smd roundrect (at -0.48 0) (size 0.59 0.64) (layers "B.Cu" "B.Paste" "B.Mask") (roundrect_rratio 0.25)
      (net 1 "GND") (pintype "passive"))
    (pad "2" smd roundrect (at 0.48 0) (size 0.59 0.64) (layers "B.Cu" "B.Paste" "B.Mask") (roundrect_rratio 0.25)
      (net 3 "5V0_USB") (pintype "passive"))
  )

  (footprint "antmicro-footprints:R_0402_1005Metric" (layer "B.Cu")
    (at 134.15 66.82 -90)
    (descr "Resistor SMD 0402")
    (tags "resistor SMD 0402")
    (property "Author" "Antmicro")
    (property "License" "Apache-2.0")
    (property "MPN" "CR0402-FX-1002GLF")
    (property "Manufacturer" "Bourns")
    (property "Sheetfile" "tb.kicad_sch")
    (property "Sheetname" "TB Controller")
    (property "Tolerance" "1%")
    (property "Val" "10k")
    (property "ki_description" "SMD Chip Resistor, 10 kohm, ± 1%, 62.5 mW, 0402 [1005 Metric], Thick Film, General Purpose")
    (property "ki_keywords" "0402, SMT, RESISTOR, PASSIVE")
    (attr smd)
    (fp_text reference "R67" (at -3.066 -0.325 90) (layer "B.SilkS")
        (effects (font (size 0.7 0.7) (thickness 0.15)) (justify left bottom mirror))
    )
    (fp_text value "R_10k_0402" (at -1.011843 -1.772047 90) (layer "B.Fab")
        (effects (font (size 0.7 0.7) (thickness 0.15)) (justify left bottom mirror))
    )
    (fp_text user "License: Apache-2.0" (at -0.95 -5.169 90) (layer "B.Fab") hide
        (effects (font (size 0.7 0.7) (thickness 0.15)) (justify left bottom mirror))
    )
    (fp_text user "Author: Antmicro" (at -0.95 -4.169 90) (layer "B.Fab") hide
        (effects (font (size 0.7 0.7) (thickness 0.15)) (justify left bottom mirror))
    )
    (fp_text user "${REFERENCE}" (at -0.95 -3.168 90) (layer "B.Fab") hide
        (effects (font (size 0.7 0.7) (thickness 0.15)) (justify left bottom mirror))
    )
    (fp_rect (start -0.925 0.47) (end 0.925 -0.47)
      (stroke (width 0.05) (type default)) (fill none) (layer "B.CrtYd"))
    (fp_rect (start -0.5 0.25) (end 0.5 -0.25)
      (stroke (width 0.15) (type solid)) (fill none) (layer "B.Fab"))
    (pad "1" smd roundrect (at -0.48 0 270) (size 0.59 0.64) (layers "B.Cu" "B.Paste" "B.Mask") (roundrect_rratio 0.25)
      (net 2 "3V3_SYS") (pintype "passive"))
    (pad "2" smd roundrect (at 0.48 0 270) (size 0.59 0.64) (layers "B.Cu" "B.Paste" "B.Mask") (roundrect_rratio 0.25)
      (net 181 "Net-(U4D-TDO)") (pintype "passive"))
  )

  (footprint "antmicro-footprints:C_0402_1005Metric" (layer "B.Cu")
    (at 127.505 80.34 -90)
    (descr "Capacitor SMD 0402")
    (tags "capacitor SMD 0402")
    (property "Author" "Antmicro")
    (property "Dielectric" "")
    (property "License" "Apache-2.0")
    (property "MPN" "CC0402MRX5R5BB106")
    (property "Manufacturer" "YAGEO")
    (property "Sheetfile" "tb-power.kicad_sch")
    (property "Sheetname" "Thunderbolt Controller - Power")
    (property "Val" "10u")
    (property "Voltage" "")
    (property "ki_description" "SMD Multilayer Ceramic Capacitor, 10 µF, 6.3 V, 0402 [1005 Metric], ± 20%, X5R, CC Series")
    (property "ki_keywords" "0402, SMT, CAPACITOR, PASSIVE, MLCC, CERAMIC")
    (attr smd)
    (fp_text reference "C96" (at -0.965 2.537 90) (layer "B.SilkS")
        (effects (font (size 0.7 0.7) (thickness 0.15)) (justify left bottom mirror))
    )
    (fp_text value "C_10u_0402" (at -1.022927 -2.155213 90) (layer "B.Fab")
        (effects (font (size 0.7 0.7) (thickness 0.15)) (justify left bottom mirror))
    )
    (fp_text user "${REFERENCE}" (at -0.939 -4.599 90) (layer "B.Fab") hide
        (effects (font (size 0.7 0.7) (thickness 0.15)) (justify left bottom mirror))
    )
    (fp_text user "License: Apache-2.0" (at -0.939 -5.799 90) (layer "B.Fab") hide
        (effects (font (size 0.7 0.7) (thickness 0.15)) (justify left bottom mirror))
    )
    (fp_text user "Author: Antmicro" (at -0.939 -3.399 90) (layer "B.Fab") hide
        (effects (font (size 0.7 0.7) (thickness 0.15)) (justify left bottom mirror))
    )
    (fp_rect (start -0.925 0.47) (end 0.925 -0.47)
      (stroke (width 0.05) (type default)) (fill none) (layer "B.CrtYd"))
    (fp_line (start -0.494 -0.248) (end -0.494 0.25)
      (stroke (width 0.15) (type solid)) (layer "B.Fab"))
    (fp_line (start -0.494 0.25) (end 0.504 0.25)
      (stroke (width 0.15) (type solid)) (layer "B.Fab"))
    (fp_line (start 0.504 -0.248) (end -0.494 -0.248)
      (stroke (width 0.15) (type solid)) (layer "B.Fab"))
    (fp_line (start 0.504 0.25) (end 0.504 -0.248)
      (stroke (width 0.15) (type solid)) (layer "B.Fab"))
    (pad "1" smd roundrect (at -0.48 0 270) (size 0.59 0.64) (layers "B.Cu" "B.Paste" "B.Mask") (roundrect_rratio 0.25)
      (net 1 "GND") (pintype "passive"))
    (pad "2" smd roundrect (at 0.48 0 270) (size 0.59 0.64) (layers "B.Cu" "B.Paste" "B.Mask") (roundrect_rratio 0.25)
      (net 114 "Net-(U4A-VCC3P3_S0)") (pintype "passive"))
  )

  (footprint "antmicro-footprints:R_0402_1005Metric" (layer "B.Cu")
    (at 156.89 57.39 -90)
    (descr "Resistor SMD 0402")
    (tags "resistor SMD 0402")
    (property "Author" "Antmicro")
    (property "License" "Apache-2.0")
    (property "MPN" "CR0402-FX-3301GLF")
    (property "Manufacturer" "Bourns")
    (property "Sheetfile" "power.kicad_sch")
    (property "Sheetname" "Power")
    (property "Tolerance" "1%")
    (property "Val" "3k3")
    (property "ki_description" "SMD Chip Resistor, 3.3 kohm, ± 1%, 63 mW, 0402 [1005 Metric], Thick Film, General Purpose")
    (property "ki_keywords" "0402, SMT, RESISTOR, PASSIVE")
    (attr smd)
    (fp_text reference "R14" (at -3.034 -0.479 90) (layer "B.SilkS")
        (effects (font (size 0.7 0.7) (thickness 0.15)) (justify left bottom mirror))
    )
    (fp_text value "R_3k3_0402" (at -1.011843 -1.772047 90) (layer "B.Fab")
        (effects (font (size 0.7 0.7) (thickness 0.15)) (justify left bottom mirror))
    )
    (fp_text user "License: Apache-2.0" (at -0.95 -5.169 90) (layer "B.Fab") hide
        (effects (font (size 0.7 0.7) (thickness 0.15)) (justify left bottom mirror))
    )
    (fp_text user "${REFERENCE}" (at -0.95 -3.168 90) (layer "B.Fab") hide
        (effects (font (size 0.7 0.7) (thickness 0.15)) (justify left bottom mirror))
    )
    (fp_text user "Author: Antmicro" (at -0.95 -4.169 90) (layer "B.Fab") hide
        (effects (font (size 0.7 0.7) (thickness 0.15)) (justify left bottom mirror))
    )
    (fp_rect (start -0.925 0.47) (end 0.925 -0.47)
      (stroke (width 0.05) (type default)) (fill none) (layer "B.CrtYd"))
    (fp_rect (start -0.5 0.25) (end 0.5 -0.25)
      (stroke (width 0.15) (type solid)) (fill none) (layer "B.Fab"))
    (pad "1" smd roundrect (at -0.48 0 270) (size 0.59 0.64) (layers "B.Cu" "B.Paste" "B.Mask") (roundrect_rratio 0.25)
      (net 9 "/Power/TPS_3V3") (pintype "passive"))
    (pad "2" smd roundrect (at 0.48 0 270) (size 0.59 0.64) (layers "B.Cu" "B.Paste" "B.Mask") (roundrect_rratio 0.25)
      (net 149 "Net-(U3-I2C_SDA2)") (pintype "passive"))
  )

  (footprint "antmicro-footprints:R_0402_1005Metric" (layer "B.Cu")
    (at 156.91 59.47 90)
    (descr "Resistor SMD 0402")
    (tags "resistor SMD 0402")
    (property "Author" "Antmicro")
    (property "License" "Apache-2.0")
    (property "MPN" "CR0402-FX-1003GLF")
    (property "Manufacturer" "Bourns")
    (property "Sheetfile" "power.kicad_sch")
    (property "Sheetname" "Power")
    (property "Tolerance" "1%")
    (property "Val" "100k")
    (property "ki_description" "SMD Chip Resistor, 100 kohm, ± 1%, 62.5 mW, 0402 [1005 Metric], Thick Film, General Purpose")
    (property "ki_keywords" "0402, SMT, RESISTOR, PASSIVE")
    (attr smd)
    (fp_text reference "R33" (at 4.86 -5.526 270) (layer "B.SilkS")
        (effects (font (size 0.7 0.7) (thickness 0.15)) (justify left bottom mirror))
    )
    (fp_text value "R_100k_0402" (at -1.011843 -1.772047 270) (layer "B.Fab")
        (effects (font (size 0.7 0.7) (thickness 0.15)) (justify left bottom mirror))
    )
    (fp_text user "License: Apache-2.0" (at -0.95 -5.169 270) (layer "B.Fab") hide
        (effects (font (size 0.7 0.7) (thickness 0.15)) (justify left bottom mirror))
    )
    (fp_text user "${REFERENCE}" (at -0.95 -3.168 270) (layer "B.Fab") hide
        (effects (font (size 0.7 0.7) (thickness 0.15)) (justify left bottom mirror))
    )
    (fp_text user "Author: Antmicro" (at -0.95 -4.169 270) (layer "B.Fab") hide
        (effects (font (size 0.7 0.7) (thickness 0.15)) (justify left bottom mirror))
    )
    (fp_rect (start -0.925 0.47) (end 0.925 -0.47)
      (stroke (width 0.05) (type default)) (fill none) (layer "B.CrtYd"))
    (fp_rect (start -0.5 0.25) (end 0.5 -0.25)
      (stroke (width 0.15) (type solid)) (fill none) (layer "B.Fab"))
    (pad "1" smd roundrect (at -0.48 0 90) (size 0.59 0.64) (layers "B.Cu" "B.Paste" "B.Mask") (roundrect_rratio 0.25)
      (net 166 "Net-(U3-HRESET)") (pintype "passive"))
    (pad "2" smd roundrect (at 0.48 0 90) (size 0.59 0.64) (layers "B.Cu" "B.Paste" "B.Mask") (roundrect_rratio 0.25)
      (net 1 "GND") (pintype "passive"))
  )

  (footprint "antmicro-footprints:C_0402_1005Metric" (layer "B.Cu")
    (at 155.085 77.42 180)
    (descr "Capacitor SMD 0402")
    (tags "capacitor SMD 0402")
    (property "Author" "Antmicro")
    (property "Dielectric" "")
    (property "License" "Apache-2.0")
    (property "MPN" "CC0402KRX5R6BB224")
    (property "Manufacturer" "YAGEO")
    (property "Sheetfile" "tb.kicad_sch")
    (property "Sheetname" "TB Controller")
    (property "Val" "220n")
    (property "Voltage" "")
    (property "ki_description" "SMD Multilayer Ceramic Capacitor, 0.22 µF, 10 V, 0402 [1005 Metric], ± 10%, X5R, CC Series")
    (property "ki_keywords" "0402, SMT, CAPACITOR, PASSIVE, MLCC, CERAMIC")
    (attr smd)
    (fp_text reference "C100" (at 1.034 -0.431) (layer "B.SilkS")
        (effects (font (size 0.7 0.7) (thickness 0.15)) (justify left bottom mirror))
    )
    (fp_text value "C_220n_0402" (at -1.022927 -2.155213) (layer "B.Fab")
        (effects (font (size 0.7 0.7) (thickness 0.15)) (justify left bottom mirror))
    )
    (fp_text user "Author: Antmicro" (at -0.939 -3.399) (layer "B.Fab") hide
        (effects (font (size 0.7 0.7) (thickness 0.15)) (justify left bottom mirror))
    )
    (fp_text user "${REFERENCE}" (at -0.939 -4.599) (layer "B.Fab") hide
        (effects (font (size 0.7 0.7) (thickness 0.15)) (justify left bottom mirror))
    )
    (fp_text user "License: Apache-2.0" (at -0.939 -5.799) (layer "B.Fab") hide
        (effects (font (size 0.7 0.7) (thickness 0.15)) (justify left bottom mirror))
    )
    (fp_rect (start -0.925 0.47) (end 0.925 -0.47)
      (stroke (width 0.05) (type default)) (fill none) (layer "B.CrtYd"))
    (fp_line (start -0.494 -0.248) (end -0.494 0.25)
      (stroke (width 0.15) (type solid)) (layer "B.Fab"))
    (fp_line (start -0.494 0.25) (end 0.504 0.25)
      (stroke (width 0.15) (type solid)) (layer "B.Fab"))
    (fp_line (start 0.504 -0.248) (end -0.494 -0.248)
      (stroke (width 0.15) (type solid)) (layer "B.Fab"))
    (fp_line (start 0.504 0.25) (end 0.504 -0.248)
      (stroke (width 0.15) (type solid)) (layer "B.Fab"))
    (pad "1" smd roundrect (at -0.48 0 180) (size 0.59 0.64) (layers "B.Cu" "B.Paste" "B.Mask") (roundrect_rratio 0.25)
      (net 14 "TB_TX1_P") (pintype "passive"))
    (pad "2" smd roundrect (at 0.48 0 180) (size 0.59 0.64) (layers "B.Cu" "B.Paste" "B.Mask") (roundrect_rratio 0.25)
      (net 15 "/TB Controller/PA_TX1_P") (pintype "passive"))
  )

  (footprint "antmicro-footprints:R_0402_1005Metric" (layer "B.Cu")
    (at 130.05 68.77 90)
    (descr "Resistor SMD 0402")
    (tags "resistor SMD 0402")
    (property "Author" "Antmicro")
    (property "License" "Apache-2.0")
    (property "MPN" "CR0402-FX-1004GLF")
    (property "Manufacturer" "Bourns")
    (property "Sheetfile" "tb.kicad_sch")
    (property "Sheetname" "TB Controller")
    (property "Tolerance" "1%")
    (property "Val" "1M")
    (property "ki_description" "SMD Chip Resistor, 1 Mohm, ± 1%, 62.5 mW, 0402 [1005 Metric], Thick Film, General Purpose")
    (property "ki_keywords" "0402, SMT, RESISTOR, PASSIVE")
    (attr smd)
    (fp_text reference "R82" (at 1.079 -2.678 270) (layer "B.SilkS")
        (effects (font (size 0.7 0.7) (thickness 0.15)) (justify left bottom mirror))
    )
    (fp_text value "R_1M_0402" (at -1.011843 -1.772047 270) (layer "B.Fab")
        (effects (font (size 0.7 0.7) (thickness 0.15)) (justify left bottom mirror))
    )
    (fp_text user "License: Apache-2.0" (at -0.95 -5.169 270) (layer "B.Fab") hide
        (effects (font (size 0.7 0.7) (thickness 0.15)) (justify left bottom mirror))
    )
    (fp_text user "${REFERENCE}" (at -0.95 -3.168 270) (layer "B.Fab") hide
        (effects (font (size 0.7 0.7) (thickness 0.15)) (justify left bottom mirror))
    )
    (fp_text user "Author: Antmicro" (at -0.95 -4.169 270) (layer "B.Fab") hide
        (effects (font (size 0.7 0.7) (thickness 0.15)) (justify left bottom mirror))
    )
    (fp_rect (start -0.925 0.47) (end 0.925 -0.47)
      (stroke (width 0.05) (type default)) (fill none) (layer "B.CrtYd"))
    (fp_rect (start -0.5 0.25) (end 0.5 -0.25)
      (stroke (width 0.15) (type solid)) (fill none) (layer "B.Fab"))
    (pad "1" smd roundrect (at -0.48 0 90) (size 0.59 0.64) (layers "B.Cu" "B.Paste" "B.Mask") (roundrect_rratio 0.25)
      (net 197 "Net-(U4C-GPIO_8)") (pintype "passive"))
    (pad "2" smd roundrect (at 0.48 0 90) (size 0.59 0.64) (layers "B.Cu" "B.Paste" "B.Mask") (roundrect_rratio 0.25)
      (net 1 "GND") (pintype "passive"))
  )

  (footprint "antmicro-footprints:R_0402_1005Metric" (layer "B.Cu")
    (at 155.89 57.39 -90)
    (descr "Resistor SMD 0402")
    (tags "resistor SMD 0402")
    (property "Author" "Antmicro")
    (property "License" "Apache-2.0")
    (property "MPN" "CR0402-FX-3301GLF")
    (property "Manufacturer" "Bourns")
    (property "Sheetfile" "power.kicad_sch")
    (property "Sheetname" "Power")
    (property "Tolerance" "1%")
    (property "Val" "3k3")
    (property "ki_description" "SMD Chip Resistor, 3.3 kohm, ± 1%, 63 mW, 0402 [1005 Metric], Thick Film, General Purpose")
    (property "ki_keywords" "0402, SMT, RESISTOR, PASSIVE")
    (attr smd)
    (fp_text reference "R15" (at -3.034 -0.479 90) (layer "B.SilkS")
        (effects (font (size 0.7 0.7) (thickness 0.15)) (justify left bottom mirror))
    )
    (fp_text value "R_3k3_0402" (at -1.011843 -1.772047 90) (layer "B.Fab")
        (effects (font (size 0.7 0.7) (thickness 0.15)) (justify left bottom mirror))
    )
    (fp_text user "Author: Antmicro" (at -0.95 -4.169 90) (layer "B.Fab") hide
        (effects (font (size 0.7 0.7) (thickness 0.15)) (justify left bottom mirror))
    )
    (fp_text user "${REFERENCE}" (at -0.95 -3.168 90) (layer "B.Fab") hide
        (effects (font (size 0.7 0.7) (thickness 0.15)) (justify left bottom mirror))
    )
    (fp_text user "License: Apache-2.0" (at -0.95 -5.169 90) (layer "B.Fab") hide
        (effects (font (size 0.7 0.7) (thickness 0.15)) (justify left bottom mirror))
    )
    (fp_rect (start -0.925 0.47) (end 0.925 -0.47)
      (stroke (width 0.05) (type default)) (fill none) (layer "B.CrtYd"))
    (fp_rect (start -0.5 0.25) (end 0.5 -0.25)
      (stroke (width 0.15) (type solid)) (fill none) (layer "B.Fab"))
    (pad "1" smd roundrect (at -0.48 0 270) (size 0.59 0.64) (layers "B.Cu" "B.Paste" "B.Mask") (roundrect_rratio 0.25)
      (net 9 "/Power/TPS_3V3") (pintype "passive"))
    (pad "2" smd roundrect (at 0.48 0 270) (size 0.59 0.64) (layers "B.Cu" "B.Paste" "B.Mask") (roundrect_rratio 0.25)
      (net 150 "Net-(U3-I2C_SCL2)") (pintype "passive"))
  )

  (footprint "antmicro-footprints:C_0402_1005Metric" (layer "B.Cu")
    (at 153.41 64.96 180)
    (descr "Capacitor SMD 0402")
    (tags "capacitor SMD 0402")
    (property "Author" "Antmicro")
    (property "Dielectric" "")
    (property "License" "Apache-2.0")
    (property "MPN" "C1005X5R1A225K050BC")
    (property "Manufacturer" "TDK")
    (property "Sheetfile" "power.kicad_sch")
    (property "Sheetname" "Power")
    (property "Val" "2u2")
    (property "Voltage" "")
    (property "ki_description" "SMD Multilayer Ceramic Capacitor, 2.2 µF, 10 V, 0402 [1005 Metric], ± 10%, X5R, C")
    (property "ki_keywords" "0402, SMT, CAPACITOR, PASSIVE, CERAMIC, MLCC")
    (attr smd)
    (fp_text reference "C35" (at -0.768 -4.509) (layer "B.SilkS")
        (effects (font (size 0.7 0.7) (thickness 0.15)) (justify left bottom mirror))
    )
    (fp_text value "C_2u2_0402" (at -1.022927 -2.155213) (layer "B.Fab")
        (effects (font (size 0.7 0.7) (thickness 0.15)) (justify left bottom mirror))
    )
    (fp_text user "${REFERENCE}" (at -0.939 -4.599) (layer "B.Fab") hide
        (effects (font (size 0.7 0.7) (thickness 0.15)) (justify left bottom mirror))
    )
    (fp_text user "License: Apache-2.0" (at -0.939 -5.799) (layer "B.Fab") hide
        (effects (font (size 0.7 0.7) (thickness 0.15)) (justify left bottom mirror))
    )
    (fp_text user "Author: Antmicro" (at -0.939 -3.399) (layer "B.Fab") hide
        (effects (font (size 0.7 0.7) (thickness 0.15)) (justify left bottom mirror))
    )
    (fp_rect (start -0.925 0.47) (end 0.925 -0.47)
      (stroke (width 0.05) (type default)) (fill none) (layer "B.CrtYd"))
    (fp_line (start -0.494 -0.248) (end -0.494 0.25)
      (stroke (width 0.15) (type solid)) (layer "B.Fab"))
    (fp_line (start -0.494 0.25) (end 0.504 0.25)
      (stroke (width 0.15) (type solid)) (layer "B.Fab"))
    (fp_line (start 0.504 -0.248) (end -0.494 -0.248)
      (stroke (width 0.15) (type solid)) (layer "B.Fab"))
    (fp_line (start 0.504 0.25) (end 0.504 -0.248)
      (stroke (width 0.15) (type solid)) (layer "B.Fab"))
    (pad "1" smd roundrect (at -0.48 0 180) (size 0.59 0.64) (layers "B.Cu" "B.Paste" "B.Mask") (roundrect_rratio 0.25)
      (net 102 "Net-(U3-LDO_1V8A)") (pintype "passive"))
    (pad "2" smd roundrect (at 0.48 0 180) (size 0.59 0.64) (layers "B.Cu" "B.Paste" "B.Mask") (roundrect_rratio 0.25)
      (net 1 "GND") (pintype "passive"))
  )

  (footprint "antmicro-footprints:C_0402_1005Metric" (layer "B.Cu")
    (at 136.75 78.875 180)
    (descr "Capacitor SMD 0402")
    (tags "capacitor SMD 0402")
    (property "Author" "Antmicro")
    (property "Dielectric" "")
    (property "License" "Apache-2.0")
    (property "MPN" "C1005X6S1A105K050BC")
    (property "Manufacturer" "TDK")
    (property "Sheetfile" "tb-power.kicad_sch")
    (property "Sheetname" "Thunderbolt Controller - Power")
    (property "Val" "1u")
    (property "Voltage" "")
    (property "ki_description" "SMD Multilayer Ceramic Capacitor, 1 µF, 10 V, 0402 [1005 Metric], ± 10%, X6S, C")
    (property "ki_keywords" "0402, SMT, CAPACITOR, PASSIVE, CERAMIC, MLCC")
    (attr smd)
    (fp_text reference "C77" (at -17.682 -7.993) (layer "B.SilkS")
        (effects (font (size 0.7 0.7) (thickness 0.15)) (justify left bottom mirror))
    )
    (fp_text value "C_1u_0402" (at -1.022927 -2.155213) (layer "B.Fab")
        (effects (font (size 0.7 0.7) (thickness 0.15)) (justify left bottom mirror))
    )
    (fp_text user "Author: Antmicro" (at -0.939 -3.399) (layer "B.Fab") hide
        (effects (font (size 0.7 0.7) (thickness 0.15)) (justify left bottom mirror))
    )
    (fp_text user "License: Apache-2.0" (at -0.939 -5.799) (layer "B.Fab") hide
        (effects (font (size 0.7 0.7) (thickness 0.15)) (justify left bottom mirror))
    )
    (fp_text user "${REFERENCE}" (at -0.939 -4.599) (layer "B.Fab") hide
        (effects (font (size 0.7 0.7) (thickness 0.15)) (justify left bottom mirror))
    )
    (fp_rect (start -0.925 0.47) (end 0.925 -0.47)
      (stroke (width 0.05) (type default)) (fill none) (layer "B.CrtYd"))
    (fp_line (start -0.494 -0.248) (end -0.494 0.25)
      (stroke (width 0.15) (type solid)) (layer "B.Fab"))
    (fp_line (start -0.494 0.25) (end 0.504 0.25)
      (stroke (width 0.15) (type solid)) (layer "B.Fab"))
    (fp_line (start 0.504 -0.248) (end -0.494 -0.248)
      (stroke (width 0.15) (type solid)) (layer "B.Fab"))
    (fp_line (start 0.504 0.25) (end 0.504 -0.248)
      (stroke (width 0.15) (type solid)) (layer "B.Fab"))
    (pad "1" smd roundrect (at -0.48 0 180) (size 0.59 0.64) (layers "B.Cu" "B.Paste" "B.Mask") (roundrect_rratio 0.25)
      (net 1 "GND") (pintype "passive"))
    (pad "2" smd roundrect (at 0.48 0 180) (size 0.59 0.64) (layers "B.Cu" "B.Paste" "B.Mask") (roundrect_rratio 0.25)
      (net 112 "Net-(U4A-VCC0P9_SVR_SENSE)") (pintype "passive"))
  )

  (footprint "antmicro-footprints:C_0402_1005Metric" (layer "B.Cu")
    (at 155.08 80.74 180)
    (descr "Capacitor SMD 0402")
    (tags "capacitor SMD 0402")
    (property "Author" "Antmicro")
    (property "Dielectric" "")
    (property "License" "Apache-2.0")
    (property "MPN" "CC0402KRX5R6BB224")
    (property "Manufacturer" "YAGEO")
    (property "Sheetfile" "tb.kicad_sch")
    (property "Sheetname" "TB Controller")
    (property "Val" "220n")
    (property "Voltage" "")
    (property "ki_description" "SMD Multilayer Ceramic Capacitor, 0.22 µF, 10 V, 0402 [1005 Metric], ± 10%, X5R, CC Series")
    (property "ki_keywords" "0402, SMT, CAPACITOR, PASSIVE, MLCC, CERAMIC")
    (attr smd)
    (fp_text reference "C102" (at 1.034 -0.431) (layer "B.SilkS")
        (effects (font (size 0.7 0.7) (thickness 0.15)) (justify left bottom mirror))
    )
    (fp_text value "C_220n_0402" (at -1.022927 -2.155213) (layer "B.Fab")
        (effects (font (size 0.7 0.7) (thickness 0.15)) (justify left bottom mirror))
    )
    (fp_text user "Author: Antmicro" (at -0.939 -3.399) (layer "B.Fab") hide
        (effects (font (size 0.7 0.7) (thickness 0.15)) (justify left bottom mirror))
    )
    (fp_text user "License: Apache-2.0" (at -0.939 -5.799) (layer "B.Fab") hide
        (effects (font (size 0.7 0.7) (thickness 0.15)) (justify left bottom mirror))
    )
    (fp_text user "${REFERENCE}" (at -0.939 -4.599) (layer "B.Fab") hide
        (effects (font (size 0.7 0.7) (thickness 0.15)) (justify left bottom mirror))
    )
    (fp_rect (start -0.925 0.47) (end 0.925 -0.47)
      (stroke (width 0.05) (type default)) (fill none) (layer "B.CrtYd"))
    (fp_line (start -0.494 -0.248) (end -0.494 0.25)
      (stroke (width 0.15) (type solid)) (layer "B.Fab"))
    (fp_line (start -0.494 0.25) (end 0.504 0.25)
      (stroke (width 0.15) (type solid)) (layer "B.Fab"))
    (fp_line (start 0.504 -0.248) (end -0.494 -0.248)
      (stroke (width 0.15) (type solid)) (layer "B.Fab"))
    (fp_line (start 0.504 0.25) (end 0.504 -0.248)
      (stroke (width 0.15) (type solid)) (layer "B.Fab"))
    (pad "1" smd roundrect (at -0.48 0 180) (size 0.59 0.64) (layers "B.Cu" "B.Paste" "B.Mask") (roundrect_rratio 0.25)
      (net 17 "TB_TX0_N") (pintype "passive"))
    (pad "2" smd roundrect (at 0.48 0 180) (size 0.59 0.64) (layers "B.Cu" "B.Paste" "B.Mask") (roundrect_rratio 0.25)
      (net 18 "/TB Controller/PA_TX0_N") (pintype "passive"))
  )

  (footprint "antmicro-footprints:R_0402_1005Metric" (layer "B.Cu")
    (at 113.675 83.68 180)
    (descr "Resistor SMD 0402")
    (tags "resistor SMD 0402")
    (property "Author" "Antmicro")
    (property "License" "Apache-2.0")
    (property "MPN" "CR0402-FX-1243GLF")
    (property "Manufacturer" "Bourns")
    (property "Sheetfile" "power.kicad_sch")
    (property "Sheetname" "Power")
    (property "Tolerance" "1%")
    (property "Val" "124k")
    (property "ki_description" "SMD Chip Resistor, 124 kohm, ± 1%, 100 mW, 0402 [1005 Metric], Thick Film, Precision")
    (property "ki_keywords" "0402, SMT, RESISTOR, PASSIVE")
    (attr smd)
    (fp_text reference "R28" (at -3.038 -0.394) (layer "B.SilkS")
        (effects (font (size 0.7 0.7) (thickness 0.15)) (justify left bottom mirror))
    )
    (fp_text value "R_124k_0402" (at -1.011843 -1.772047) (layer "B.Fab")
        (effects (font (size 0.7 0.7) (thickness 0.15)) (justify left bottom mirror))
    )
    (fp_text user "License: Apache-2.0" (at -0.95 -5.169) (layer "B.Fab") hide
        (effects (font (size 0.7 0.7) (thickness 0.15)) (justify left bottom mirror))
    )
    (fp_text user "${REFERENCE}" (at -0.95 -3.168) (layer "B.Fab") hide
        (effects (font (size 0.7 0.7) (thickness 0.15)) (justify left bottom mirror))
    )
    (fp_text user "Author: Antmicro" (at -0.95 -4.169) (layer "B.Fab") hide
        (effects (font (size 0.7 0.7) (thickness 0.15)) (justify left bottom mirror))
    )
    (fp_rect (start -0.925 0.47) (end 0.925 -0.47)
      (stroke (width 0.05) (type default)) (fill none) (layer "B.CrtYd"))
    (fp_rect (start -0.5 0.25) (end 0.5 -0.25)
      (stroke (width 0.15) (type solid)) (fill none) (layer "B.Fab"))
    (pad "1" smd roundrect (at -0.48 0 180) (size 0.59 0.64) (layers "B.Cu" "B.Paste" "B.Mask") (roundrect_rratio 0.25)
      (net 1 "GND") (pintype "passive"))
    (pad "2" smd roundrect (at 0.48 0 180) (size 0.59 0.64) (layers "B.Cu" "B.Paste" "B.Mask") (roundrect_rratio 0.25)
      (net 161 "Net-(U1-RT)") (pintype "passive"))
  )

  (footprint "antmicro-footprints:R_0603_1608Metric" (layer "B.Cu")
    (at 112.13 91.83 -90)
    (descr "Resistor SMD 0603")
    (tags "resistor SMD 0603")
    (property "Author" "Antmicro")
    (property "License" "Apache-2.0")
    (property "MPN" "PMR03EZPJ000")
    (property "Manufacturer" "ROHM Semiconductor")
    (property "Max. Curr." "22.4A")
    (property "Sheetfile" "power.kicad_sch")
    (property "Sheetname" "Power")
    (property "Tolerance" "template_tolerance")
    (property "Val" "0R")
    (property "ki_description" "SMD Chip Resistor")
    (property "ki_keywords" "0603, SMT, RESISTOR, PASSIVE")
    (attr smd)
    (fp_text reference "R98" (at -1.025 0.751 90) (layer "B.SilkS")
        (effects (font (size 0.7 0.7) (thickness 0.15)) (justify left bottom mirror))
    )
    (fp_text value "R_0R_22.4A_0603" (at 0 -1.6 90) (layer "B.Fab")
        (effects (font (size 0.7 0.7) (thickness 0.15)) (justify left bottom mirror))
    )
    (fp_text user "Author: Antmicro" (at -1.25 -4.9 90) (layer "B.Fab") hide
        (effects (font (size 0.7 0.7) (thickness 0.15)) (justify left bottom mirror))
    )
    (fp_text user "${REFERENCE}" (at -1.25 -3.898 90) (layer "B.Fab") hide
        (effects (font (size 0.7 0.7) (thickness 0.15)) (justify left bottom mirror))
    )
    (fp_text user "License: Apache-2.0" (at -1.25 -5.9 90) (layer "B.Fab") hide
        (effects (font (size 0.7 0.7) (thickness 0.15)) (justify left bottom mirror))
    )
    (fp_line (start -0.15 -0.4) (end 0.15 -0.4)
      (stroke (width 0.15) (type solid)) (layer "B.SilkS"))
    (fp_line (start -0.15 0.4) (end 0.15 0.4)
      (stroke (width 0.15) (type solid)) (layer "B.SilkS"))
    (fp_rect (start -1.25 0.65) (end 1.25 -0.65)
      (stroke (width 0.05) (type solid)) (fill none) (layer "B.CrtYd"))
    (fp_rect (start -0.8 0.4) (end 0.8 -0.4)
      (stroke (width 0.15) (type solid)) (fill none) (layer "B.Fab"))
    (pad "1" smd roundrect (at -0.7 0 270) (size 0.8 1) (layers "B.Cu" "B.Paste" "B.Mask") (roundrect_rratio 0.2)
      (net 143 "Net-(Q3-S)") (pintype "passive"))
    (pad "2" smd roundrect (at 0.7 0 270) (size 0.8 1) (layers "B.Cu" "B.Paste" "B.Mask") (roundrect_rratio 0.2)
      (net 8 "12V0_PCIE") (pintype "passive"))
  )

  (footprint "antmicro-footprints:C_0402_1005Metric" (layer "B.Cu")
    (at 135.5 92.65 -90)
    (descr "Capacitor SMD 0402")
    (tags "capacitor SMD 0402")
    (property "Author" "Antmicro")
    (property "Dielectric" "")
    (property "License" "Apache-2.0")
    (property "MPN" "CC0402KRX5R6BB224")
    (property "Manufacturer" "YAGEO")
    (property "Sheetfile" "tb.kicad_sch")
    (property "Sheetname" "TB Controller")
    (property "Val" "220n")
    (property "Voltage" "")
    (property "ki_description" "SMD Multilayer Ceramic Capacitor, 0.22 µF, 10 V, 0402 [1005 Metric], ± 10%, X5R, CC Series")
    (property "ki_keywords" "0402, SMT, CAPACITOR, PASSIVE, MLCC, CERAMIC")
    (attr smd)
    (fp_text reference "C111" (at -3.877 -0.47 90) (layer "B.SilkS")
        (effects (font (size 0.7 0.7) (thickness 0.15)) (justify left bottom mirror))
    )
    (fp_text value "C_220n_0402" (at -1.022927 -2.155213 90) (layer "B.Fab")
        (effects (font (size 0.7 0.7) (thickness 0.15)) (justify left bottom mirror))
    )
    (fp_text user "License: Apache-2.0" (at -0.939 -5.799 90) (layer "B.Fab") hide
        (effects (font (size 0.7 0.7) (thickness 0.15)) (justify left bottom mirror))
    )
    (fp_text user "Author: Antmicro" (at -0.939 -3.399 90) (layer "B.Fab") hide
        (effects (font (size 0.7 0.7) (thickness 0.15)) (justify left bottom mirror))
    )
    (fp_text user "${REFERENCE}" (at -0.939 -4.599 90) (layer "B.Fab") hide
        (effects (font (size 0.7 0.7) (thickness 0.15)) (justify left bottom mirror))
    )
    (fp_rect (start -0.925 0.47) (end 0.925 -0.47)
      (stroke (width 0.05) (type default)) (fill none) (layer "B.CrtYd"))
    (fp_line (start -0.494 -0.248) (end -0.494 0.25)
      (stroke (width 0.15) (type solid)) (layer "B.Fab"))
    (fp_line (start -0.494 0.25) (end 0.504 0.25)
      (stroke (width 0.15) (type solid)) (layer "B.Fab"))
    (fp_line (start 0.504 -0.248) (end -0.494 -0.248)
      (stroke (width 0.15) (type solid)) (layer "B.Fab"))
    (fp_line (start 0.504 0.25) (end 0.504 -0.248)
      (stroke (width 0.15) (type solid)) (layer "B.Fab"))
    (pad "1" smd roundrect (at -0.48 0 270) (size 0.59 0.64) (layers "B.Cu" "B.Paste" "B.Mask") (roundrect_rratio 0.25)
      (net 82 "/TB Controller/TX2_P") (pintype "passive"))
    (pad "2" smd roundrect (at 0.48 0 270) (size 0.59 0.64) (layers "B.Cu" "B.Paste" "B.Mask") (roundrect_rratio 0.25)
      (net 30 "PCIE_TX2_P") (pintype "passive"))
  )

  (footprint "antmicro-footprints:C_0402_1005Metric" (layer "B.Cu")
    (at 130.9 79.85)
    (descr "Capacitor SMD 0402")
    (tags "capacitor SMD 0402")
    (property "Author" "Antmicro")
    (property "Dielectric" "")
    (property "License" "Apache-2.0")
    (property "MPN" "C1005X6S1A105K050BC")
    (property "Manufacturer" "TDK")
    (property "Sheetfile" "tb-power.kicad_sch")
    (property "Sheetname" "Thunderbolt Controller - Power")
    (property "Val" "1u")
    (property "Voltage" "")
    (property "ki_description" "SMD Multilayer Ceramic Capacitor, 1 µF, 10 V, 0402 [1005 Metric], ± 10%, X6S, C")
    (property "ki_keywords" "0402, SMT, CAPACITOR, PASSIVE, CERAMIC, MLCC")
    (attr smd)
    (fp_text reference "C55" (at 17.309 7.567 180) (layer "B.SilkS")
        (effects (font (size 0.7 0.7) (thickness 0.15)) (justify left bottom mirror))
    )
    (fp_text value "C_1u_0402" (at -1.022927 -2.155213 180) (layer "B.Fab")
        (effects (font (size 0.7 0.7) (thickness 0.15)) (justify left bottom mirror))
    )
    (fp_text user "${REFERENCE}" (at -0.939 -4.599 180) (layer "B.Fab") hide
        (effects (font (size 0.7 0.7) (thickness 0.15)) (justify left bottom mirror))
    )
    (fp_text user "Author: Antmicro" (at -0.939 -3.399 180) (layer "B.Fab") hide
        (effects (font (size 0.7 0.7) (thickness 0.15)) (justify left bottom mirror))
    )
    (fp_text user "License: Apache-2.0" (at -0.939 -5.799 180) (layer "B.Fab") hide
        (effects (font (size 0.7 0.7) (thickness 0.15)) (justify left bottom mirror))
    )
    (fp_rect (start -0.925 0.47) (end 0.925 -0.47)
      (stroke (width 0.05) (type default)) (fill none) (layer "B.CrtYd"))
    (fp_line (start -0.494 -0.248) (end -0.494 0.25)
      (stroke (width 0.15) (type solid)) (layer "B.Fab"))
    (fp_line (start -0.494 0.25) (end 0.504 0.25)
      (stroke (width 0.15) (type solid)) (layer "B.Fab"))
    (fp_line (start 0.504 -0.248) (end -0.494 -0.248)
      (stroke (width 0.15) (type solid)) (layer "B.Fab"))
    (fp_line (start 0.504 0.25) (end 0.504 -0.248)
      (stroke (width 0.15) (type solid)) (layer "B.Fab"))
    (pad "1" smd roundrect (at -0.48 0) (size 0.59 0.64) (layers "B.Cu" "B.Paste" "B.Mask") (roundrect_rratio 0.25)
      (net 1 "GND") (pintype "passive"))
    (pad "2" smd roundrect (at 0.48 0) (size 0.59 0.64) (layers "B.Cu" "B.Paste" "B.Mask") (roundrect_rratio 0.25)
      (net 106 "Net-(C53-Pad2)") (pintype "passive"))
  )

  (footprint "antmicro-footprints:R_0402_1005Metric" (layer "B.Cu")
    (at 133.125 70.72 90)
    (descr "Resistor SMD 0402")
    (tags "resistor SMD 0402")
    (property "Author" "Antmicro")
    (property "License" "Apache-2.0")
    (property "MPN" "CR0402-FX-1003GLF")
    (property "Manufacturer" "Bourns")
    (property "Sheetfile" "tb.kicad_sch")
    (property "Sheetname" "TB Controller")
    (property "Tolerance" "1%")
    (property "Val" "100k")
    (property "ki_description" "SMD Chip Resistor, 100 kohm, ± 1%, 62.5 mW, 0402 [1005 Metric], Thick Film, General Purpose")
    (property "ki_keywords" "0402, SMT, RESISTOR, PASSIVE")
    (attr smd)
    (fp_text reference "R77" (at -0.908 0.361 270) (layer "B.SilkS")
        (effects (font (size 0.7 0.7) (thickness 0.15)) (justify left bottom mirror))
    )
    (fp_text value "R_100k_0402" (at -1.011843 -1.772047 270) (layer "B.Fab")
        (effects (font (size 0.7 0.7) (thickness 0.15)) (justify left bottom mirror))
    )
    (fp_text user "License: Apache-2.0" (at -0.95 -5.169 270) (layer "B.Fab") hide
        (effects (font (size 0.7 0.7) (thickness 0.15)) (justify left bottom mirror))
    )
    (fp_text user "${REFERENCE}" (at -0.95 -3.168 270) (layer "B.Fab") hide
        (effects (font (size 0.7 0.7) (thickness 0.15)) (justify left bottom mirror))
    )
    (fp_text user "Author: Antmicro" (at -0.95 -4.169 270) (layer "B.Fab") hide
        (effects (font (size 0.7 0.7) (thickness 0.15)) (justify left bottom mirror))
    )
    (fp_rect (start -0.925 0.47) (end 0.925 -0.47)
      (stroke (width 0.05) (type default)) (fill none) (layer "B.CrtYd"))
    (fp_rect (start -0.5 0.25) (end 0.5 -0.25)
      (stroke (width 0.15) (type solid)) (fill none) (layer "B.Fab"))
    (pad "1" smd roundrect (at -0.48 0 90) (size 0.59 0.64) (layers "B.Cu" "B.Paste" "B.Mask") (roundrect_rratio 0.25)
      (net 192 "Net-(U4C-GPIO_3)") (pintype "passive"))
    (pad "2" smd roundrect (at 0.48 0 90) (size 0.59 0.64) (layers "B.Cu" "B.Paste" "B.Mask") (roundrect_rratio 0.25)
      (net 1 "GND") (pintype "passive"))
  )

  (footprint "antmicro-footprints:R_0402_1005Metric" (layer "B.Cu")
    (at 159.41 61.97 180)
    (descr "Resistor SMD 0402")
    (tags "resistor SMD 0402")
    (property "Author" "Antmicro")
    (property "License" "Apache-2.0")
    (property "MPN" "CR0402-FX-1002GLF")
    (property "Manufacturer" "Bourns")
    (property "Sheetfile" "power.kicad_sch")
    (property "Sheetname" "Power")
    (property "Tolerance" "1%")
    (property "Val" "10k")
    (property "ki_description" "SMD Chip Resistor, 10 kohm, ± 1%, 62.5 mW, 0402 [1005 Metric], Thick Film, General Purpose")
    (property "ki_keywords" "0402, SMT, RESISTOR, PASSIVE")
    (attr smd)
    (fp_text reference "R32" (at -1.166727 -2.16534) (layer "B.SilkS")
        (effects (font (size 0.7 0.7) (thickness 0.15)) (justify left bottom mirror))
    )
    (fp_text value "R_10k_0402" (at -1.011843 -1.772047) (layer "B.Fab")
        (effects (font (size 0.7 0.7) (thickness 0.15)) (justify left bottom mirror))
    )
    (fp_text user "License: Apache-2.0" (at -0.95 -5.169) (layer "B.Fab") hide
        (effects (font (size 0.7 0.7) (thickness 0.15)) (justify left bottom mirror))
    )
    (fp_text user "Author: Antmicro" (at -0.95 -4.169) (layer "B.Fab") hide
        (effects (font (size 0.7 0.7) (thickness 0.15)) (justify left bottom mirror))
    )
    (fp_text user "${REFERENCE}" (at -0.95 -3.168) (layer "B.Fab") hide
        (effects (font (size 0.7 0.7) (thickness 0.15)) (justify left bottom mirror))
    )
    (fp_rect (start -0.925 0.47) (end 0.925 -0.47)
      (stroke (width 0.05) (type default)) (fill none) (layer "B.CrtYd"))
    (fp_rect (start -0.5 0.25) (end 0.5 -0.25)
      (stroke (width 0.15) (type solid)) (fill none) (layer "B.Fab"))
    (pad "1" smd roundrect (at -0.48 0 180) (size 0.59 0.64) (layers "B.Cu" "B.Paste" "B.Mask") (roundrect_rratio 0.25)
      (net 165 "Net-(U3-MRESET(GPIO11))") (pintype "passive"))
    (pad "2" smd roundrect (at 0.48 0 180) (size 0.59 0.64) (layers "B.Cu" "B.Paste" "B.Mask") (roundrect_rratio 0.25)
      (net 1 "GND") (pintype "passive"))
  )

  (footprint "antmicro-footprints:C_0402_1005Metric" (layer "B.Cu")
    (at 143.15 76.432 90)
    (descr "Capacitor SMD 0402")
    (tags "capacitor SMD 0402")
    (property "Author" "Antmicro")
    (property "Dielectric" "")
    (property "License" "Apache-2.0")
    (property "MPN" "CC0402MRX5R5BB106")
    (property "Manufacturer" "YAGEO")
    (property "Sheetfile" "tb-power.kicad_sch")
    (property "Sheetname" "Thunderbolt Controller - Power")
    (property "Val" "10u")
    (property "Voltage" "")
    (property "ki_description" "SMD Multilayer Ceramic Capacitor, 10 µF, 6.3 V, 0402 [1005 Metric], ± 20%, X5R, CC Series")
    (property "ki_keywords" "0402, SMT, CAPACITOR, PASSIVE, MLCC, CERAMIC")
    (attr smd)
    (fp_text reference "C80" (at 5.439 1.503 270) (layer "B.SilkS")
        (effects (font (size 0.7 0.7) (thickness 0.15)) (justify left bottom mirror))
    )
    (fp_text value "C_10u_0402" (at -1.022927 -2.155213 270) (layer "B.Fab")
        (effects (font (size 0.7 0.7) (thickness 0.15)) (justify left bottom mirror))
    )
    (fp_text user "License: Apache-2.0" (at -0.939 -5.799 270) (layer "B.Fab") hide
        (effects (font (size 0.7 0.7) (thickness 0.15)) (justify left bottom mirror))
    )
    (fp_text user "Author: Antmicro" (at -0.939 -3.399 270) (layer "B.Fab") hide
        (effects (font (size 0.7 0.7) (thickness 0.15)) (justify left bottom mirror))
    )
    (fp_text user "${REFERENCE}" (at -0.939 -4.599 270) (layer "B.Fab") hide
        (effects (font (size 0.7 0.7) (thickness 0.15)) (justify left bottom mirror))
    )
    (fp_rect (start -0.925 0.47) (end 0.925 -0.47)
      (stroke (width 0.05) (type default)) (fill none) (layer "B.CrtYd"))
    (fp_line (start -0.494 -0.248) (end -0.494 0.25)
      (stroke (width 0.15) (type solid)) (layer "B.Fab"))
    (fp_line (start -0.494 0.25) (end 0.504 0.25)
      (stroke (width 0.15) (type solid)) (layer "B.Fab"))
    (fp_line (start 0.504 -0.248) (end -0.494 -0.248)
      (stroke (width 0.15) (type solid)) (layer "B.Fab"))
    (fp_line (start 0.504 0.25) (end 0.504 -0.248)
      (stroke (width 0.15) (type solid)) (layer "B.Fab"))
    (pad "1" smd roundrect (at -0.48 0 90) (size 0.59 0.64) (layers "B.Cu" "B.Paste" "B.Mask") (roundrect_rratio 0.25)
      (net 1 "GND") (pintype "passive"))
    (pad "2" smd roundrect (at 0.48 0 90) (size 0.59 0.64) (layers "B.Cu" "B.Paste" "B.Mask") (roundrect_rratio 0.25)
      (net 2 "3V3_SYS") (pintype "passive"))
  )

  (footprint "antmicro-footprints:R_0402_1005Metric" (layer "B.Cu")
    (at 102.390003 88.425 -90)
    (descr "Resistor SMD 0402")
    (tags "resistor SMD 0402")
    (property "Author" "Antmicro")
    (property "License" "Apache-2.0")
    (property "MPN" "CR0402-FX-1003GLF")
    (property "Manufacturer" "Bourns")
    (property "Sheetfile" "power.kicad_sch")
    (property "Sheetname" "Power")
    (property "Tolerance" "1%")
    (property "Val" "100k")
    (property "ki_description" "SMD Chip Resistor, 100 kohm, ± 1%, 62.5 mW, 0402 [1005 Metric], Thick Film, General Purpose")
    (property "ki_keywords" "0402, SMT, RESISTOR, PASSIVE")
    (attr smd)
    (fp_text reference "R92" (at -3.081 -0.45 90) (layer "B.SilkS")
        (effects (font (size 0.7 0.7) (thickness 0.15)) (justify left bottom mirror))
    )
    (fp_text value "R_100k_0402" (at -1.011843 -1.772047 90) (layer "B.Fab")
        (effects (font (size 0.7 0.7) (thickness 0.15)) (justify left bottom mirror))
    )
    (fp_text user "License: Apache-2.0" (at -0.95 -5.169 90) (layer "B.Fab") hide
        (effects (font (size 0.7 0.7) (thickness 0.15)) (justify left bottom mirror))
    )
    (fp_text user "Author: Antmicro" (at -0.95 -4.169 90) (layer "B.Fab") hide
        (effects (font (size 0.7 0.7) (thickness 0.15)) (justify left bottom mirror))
    )
    (fp_text user "${REFERENCE}" (at -0.95 -3.168 90) (layer "B.Fab") hide
        (effects (font (size 0.7 0.7) (thickness 0.15)) (justify left bottom mirror))
    )
    (fp_rect (start -0.925 0.47) (end 0.925 -0.47)
      (stroke (width 0.05) (type default)) (fill none) (layer "B.CrtYd"))
    (fp_rect (start -0.5 0.25) (end 0.5 -0.25)
      (stroke (width 0.15) (type solid)) (fill none) (layer "B.Fab"))
    (pad "1" smd roundrect (at -0.48 0 270) (size 0.59 0.64) (layers "B.Cu" "B.Paste" "B.Mask") (roundrect_rratio 0.25)
      (net 1 "GND") (pintype "passive"))
    (pad "2" smd roundrect (at 0.48 0 270) (size 0.59 0.64) (layers "B.Cu" "B.Paste" "B.Mask") (roundrect_rratio 0.25)
      (net 140 "Net-(Q2-B)") (pintype "passive"))
  )

  (footprint "antmicro-footprints:C_0402_1005Metric" (layer "B.Cu")
    (at 144.15 74.482 -90)
    (descr "Capacitor SMD 0402")
    (tags "capacitor SMD 0402")
    (property "Author" "Antmicro")
    (property "Dielectric" "")
    (property "License" "Apache-2.0")
    (property "MPN" "CC0402MRX5R5BB106")
    (property "Manufacturer" "YAGEO")
    (property "Sheetfile" "tb-power.kicad_sch")
    (property "Sheetname" "Thunderbolt Controller - Power")
    (property "Val" "10u")
    (property "Voltage" "")
    (property "ki_description" "SMD Multilayer Ceramic Capacitor, 10 µF, 6.3 V, 0402 [1005 Metric], ± 20%, X5R, CC Series")
    (property "ki_keywords" "0402, SMT, CAPACITOR, PASSIVE, MLCC, CERAMIC")
    (attr smd)
    (fp_text reference "C76" (at -5.521 -1.519 90) (layer "B.SilkS")
        (effects (font (size 0.7 0.7) (thickness 0.15)) (justify left bottom mirror))
    )
    (fp_text value "C_10u_0402" (at -1.022927 -2.155213 90) (layer "B.Fab")
        (effects (font (size 0.7 0.7) (thickness 0.15)) (justify left bottom mirror))
    )
    (fp_text user "Author: Antmicro" (at -0.939 -3.399 90) (layer "B.Fab") hide
        (effects (font (size 0.7 0.7) (thickness 0.15)) (justify left bottom mirror))
    )
    (fp_text user "License: Apache-2.0" (at -0.939 -5.799 90) (layer "B.Fab") hide
        (effects (font (size 0.7 0.7) (thickness 0.15)) (justify left bottom mirror))
    )
    (fp_text user "${REFERENCE}" (at -0.939 -4.599 90) (layer "B.Fab") hide
        (effects (font (size 0.7 0.7) (thickness 0.15)) (justify left bottom mirror))
    )
    (fp_rect (start -0.925 0.47) (end 0.925 -0.47)
      (stroke (width 0.05) (type default)) (fill none) (layer "B.CrtYd"))
    (fp_line (start -0.494 -0.248) (end -0.494 0.25)
      (stroke (width 0.15) (type solid)) (layer "B.Fab"))
    (fp_line (start -0.494 0.25) (end 0.504 0.25)
      (stroke (width 0.15) (type solid)) (layer "B.Fab"))
    (fp_line (start 0.504 -0.248) (end -0.494 -0.248)
      (stroke (width 0.15) (type solid)) (layer "B.Fab"))
    (fp_line (start 0.504 0.25) (end 0.504 -0.248)
      (stroke (width 0.15) (type solid)) (layer "B.Fab"))
    (pad "1" smd roundrect (at -0.48 0 270) (size 0.59 0.64) (layers "B.Cu" "B.Paste" "B.Mask") (roundrect_rratio 0.25)
      (net 1 "GND") (pintype "passive"))
    (pad "2" smd roundrect (at 0.48 0 270) (size 0.59 0.64) (layers "B.Cu" "B.Paste" "B.Mask") (roundrect_rratio 0.25)
      (net 2 "3V3_SYS") (pintype "passive"))
  )

  (footprint "antmicro-footprints:C_0402_1005Metric" (layer "B.Cu")
    (at 111.725 79.65)
    (descr "Capacitor SMD 0402")
    (tags "capacitor SMD 0402")
    (property "Author" "Antmicro")
    (property "Dielectric" "X5R")
    (property "License" "Apache-2.0")
    (property "MPN" "GRM155R61H104KE14D")
    (property "Manufacturer" "Murata")
    (property "Sheetfile" "power.kicad_sch")
    (property "Sheetname" "Power")
    (property "Val" "100n")
    (property "Voltage" "50V")
    (property "ki_description" "SMD Multilayer Ceramic Capacitor, 0.1 µF, 50 V, 0402 [1005 Metric], ± 10%, X5R, GRM Series")
    (property "ki_keywords" "0402, SMT, CAPACITOR, PASSIVE, CERAMIC, MLCC")
    (attr smd)
    (fp_text reference "C28" (at 1.051 -4.72 180) (layer "B.SilkS")
        (effects (font (size 0.7 0.7) (thickness 0.15)) (justify left bottom mirror))
    )
    (fp_text value "C_100n_0402" (at -1.022927 -2.155213 180) (layer "B.Fab")
        (effects (font (size 0.7 0.7) (thickness 0.15)) (justify left bottom mirror))
    )
    (fp_text user "${REFERENCE}" (at -0.939 -4.599 180) (layer "B.Fab") hide
        (effects (font (size 0.7 0.7) (thickness 0.15)) (justify left bottom mirror))
    )
    (fp_text user "Author: Antmicro" (at -0.939 -3.399 180) (layer "B.Fab") hide
        (effects (font (size 0.7 0.7) (thickness 0.15)) (justify left bottom mirror))
    )
    (fp_text user "License: Apache-2.0" (at -0.939 -5.799 180) (layer "B.Fab") hide
        (effects (font (size 0.7 0.7) (thickness 0.15)) (justify left bottom mirror))
    )
    (fp_rect (start -0.925 0.47) (end 0.925 -0.47)
      (stroke (width 0.05) (type default)) (fill none) (layer "B.CrtYd"))
    (fp_line (start -0.494 -0.248) (end -0.494 0.25)
      (stroke (width 0.15) (type solid)) (layer "B.Fab"))
    (fp_line (start -0.494 0.25) (end 0.504 0.25)
      (stroke (width 0.15) (type solid)) (layer "B.Fab"))
    (fp_line (start 0.504 -0.248) (end -0.494 -0.248)
      (stroke (width 0.15) (type solid)) (layer "B.Fab"))
    (fp_line (start 0.504 0.25) (end 0.504 -0.248)
      (stroke (width 0.15) (type solid)) (layer "B.Fab"))
    (pad "1" smd roundrect (at -0.48 0) (size 0.59 0.64) (layers "B.Cu" "B.Paste" "B.Mask") (roundrect_rratio 0.25)
      (net 96 "Net-(U1-BST2)") (pintype "passive"))
    (pad "2" smd roundrect (at 0.48 0) (size 0.59 0.64) (layers "B.Cu" "B.Paste" "B.Mask") (roundrect_rratio 0.25)
      (net 268 "Net-(C28-Pad2)") (pintype "passive"))
  )

  (footprint "antmicro-footprints:C_0805_2012Metric" (layer "B.Cu")
    (at 114.8 93.55 180)
    (descr "Capacitor SMD 0805")
    (tags "capacitor SMD 0805")
    (property "Author" "Antmicro")
    (property "Dielectric" "")
    (property "License" "Apache-2.0")
    (property "MPN" "GRM21BR6YA106KE43L")
    (property "Manufacturer" "Murata")
    (property "Sheetfile" "connectors.kicad_sch")
    (property "Sheetname" "Connectors")
    (property "Val" "10u")
    (property "Voltage" "35V")
    (property "ki_description" "SMD Multilayer Ceramic Capacitor, 10 µF, 35 V, 0805 [2012 Metric], ± 10%, X5R, GRM Series")
    (property "ki_keywords" "0805, SMT, CAPACITOR, PASSIVE")
    (attr smd)
    (fp_text reference "C6" (at -3.564 -0.43) (layer "B.SilkS")
        (effects (font (size 0.7 0.7) (thickness 0.15)) (justify left bottom mirror))
    )
    (fp_text value "C_10u_0805_35V" (at -2.055717 -1.963152) (layer "B.Fab")
        (effects (font (size 0.7 0.7) (thickness 0.15)) (justify left bottom mirror))
    )
    (fp_text user "${REFERENCE}" (at -1.9 -3.947) (layer "B.Fab") hide
        (effects (font (size 0.7 0.7) (thickness 0.15)) (justify left bottom mirror))
    )
    (fp_text user "License: Apache-2.0" (at -1.9 -4.947) (layer "B.Fab") hide
        (effects (font (size 0.7 0.7) (thickness 0.15)) (justify left bottom mirror))
    )
    (fp_text user "Author: Antmicro" (at -1.9 -5.947) (layer "B.Fab") hide
        (effects (font (size 0.7 0.7) (thickness 0.15)) (justify left bottom mirror))
    )
    (fp_line (start -0.3 -0.7) (end 0.3 -0.7)
      (stroke (width 0.15) (type solid)) (layer "B.SilkS"))
    (fp_line (start -0.3 0.7) (end 0.3 0.7)
      (stroke (width 0.15) (type solid)) (layer "B.SilkS"))
    (fp_rect (start 1.95 0.9) (end -1.95 -0.9)
      (stroke (width 0.05) (type default)) (fill none) (layer "B.CrtYd"))
    (fp_rect (start -0.95 0.675) (end 0.95 -0.675)
      (stroke (width 0.15) (type solid)) (fill none) (layer "B.Fab"))
    (pad "1" smd roundrect (at -1.1 0 180) (size 1.2 1.3) (layers "B.Cu" "B.Paste" "B.Mask") (roundrect_rratio 0.25)
      (net 1 "GND") (pintype "passive"))
    (pad "2" smd roundrect (at 1.1 0 180) (size 1.2 1.3) (layers "B.Cu" "B.Paste" "B.Mask") (roundrect_rratio 0.25)
      (net 8 "12V0_PCIE") (pintype "passive"))
  )

  (footprint "antmicro-footprints:C_0402_1005Metric" (layer "B.Cu")
    (at 153.41 63.97)
    (descr "Capacitor SMD 0402")
    (tags "capacitor SMD 0402")
    (property "Author" "Antmicro")
    (property "Dielectric" "")
    (property "License" "Apache-2.0")
    (property "MPN" "CC0402MRX5R5BB106")
    (property "Manufacturer" "YAGEO")
    (property "Sheetfile" "power.kicad_sch")
    (property "Sheetname" "Power")
    (property "Val" "10u")
    (property "Voltage" "")
    (property "ki_description" "SMD Multilayer Ceramic Capacitor, 10 µF, 6.3 V, 0402 [1005 Metric], ± 20%, X5R, CC Series")
    (property "ki_keywords" "0402, SMT, CAPACITOR, PASSIVE, MLCC, CERAMIC")
    (attr smd)
    (fp_text reference "C23" (at 0.768 4.483 180) (layer "B.SilkS")
        (effects (font (size 0.7 0.7) (thickness 0.15)) (justify left bottom mirror))
    )
    (fp_text value "C_10u_0402" (at -1.022927 -2.155213 180) (layer "B.Fab")
        (effects (font (size 0.7 0.7) (thickness 0.15)) (justify left bottom mirror))
    )
    (fp_text user "Author: Antmicro" (at -0.939 -3.399 180) (layer "B.Fab") hide
        (effects (font (size 0.7 0.7) (thickness 0.15)) (justify left bottom mirror))
    )
    (fp_text user "${REFERENCE}" (at -0.939 -4.599 180) (layer "B.Fab") hide
        (effects (font (size 0.7 0.7) (thickness 0.15)) (justify left bottom mirror))
    )
    (fp_text user "License: Apache-2.0" (at -0.939 -5.799 180) (layer "B.Fab") hide
        (effects (font (size 0.7 0.7) (thickness 0.15)) (justify left bottom mirror))
    )
    (fp_rect (start -0.925 0.47) (end 0.925 -0.47)
      (stroke (width 0.05) (type default)) (fill none) (layer "B.CrtYd"))
    (fp_line (start -0.494 -0.248) (end -0.494 0.25)
      (stroke (width 0.15) (type solid)) (layer "B.Fab"))
    (fp_line (start -0.494 0.25) (end 0.504 0.25)
      (stroke (width 0.15) (type solid)) (layer "B.Fab"))
    (fp_line (start 0.504 -0.248) (end -0.494 -0.248)
      (stroke (width 0.15) (type solid)) (layer "B.Fab"))
    (fp_line (start 0.504 0.25) (end 0.504 -0.248)
      (stroke (width 0.15) (type solid)) (layer "B.Fab"))
    (pad "1" smd roundrect (at -0.48 0) (size 0.59 0.64) (layers "B.Cu" "B.Paste" "B.Mask") (roundrect_rratio 0.25)
      (net 1 "GND") (pintype "passive"))
    (pad "2" smd roundrect (at 0.48 0) (size 0.59 0.64) (layers "B.Cu" "B.Paste" "B.Mask") (roundrect_rratio 0.25)
      (net 2 "3V3_SYS") (pintype "passive"))
  )

  (footprint "antmicro-footprints:R_0402_1005Metric" (layer "B.Cu")
    (at 161.41 60.97)
    (descr "Resistor SMD 0402")
    (tags "resistor SMD 0402")
    (property "Author" "Antmicro")
    (property "License" "Apache-2.0")
    (property "MPN" "CR0402-FX-1003GLF")
    (property "Manufacturer" "Bourns")
    (property "Sheetfile" "power.kicad_sch")
    (property "Sheetname" "Power")
    (property "Tolerance" "1%")
    (property "Val" "100k")
    (property "ki_description" "SMD Chip Resistor, 100 kohm, ± 1%, 62.5 mW, 0402 [1005 Metric], Thick Film, General Purpose")
    (property "ki_keywords" "0402, SMT, RESISTOR, PASSIVE")
    (attr smd)
    (fp_text reference "R34" (at 3.182 0.371 180) (layer "B.SilkS")
        (effects (font (size 0.7 0.7) (thickness 0.15)) (justify left bottom mirror))
    )
    (fp_text value "R_100k_0402" (at -1.011843 -1.772047 180) (layer "B.Fab")
        (effects (font (size 0.7 0.7) (thickness 0.15)) (justify left bottom mirror))
    )
    (fp_text user "${REFERENCE}" (at -0.95 -3.168 180) (layer "B.Fab") hide
        (effects (font (size 0.7 0.7) (thickness 0.15)) (justify left bottom mirror))
    )
    (fp_text user "Author: Antmicro" (at -0.95 -4.169 180) (layer "B.Fab") hide
        (effects (font (size 0.7 0.7) (thickness 0.15)) (justify left bottom mirror))
    )
    (fp_text user "License: Apache-2.0" (at -0.95 -5.169 180) (layer "B.Fab") hide
        (effects (font (size 0.7 0.7) (thickness 0.15)) (justify left bottom mirror))
    )
    (fp_rect (start -0.925 0.47) (end 0.925 -0.47)
      (stroke (width 0.05) (type default)) (fill none) (layer "B.CrtYd"))
    (fp_rect (start -0.5 0.25) (end 0.5 -0.25)
      (stroke (width 0.15) (type solid)) (fill none) (layer "B.Fab"))
    (pad "1" smd roundrect (at -0.48 0) (size 0.59 0.64) (layers "B.Cu" "B.Paste" "B.Mask") (roundrect_rratio 0.25)
      (net 167 "Net-(U3-BUSPOWERZ(GPIO10))") (pintype "passive"))
    (pad "2" smd roundrect (at 0.48 0) (size 0.59 0.64) (layers "B.Cu" "B.Paste" "B.Mask") (roundrect_rratio 0.25)
      (net 9 "/Power/TPS_3V3") (pintype "passive"))
  )

  (footprint "antmicro-footprints:C_0402_1005Metric" (layer "B.Cu")
    (at 116.920001 61.195)
    (descr "Capacitor SMD 0402")
    (tags "capacitor SMD 0402")
    (property "Author" "Antmicro")
    (property "Dielectric" "")
    (property "License" "Apache-2.0")
    (property "MPN" "04025A330FAT2A")
    (property "Manufacturer" "KYOCERA AVX")
    (property "Sheetfile" "power.kicad_sch")
    (property "Sheetname" "Power")
    (property "Val" "33p")
    (property "Voltage" "")
    (property "ki_description" "SMD Multilayer Ceramic Capacitor, 33 pF, 50 V, 0402 [1005 Metric], ± 5%, C0G / NP0, MC")
    (property "ki_keywords" "0402, SMT, CAPACITOR, PASSIVE")
    (attr smd)
    (fp_text reference "C33" (at 3.094999 0.4 180) (layer "B.SilkS")
        (effects (font (size 0.7 0.7) (thickness 0.15)) (justify left bottom mirror))
    )
    (fp_text value "C_33p_0402" (at -1.022927 -2.155213 180) (layer "B.Fab")
        (effects (font (size 0.7 0.7) (thickness 0.15)) (justify left bottom mirror))
    )
    (fp_text user "Author: Antmicro" (at -0.939 -3.399 180) (layer "B.Fab") hide
        (effects (font (size 0.7 0.7) (thickness 0.15)) (justify left bottom mirror))
    )
    (fp_text user "License: Apache-2.0" (at -0.939 -5.799 180) (layer "B.Fab") hide
        (effects (font (size 0.7 0.7) (thickness 0.15)) (justify left bottom mirror))
    )
    (fp_text user "${REFERENCE}" (at -0.939 -4.599 180) (layer "B.Fab") hide
        (effects (font (size 0.7 0.7) (thickness 0.15)) (justify left bottom mirror))
    )
    (fp_rect (start -0.925 0.47) (end 0.925 -0.47)
      (stroke (width 0.05) (type default)) (fill none) (layer "B.CrtYd"))
    (fp_line (start -0.494 -0.248) (end -0.494 0.25)
      (stroke (width 0.15) (type solid)) (layer "B.Fab"))
    (fp_line (start -0.494 0.25) (end 0.504 0.25)
      (stroke (width 0.15) (type solid)) (layer "B.Fab"))
    (fp_line (start 0.504 -0.248) (end -0.494 -0.248)
      (stroke (width 0.15) (type solid)) (layer "B.Fab"))
    (fp_line (start 0.504 0.25) (end 0.504 -0.248)
      (stroke (width 0.15) (type solid)) (layer "B.Fab"))
    (pad "1" smd roundrect (at -0.48 0) (size 0.59 0.64) (layers "B.Cu" "B.Paste" "B.Mask") (roundrect_rratio 0.25)
      (net 99 "Net-(U2-FB)") (pintype "passive"))
    (pad "2" smd roundrect (at 0.48 0) (size 0.59 0.64) (layers "B.Cu" "B.Paste" "B.Mask") (roundrect_rratio 0.25)
      (net 100 "Net-(D2-A)") (pintype "passive"))
  )

  (footprint "antmicro-footprints:C_0402_1005Metric" (layer "B.Cu")
    (at 142.15 74.482 -90)
    (descr "Capacitor SMD 0402")
    (tags "capacitor SMD 0402")
    (property "Author" "Antmicro")
    (property "Dielectric" "X5R")
    (property "License" "Apache-2.0")
    (property "MPN" "GRM155R61H104KE14D")
    (property "Manufacturer" "Murata")
    (property "Sheetfile" "tb-power.kicad_sch")
    (property "Sheetname" "Thunderbolt Controller - Power")
    (property "Val" "100n")
    (property "Voltage" "50V")
    (property "ki_description" "SMD Multilayer Ceramic Capacitor, 0.1 µF, 50 V, 0402 [1005 Metric], ± 10%, X5R, GRM Series")
    (property "ki_keywords" "0402, SMT, CAPACITOR, PASSIVE, CERAMIC, MLCC")
    (attr smd)
    (fp_text reference "C93" (at -5.521 -1.487 90) (layer "B.SilkS")
        (effects (font (size 0.7 0.7) (thickness 0.15)) (justify left bottom mirror))
    )
    (fp_text value "C_100n_0402" (at -1.022927 -2.155213 90) (layer "B.Fab")
        (effects (font (size 0.7 0.7) (thickness 0.15)) (justify left bottom mirror))
    )
    (fp_text user "Author: Antmicro" (at -0.939 -3.399 90) (layer "B.Fab") hide
        (effects (font (size 0.7 0.7) (thickness 0.15)) (justify left bottom mirror))
    )
    (fp_text user "${REFERENCE}" (at -0.939 -4.599 90) (layer "B.Fab") hide
        (effects (font (size 0.7 0.7) (thickness 0.15)) (justify left bottom mirror))
    )
    (fp_text user "License: Apache-2.0" (at -0.939 -5.799 90) (layer "B.Fab") hide
        (effects (font (size 0.7 0.7) (thickness 0.15)) (justify left bottom mirror))
    )
    (fp_rect (start -0.925 0.47) (end 0.925 -0.47)
      (stroke (width 0.05) (type default)) (fill none) (layer "B.CrtYd"))
    (fp_line (start -0.494 -0.248) (end -0.494 0.25)
      (stroke (width 0.15) (type solid)) (layer "B.Fab"))
    (fp_line (start -0.494 0.25) (end 0.504 0.25)
      (stroke (width 0.15) (type solid)) (layer "B.Fab"))
    (fp_line (start 0.504 -0.248) (end -0.494 -0.248)
      (stroke (width 0.15) (type solid)) (layer "B.Fab"))
    (fp_line (start 0.504 0.25) (end 0.504 -0.248)
      (stroke (width 0.15) (type solid)) (layer "B.Fab"))
    (pad "1" smd roundrect (at -0.48 0 270) (size 0.59 0.64) (layers "B.Cu" "B.Paste" "B.Mask") (roundrect_rratio 0.25)
      (net 1 "GND") (pintype "passive"))
    (pad "2" smd roundrect (at 0.48 0 270) (size 0.59 0.64) (layers "B.Cu" "B.Paste" "B.Mask") (roundrect_rratio 0.25)
      (net 2 "3V3_SYS") (pintype "passive"))
  )

  (footprint "antmicro-footprints:R_0402_1005Metric" (layer "B.Cu")
    (at 136.2 70.72 90)
    (descr "Resistor SMD 0402")
    (tags "resistor SMD 0402")
    (property "Author" "Antmicro")
    (property "License" "Apache-2.0")
    (property "MPN" "CR0402-FX-1003GLF")
    (property "Manufacturer" "Bourns")
    (property "Sheetfile" "tb.kicad_sch")
    (property "Sheetname" "TB Controller")
    (property "Tolerance" "1%")
    (property "Val" "100k")
    (property "ki_description" "SMD Chip Resistor, 100 kohm, ± 1%, 62.5 mW, 0402 [1005 Metric], Thick Film, General Purpose")
    (property "ki_keywords" "0402, SMT, RESISTOR, PASSIVE")
    (attr smd)
    (fp_text reference "R90" (at -1.035 0.434 270) (layer "B.SilkS")
        (effects (font (size 0.7 0.7) (thickness 0.15)) (justify left bottom mirror))
    )
    (fp_text value "R_100k_0402" (at -1.011843 -1.772047 270) (layer "B.Fab")
        (effects (font (size 0.7 0.7) (thickness 0.15)) (justify left bottom mirror))
    )
    (fp_text user "Author: Antmicro" (at -0.95 -4.169 270) (layer "B.Fab") hide
        (effects (font (size 0.7 0.7) (thickness 0.15)) (justify left bottom mirror))
    )
    (fp_text user "${REFERENCE}" (at -0.95 -3.168 270) (layer "B.Fab") hide
        (effects (font (size 0.7 0.7) (thickness 0.15)) (justify left bottom mirror))
    )
    (fp_text user "License: Apache-2.0" (at -0.95 -5.169 270) (layer "B.Fab") hide
        (effects (font (size 0.7 0.7) (thickness 0.15)) (justify left bottom mirror))
    )
    (fp_rect (start -0.925 0.47) (end 0.925 -0.47)
      (stroke (width 0.05) (type default)) (fill none) (layer "B.CrtYd"))
    (fp_rect (start -0.5 0.25) (end 0.5 -0.25)
      (stroke (width 0.15) (type solid)) (fill none) (layer "B.Fab"))
    (pad "1" smd roundrect (at -0.48 0 90) (size 0.59 0.64) (layers "B.Cu" "B.Paste" "B.Mask") (roundrect_rratio 0.25)
      (net 54 "PCIE_WAKE") (pintype "passive"))
    (pad "2" smd roundrect (at 0.48 0 90) (size 0.59 0.64) (layers "B.Cu" "B.Paste" "B.Mask") (roundrect_rratio 0.25)
      (net 2 "3V3_SYS") (pintype "passive"))
  )

  (footprint "antmicro-footprints:R_0402_1005Metric" (layer "B.Cu")
    (at 138.25 66.82 90)
    (descr "Resistor SMD 0402")
    (tags "resistor SMD 0402")
    (property "Author" "Antmicro")
    (property "License" "Apache-2.0")
    (property "MPN" "CR0402-FX-1402GLF")
    (property "Manufacturer" "Bourns")
    (property "Sheetfile" "tb.kicad_sch")
    (property "Sheetname" "TB Controller")
    (property "Tolerance" "1%")
    (property "Val" "14k")
    (property "dnp" "")
    (property "ki_description" "SMD Chip Resistor, 14 kohm, ± 1%, 100 mW, 0402 [1005 Metric], Thick Film, Precision")
    (property "ki_keywords" "0402, SMT, RESISTOR, PASSIVE")
    (attr smd)
    (fp_text reference "R76" (at 3.066 0.434 270) (layer "B.SilkS")
        (effects (font (size 0.7 0.7) (thickness 0.15)) (justify left bottom mirror))
    )
    (fp_text value "R_14k_0402" (at -1.011843 -1.772047 270) (layer "B.Fab")
        (effects (font (size 0.7 0.7) (thickness 0.15)) (justify left bottom mirror))
    )
    (fp_text user "Author: Antmicro" (at -0.95 -4.169 270) (layer "B.Fab") hide
        (effects (font (size 0.7 0.7) (thickness 0.15)) (justify left bottom mirror))
    )
    (fp_text user "License: Apache-2.0" (at -0.95 -5.169 270) (layer "B.Fab") hide
        (effects (font (size 0.7 0.7) (thickness 0.15)) (justify left bottom mirror))
    )
    (fp_text user "${REFERENCE}" (at -0.95 -3.168 270) (layer "B.Fab") hide
        (effects (font (size 0.7 0.7) (thickness 0.15)) (justify left bottom mirror))
    )
    (fp_rect (start -0.925 0.47) (end 0.925 -0.47)
      (stroke (width 0.05) (type default)) (fill none) (layer "B.CrtYd"))
    (fp_rect (start -0.5 0.25) (end 0.5 -0.25)
      (stroke (width 0.15) (type solid)) (fill none) (layer "B.Fab"))
    (pad "1" smd roundrect (at -0.48 0 90) (size 0.59 0.64) (layers "B.Cu" "B.Paste" "B.Mask") (roundrect_rratio 0.25)
      (net 191 "Net-(U4C-DPSRC_RBIAS)") (pintype "passive"))
    (pad "2" smd roundrect (at 0.48 0 90) (size 0.59 0.64) (layers "B.Cu" "B.Paste" "B.Mask") (roundrect_rratio 0.25)
      (net 1 "GND") (pintype "passive"))
  )

  (footprint "antmicro-footprints:R_0402_1005Metric" (layer "B.Cu")
    (at 135.175 70.72 90)
    (descr "Resistor SMD 0402")
    (tags "resistor SMD 0402")
    (property "Author" "Antmicro")
    (property "License" "Apache-2.0")
    (property "MPN" "CR0402-FX-1003GLF")
    (property "Manufacturer" "Bourns")
    (property "Sheetfile" "tb.kicad_sch")
    (property "Sheetname" "TB Controller")
    (property "Tolerance" "1%")
    (property "Val" "100k")
    (property "ki_description" "SMD Chip Resistor, 100 kohm, ± 1%, 62.5 mW, 0402 [1005 Metric], Thick Film, General Purpose")
    (property "ki_keywords" "0402, SMT, RESISTOR, PASSIVE")
    (attr smd)
    (fp_text reference "R72" (at -1.035 0.434 270) (layer "B.SilkS")
        (effects (font (size 0.7 0.7) (thickness 0.15)) (justify left bottom mirror))
    )
    (fp_text value "R_100k_0402" (at -1.011843 -1.772047 270) (layer "B.Fab")
        (effects (font (size 0.7 0.7) (thickness 0.15)) (justify left bottom mirror))
    )
    (fp_text user "License: Apache-2.0" (at -0.95 -5.169 270) (layer "B.Fab") hide
        (effects (font (size 0.7 0.7) (thickness 0.15)) (justify left bottom mirror))
    )
    (fp_text user "${REFERENCE}" (at -0.95 -3.168 270) (layer "B.Fab") hide
        (effects (font (size 0.7 0.7) (thickness 0.15)) (justify left bottom mirror))
    )
    (fp_text user "Author: Antmicro" (at -0.95 -4.169 270) (layer "B.Fab") hide
        (effects (font (size 0.7 0.7) (thickness 0.15)) (justify left bottom mirror))
    )
    (fp_rect (start -0.925 0.47) (end 0.925 -0.47)
      (stroke (width 0.05) (type default)) (fill none) (layer "B.CrtYd"))
    (fp_rect (start -0.5 0.25) (end 0.5 -0.25)
      (stroke (width 0.15) (type solid)) (fill none) (layer "B.Fab"))
    (pad "1" smd roundrect (at -0.48 0 90) (size 0.59 0.64) (layers "B.Cu" "B.Paste" "B.Mask") (roundrect_rratio 0.25)
      (net 187 "Net-(U4E-PB_DPSRC_HPD)") (pintype "passive"))
    (pad "2" smd roundrect (at 0.48 0 90) (size 0.59 0.64) (layers "B.Cu" "B.Paste" "B.Mask") (roundrect_rratio 0.25)
      (net 1 "GND") (pintype "passive"))
  )

  (footprint "antmicro-footprints:C_0402_1005Metric" (layer "B.Cu")
    (at 132.85 82.125)
    (descr "Capacitor SMD 0402")
    (tags "capacitor SMD 0402")
    (property "Author" "Antmicro")
    (property "Dielectric" "")
    (property "License" "Apache-2.0")
    (property "MPN" "C1005X6S1A105K050BC")
    (property "Manufacturer" "TDK")
    (property "Sheetfile" "tb-power.kicad_sch")
    (property "Sheetname" "Thunderbolt Controller - Power")
    (property "Val" "1u")
    (property "Voltage" "")
    (property "ki_description" "SMD Multilayer Ceramic Capacitor, 1 µF, 10 V, 0402 [1005 Metric], ± 10%, X6S, C")
    (property "ki_keywords" "0402, SMT, CAPACITOR, PASSIVE, CERAMIC, MLCC")
    (attr smd)
    (fp_text reference "C51" (at 17.518 7.41 180) (layer "B.SilkS")
        (effects (font (size 0.7 0.7) (thickness 0.15)) (justify left bottom mirror))
    )
    (fp_text value "C_1u_0402" (at -1.022927 -2.155213 180) (layer "B.Fab")
        (effects (font (size 0.7 0.7) (thickness 0.15)) (justify left bottom mirror))
    )
    (fp_text user "Author: Antmicro" (at -0.939 -3.399 180) (layer "B.Fab") hide
        (effects (font (size 0.7 0.7) (thickness 0.15)) (justify left bottom mirror))
    )
    (fp_text user "License: Apache-2.0" (at -0.939 -5.799 180) (layer "B.Fab") hide
        (effects (font (size 0.7 0.7) (thickness 0.15)) (justify left bottom mirror))
    )
    (fp_text user "${REFERENCE}" (at -0.939 -4.599 180) (layer "B.Fab") hide
        (effects (font (size 0.7 0.7) (thickness 0.15)) (justify left bottom mirror))
    )
    (fp_rect (start -0.925 0.47) (end 0.925 -0.47)
      (stroke (width 0.05) (type default)) (fill none) (layer "B.CrtYd"))
    (fp_line (start -0.494 -0.248) (end -0.494 0.25)
      (stroke (width 0.15) (type solid)) (layer "B.Fab"))
    (fp_line (start -0.494 0.25) (end 0.504 0.25)
      (stroke (width 0.15) (type solid)) (layer "B.Fab"))
    (fp_line (start 0.504 -0.248) (end -0.494 -0.248)
      (stroke (width 0.15) (type solid)) (layer "B.Fab"))
    (fp_line (start 0.504 0.25) (end 0.504 -0.248)
      (stroke (width 0.15) (type solid)) (layer "B.Fab"))
    (pad "1" smd roundrect (at -0.48 0) (size 0.59 0.64) (layers "B.Cu" "B.Paste" "B.Mask") (roundrect_rratio 0.25)
      (net 1 "GND") (pintype "passive"))
    (pad "2" smd roundrect (at 0.48 0) (size 0.59 0.64) (layers "B.Cu" "B.Paste" "B.Mask") (roundrect_rratio 0.25)
      (net 105 "Net-(C51-Pad2)") (pintype "passive"))
  )

  (footprint "antmicro-footprints:R_0402_1005Metric" (layer "B.Cu")
    (at 131.075 66.82 -90)
    (descr "Resistor SMD 0402")
    (tags "resistor SMD 0402")
    (property "Author" "Antmicro")
    (property "License" "Apache-2.0")
    (property "MPN" "CR0402-FX-2201GLF")
    (property "Manufacturer" "Bourns")
    (property "Sheetfile" "tb.kicad_sch")
    (property "Sheetname" "TB Controller")
    (property "Tolerance" "1%")
    (property "Val" "2k2")
    (property "ki_description" "SMD Chip Resistor, 2.2 kohm, ± 1%, 62.5 mW, 0402 [1005 Metric], Thick Film, General Purpose")
    (property "ki_keywords" "0402, SMT, RESISTOR, PASSIVE")
    (attr smd)
    (fp_text reference "R58" (at -3.066 -0.325 90) (layer "B.SilkS")
        (effects (font (size 0.7 0.7) (thickness 0.15)) (justify left bottom mirror))
    )
    (fp_text value "R_2k2_0402" (at -1.011843 -1.772047 90) (layer "B.Fab")
        (effects (font (size 0.7 0.7) (thickness 0.15)) (justify left bottom mirror))
    )
    (fp_text user "Author: Antmicro" (at -0.95 -4.169 90) (layer "B.Fab") hide
        (effects (font (size 0.7 0.7) (thickness 0.15)) (justify left bottom mirror))
    )
    (fp_text user "${REFERENCE}" (at -0.95 -3.168 90) (layer "B.Fab") hide
        (effects (font (size 0.7 0.7) (thickness 0.15)) (justify left bottom mirror))
    )
    (fp_text user "License: Apache-2.0" (at -0.95 -5.169 90) (layer "B.Fab") hide
        (effects (font (size 0.7 0.7) (thickness 0.15)) (justify left bottom mirror))
    )
    (fp_rect (start -0.925 0.47) (end 0.925 -0.47)
      (stroke (width 0.05) (type default)) (fill none) (layer "B.CrtYd"))
    (fp_rect (start -0.5 0.25) (end 0.5 -0.25)
      (stroke (width 0.15) (type solid)) (fill none) (layer "B.Fab"))
    (pad "1" smd roundrect (at -0.48 0 270) (size 0.59 0.64) (layers "B.Cu" "B.Paste" "B.Mask") (roundrect_rratio 0.25)
      (net 1 "GND") (pintype "passive"))
    (pad "2" smd roundrect (at 0.48 0 270) (size 0.59 0.64) (layers "B.Cu" "B.Paste" "B.Mask") (roundrect_rratio 0.25)
      (net 172 "Net-(U4C-DPSNK0_DDC_CLK)") (pintype "passive"))
  )

  (footprint "antmicro-footprints:C_0402_1005Metric" (layer "B.Cu")
    (at 137.225 81.3 90)
    (descr "Capacitor SMD 0402")
    (tags "capacitor SMD 0402")
    (property "Author" "Antmicro")
    (property "Dielectric" "")
    (property "License" "Apache-2.0")
    (property "MPN" "C1005X6S1A105K050BC")
    (property "Manufacturer" "TDK")
    (property "Sheetfile" "tb-power.kicad_sch")
    (property "Sheetname" "Thunderbolt Controller - Power")
    (property "Val" "1u")
    (property "Voltage" "")
    (property "ki_description" "SMD Multilayer Ceramic Capacitor, 1 µF, 10 V, 0402 [1005 Metric], ± 10%, X6S, C")
    (property "ki_keywords" "0402, SMT, CAPACITOR, PASSIVE, CERAMIC, MLCC")
    (attr smd)
    (fp_text reference "C87" (at -6.584 16.953 270) (layer "B.SilkS")
        (effects (font (size 0.7 0.7) (thickness 0.15)) (justify left bottom mirror))
    )
    (fp_text value "C_1u_0402" (at -1.022927 -2.155213 270) (layer "B.Fab")
        (effects (font (size 0.7 0.7) (thickness 0.15)) (justify left bottom mirror))
    )
    (fp_text user "${REFERENCE}" (at -0.939 -4.599 270) (layer "B.Fab") hide
        (effects (font (size 0.7 0.7) (thickness 0.15)) (justify left bottom mirror))
    )
    (fp_text user "Author: Antmicro" (at -0.939 -3.399 270) (layer "B.Fab") hide
        (effects (font (size 0.7 0.7) (thickness 0.15)) (justify left bottom mirror))
    )
    (fp_text user "License: Apache-2.0" (at -0.939 -5.799 270) (layer "B.Fab") hide
        (effects (font (size 0.7 0.7) (thickness 0.15)) (justify left bottom mirror))
    )
    (fp_rect (start -0.925 0.47) (end 0.925 -0.47)
      (stroke (width 0.05) (type default)) (fill none) (layer "B.CrtYd"))
    (fp_line (start -0.494 -0.248) (end -0.494 0.25)
      (stroke (width 0.15) (type solid)) (layer "B.Fab"))
    (fp_line (start -0.494 0.25) (end 0.504 0.25)
      (stroke (width 0.15) (type solid)) (layer "B.Fab"))
    (fp_line (start 0.504 -0.248) (end -0.494 -0.248)
      (stroke (width 0.15) (type solid)) (layer "B.Fab"))
    (fp_line (start 0.504 0.25) (end 0.504 -0.248)
      (stroke (width 0.15) (type solid)) (layer "B.Fab"))
    (pad "1" smd roundrect (at -0.48 0 90) (size 0.59 0.64) (layers "B.Cu" "B.Paste" "B.Mask") (roundrect_rratio 0.25)
      (net 1 "GND") (pintype "passive"))
    (pad "2" smd roundrect (at 0.48 0 90) (size 0.59 0.64) (layers "B.Cu" "B.Paste" "B.Mask") (roundrect_rratio 0.25)
      (net 112 "Net-(U4A-VCC0P9_SVR_SENSE)") (pintype "passive"))
  )

  (footprint "antmicro-footprints:C_0402_1005Metric" (layer "B.Cu")
    (at 137.725 79.85 180)
    (descr "Capacitor SMD 0402")
    (tags "capacitor SMD 0402")
    (property "Author" "Antmicro")
    (property "Dielectric" "")
    (property "License" "Apache-2.0")
    (property "MPN" "C1005X6S1A105K050BC")
    (property "Manufacturer" "TDK")
    (property "Sheetfile" "tb-power.kicad_sch")
    (property "Sheetname" "Thunderbolt Controller - Power")
    (property "Val" "1u")
    (property "Voltage" "")
    (property "ki_description" "SMD Multilayer Ceramic Capacitor, 1 µF, 10 V, 0402 [1005 Metric], ± 10%, X6S, C")
    (property "ki_keywords" "0402, SMT, CAPACITOR, PASSIVE, CERAMIC, MLCC")
    (attr smd)
    (fp_text reference "C85" (at -17.596 -8.034) (layer "B.SilkS")
        (effects (font (size 0.7 0.7) (thickness 0.15)) (justify left bottom mirror))
    )
    (fp_text value "C_1u_0402" (at -1.022927 -2.155213) (layer "B.Fab")
        (effects (font (size 0.7 0.7) (thickness 0.15)) (justify left bottom mirror))
    )
    (fp_text user "License: Apache-2.0" (at -0.939 -5.799) (layer "B.Fab") hide
        (effects (font (size 0.7 0.7) (thickness 0.15)) (justify left bottom mirror))
    )
    (fp_text user "${REFERENCE}" (at -0.939 -4.599) (layer "B.Fab") hide
        (effects (font (size 0.7 0.7) (thickness 0.15)) (justify left bottom mirror))
    )
    (fp_text user "Author: Antmicro" (at -0.939 -3.399) (layer "B.Fab") hide
        (effects (font (size 0.7 0.7) (thickness 0.15)) (justify left bottom mirror))
    )
    (fp_rect (start -0.925 0.47) (end 0.925 -0.47)
      (stroke (width 0.05) (type default)) (fill none) (layer "B.CrtYd"))
    (fp_line (start -0.494 -0.248) (end -0.494 0.25)
      (stroke (width 0.15) (type solid)) (layer "B.Fab"))
    (fp_line (start -0.494 0.25) (end 0.504 0.25)
      (stroke (width 0.15) (type solid)) (layer "B.Fab"))
    (fp_line (start 0.504 -0.248) (end -0.494 -0.248)
      (stroke (width 0.15) (type solid)) (layer "B.Fab"))
    (fp_line (start 0.504 0.25) (end 0.504 -0.248)
      (stroke (width 0.15) (type solid)) (layer "B.Fab"))
    (pad "1" smd roundrect (at -0.48 0 180) (size 0.59 0.64) (layers "B.Cu" "B.Paste" "B.Mask") (roundrect_rratio 0.25)
      (net 1 "GND") (pintype "passive"))
    (pad "2" smd roundrect (at 0.48 0 180) (size 0.59 0.64) (layers "B.Cu" "B.Paste" "B.Mask") (roundrect_rratio 0.25)
      (net 113 "Net-(U4A-VCC0P9_LVR_SENSE)") (pintype "passive"))
  )

  (footprint "antmicro-footprints:R_0402_1005Metric" (layer "B.Cu")
    (at 142.17 78.385 90)
    (descr "Resistor SMD 0402")
    (tags "resistor SMD 0402")
    (property "Author" "Antmicro")
    (property "License" "Apache-2.0")
    (property "MPN" "CR0402-FX-4990GLF")
    (property "Manufacturer" "Bourns")
    (property "Sheetfile" "tb.kicad_sch")
    (property "Sheetname" "TB Controller")
    (property "Tolerance" "1%")
    (property "Val" "499R")
    (property "ki_description" "SMD Chip Resistor, 499 ohm, ± 1%, 63 mW, 0402 [1005 Metric], Thick Film, General Purpose")
    (property "ki_keywords" "0402, SMT, RESISTOR, PASSIVE")
    (attr smd)
    (fp_text reference "R73" (at -0.99 0.451 270) (layer "B.SilkS")
        (effects (font (size 0.7 0.7) (thickness 0.15)) (justify left bottom mirror))
    )
    (fp_text value "R_499R_0402" (at -1.011843 -1.772047 270) (layer "B.Fab")
        (effects (font (size 0.7 0.7) (thickness 0.15)) (justify left bottom mirror))
    )
    (fp_text user "License: Apache-2.0" (at -0.95 -5.169 270) (layer "B.Fab") hide
        (effects (font (size 0.7 0.7) (thickness 0.15)) (justify left bottom mirror))
    )
    (fp_text user "Author: Antmicro" (at -0.95 -4.169 270) (layer "B.Fab") hide
        (effects (font (size 0.7 0.7) (thickness 0.15)) (justify left bottom mirror))
    )
    (fp_text user "${REFERENCE}" (at -0.95 -3.168 270) (layer "B.Fab") hide
        (effects (font (size 0.7 0.7) (thickness 0.15)) (justify left bottom mirror))
    )
    (fp_rect (start -0.925 0.47) (end 0.925 -0.47)
      (stroke (width 0.05) (type default)) (fill none) (layer "B.CrtYd"))
    (fp_rect (start -0.5 0.25) (end 0.5 -0.25)
      (stroke (width 0.15) (type solid)) (fill none) (layer "B.Fab"))
    (pad "1" smd roundrect (at -0.48 0 90) (size 0.59 0.64) (layers "B.Cu" "B.Paste" "B.Mask") (roundrect_rratio 0.25)
      (net 188 "Net-(U4E-PB_USB2_RBIAS)") (pintype "passive"))
    (pad "2" smd roundrect (at 0.48 0 90) (size 0.59 0.64) (layers "B.Cu" "B.Paste" "B.Mask") (roundrect_rratio 0.25)
      (net 1 "GND") (pintype "passive"))
  )

  (footprint "antmicro-footprints:Fiducial_1mm_Mask3mm" (layer "B.Cu")
    (at 168 59 180)
    (descr "Circular Fiducial, 1.5mm bare copper, 3mm soldermask opening")
    (tags "fiducial")
    (property "Author" "Antmicro")
    (property "License" "Apache-2.0")
    (property "Sheetfile" "thunderbolt-pcie-adapter.kicad_sch")
    (property "Sheetname" "")
    (property "exclude_from_bom" "")
    (property "ki_description" "Fiducial mask")
    (attr through_hole exclude_from_bom)
    (fp_text reference "FID7" (at -1.291 -2.595) (layer "B.SilkS")
        (effects (font (size 0.7 0.7) (thickness 0.15)) (justify left bottom mirror))
    )
    (fp_text value "Fiducial_1mm_Mask3mm" (at 0 -2.603) (layer "B.Fab")
        (effects (font (size 0.7 0.7) (thickness 0.15)) (justify left bottom mirror))
    )
    (fp_text user "${REFERENCE}" (at -1.25 -4.603) (layer "B.Fab") hide
        (effects (font (size 0.7 0.7) (thickness 0.15)) (justify left bottom mirror))
    )
    (fp_text user "License: Apache-2.0" (at -1.25 -7.003) (layer "B.Fab") hide
        (effects (font (size 0.7 0.7) (thickness 0.15)) (justify left bottom mirror))
    )
    (fp_text user "Author: Antmicro" (at -1.25 -5.803) (layer "B.Fab") hide
        (effects (font (size 0.7 0.7) (thickness 0.15)) (justify left bottom mirror))
    )
    (fp_circle (center 0 0) (end 1.5 0)
      (stroke (width 0.05) (type solid)) (fill none) (layer "B.CrtYd"))
    (fp_circle (center 0 0) (end 1.5 0)
      (stroke (width 0.15) (type solid)) (fill none) (layer "B.Fab"))
    (pad "" smd circle (at 0 0 180) (size 1 1) (layers "B.Cu" "B.Mask")
      (solder_mask_margin 1) (clearance 1))
  )

  (footprint "antmicro-footprints:R_0402_1005Metric" (layer "B.Cu")
    (at 145.62 73.96 180)
    (descr "Resistor SMD 0402")
    (tags "resistor SMD 0402")
    (property "Author" "Antmicro")
    (property "License" "Apache-2.0")
    (property "MPN" "CR0402-FX-1004GLF")
    (property "Manufacturer" "Bourns")
    (property "Sheetfile" "tb.kicad_sch")
    (property "Sheetname" "TB Controller")
    (property "Tolerance" "1%")
    (property "Val" "1M")
    (property "ki_description" "SMD Chip Resistor, 1 Mohm, ± 1%, 62.5 mW, 0402 [1005 Metric], Thick Film, General Purpose")
    (property "ki_keywords" "0402, SMT, RESISTOR, PASSIVE")
    (attr smd)
    (fp_text reference "R70" (at -3.097 -0.462) (layer "B.SilkS")
        (effects (font (size 0.7 0.7) (thickness 0.15)) (justify left bottom mirror))
    )
    (fp_text value "R_1M_0402" (at -1.011843 -1.772047) (layer "B.Fab")
        (effects (font (size 0.7 0.7) (thickness 0.15)) (justify left bottom mirror))
    )
    (fp_text user "${REFERENCE}" (at -0.95 -3.168) (layer "B.Fab") hide
        (effects (font (size 0.7 0.7) (thickness 0.15)) (justify left bottom mirror))
    )
    (fp_text user "Author: Antmicro" (at -0.95 -4.169) (layer "B.Fab") hide
        (effects (font (size 0.7 0.7) (thickness 0.15)) (justify left bottom mirror))
    )
    (fp_text user "License: Apache-2.0" (at -0.95 -5.169) (layer "B.Fab") hide
        (effects (font (size 0.7 0.7) (thickness 0.15)) (justify left bottom mirror))
    )
    (fp_rect (start -0.925 0.47) (end 0.925 -0.47)
      (stroke (width 0.05) (type default)) (fill none) (layer "B.CrtYd"))
    (fp_rect (start -0.5 0.25) (end 0.5 -0.25)
      (stroke (width 0.15) (type solid)) (fill none) (layer "B.Fab"))
    (pad "1" smd roundrect (at -0.48 0 180) (size 0.59 0.64) (layers "B.Cu" "B.Paste" "B.Mask") (roundrect_rratio 0.25)
      (net 185 "Net-(U4E-PB_LSTX)") (pintype "passive"))
    (pad "2" smd roundrect (at 0.48 0 180) (size 0.59 0.64) (layers "B.Cu" "B.Paste" "B.Mask") (roundrect_rratio 0.25)
      (net 1 "GND") (pintype "passive"))
  )

  (footprint "antmicro-footprints:R_0402_1005Metric" (layer "B.Cu")
    (at 151.41 60.97)
    (descr "Resistor SMD 0402")
    (tags "resistor SMD 0402")
    (property "Author" "Antmicro")
    (property "License" "Apache-2.0")
    (property "MPN" "CR0402-FX-2201GLF")
    (property "Manufacturer" "Bourns")
    (property "Sheetfile" "power.kicad_sch")
    (property "Sheetname" "Power")
    (property "Tolerance" "1%")
    (property "Val" "2k2")
    (property "ki_description" "SMD Chip Resistor, 2.2 kohm, ± 1%, 62.5 mW, 0402 [1005 Metric], Thick Film, General Purpose")
    (property "ki_keywords" "0402, SMT, RESISTOR, PASSIVE")
    (attr smd)
    (fp_text reference "R3" (at -0.915 0.482 180) (layer "B.SilkS")
        (effects (font (size 0.7 0.7) (thickness 0.15)) (justify left bottom mirror))
    )
    (fp_text value "R_2k2_0402" (at -1.011843 -1.772047 180) (layer "B.Fab")
        (effects (font (size 0.7 0.7) (thickness 0.15)) (justify left bottom mirror))
    )
    (fp_text user "License: Apache-2.0" (at -0.95 -5.169 180) (layer "B.Fab") hide
        (effects (font (size 0.7 0.7) (thickness 0.15)) (justify left bottom mirror))
    )
    (fp_text user "${REFERENCE}" (at -0.95 -3.168 180) (layer "B.Fab") hide
        (effects (font (size 0.7 0.7) (thickness 0.15)) (justify left bottom mirror))
    )
    (fp_text user "Author: Antmicro" (at -0.95 -4.169 180) (layer "B.Fab") hide
        (effects (font (size 0.7 0.7) (thickness 0.15)) (justify left bottom mirror))
    )
    (fp_rect (start -0.925 0.47) (end 0.925 -0.47)
      (stroke (width 0.05) (type default)) (fill none) (layer "B.CrtYd"))
    (fp_rect (start -0.5 0.25) (end 0.5 -0.25)
      (stroke (width 0.15) (type solid)) (fill none) (layer "B.Fab"))
    (pad "1" smd roundrect (at -0.48 0) (size 0.59 0.64) (layers "B.Cu" "B.Paste" "B.Mask") (roundrect_rratio 0.25)
      (net 57 "I2C1_SCL") (pintype "passive"))
    (pad "2" smd roundrect (at 0.48 0) (size 0.59 0.64) (layers "B.Cu" "B.Paste" "B.Mask") (roundrect_rratio 0.25)
      (net 2 "3V3_SYS") (pintype "passive"))
  )

  (footprint "antmicro-footprints:C_0402_1005Metric" (layer "B.Cu")
    (at 153.41 62.97 180)
    (descr "Capacitor SMD 0402")
    (tags "capacitor SMD 0402")
    (property "Author" "Antmicro")
    (property "Dielectric" "")
    (property "License" "Apache-2.0")
    (property "MPN" "CC0402MRX5R5BB106")
    (property "Manufacturer" "YAGEO")
    (property "Sheetfile" "power.kicad_sch")
    (property "Sheetname" "Power")
    (property "Val" "10u")
    (property "Voltage" "")
    (property "ki_description" "SMD Multilayer Ceramic Capacitor, 10 µF, 6.3 V, 0402 [1005 Metric], ± 20%, X5R, CC Series")
    (property "ki_keywords" "0402, SMT, CAPACITOR, PASSIVE, MLCC, CERAMIC")
    (attr smd)
    (fp_text reference "C39" (at -0.768 -4.467) (layer "B.SilkS")
        (effects (font (size 0.7 0.7) (thickness 0.15)) (justify left bottom mirror))
    )
    (fp_text value "C_10u_0402" (at -1.022927 -2.155213) (layer "B.Fab")
        (effects (font (size 0.7 0.7) (thickness 0.15)) (justify left bottom mirror))
    )
    (fp_text user "Author: Antmicro" (at -0.939 -3.399) (layer "B.Fab") hide
        (effects (font (size 0.7 0.7) (thickness 0.15)) (justify left bottom mirror))
    )
    (fp_text user "${REFERENCE}" (at -0.939 -4.599) (layer "B.Fab") hide
        (effects (font (size 0.7 0.7) (thickness 0.15)) (justify left bottom mirror))
    )
    (fp_text user "License: Apache-2.0" (at -0.939 -5.799) (layer "B.Fab") hide
        (effects (font (size 0.7 0.7) (thickness 0.15)) (justify left bottom mirror))
    )
    (fp_rect (start -0.925 0.47) (end 0.925 -0.47)
      (stroke (width 0.05) (type default)) (fill none) (layer "B.CrtYd"))
    (fp_line (start -0.494 -0.248) (end -0.494 0.25)
      (stroke (width 0.15) (type solid)) (layer "B.Fab"))
    (fp_line (start -0.494 0.25) (end 0.504 0.25)
      (stroke (width 0.15) (type solid)) (layer "B.Fab"))
    (fp_line (start 0.504 -0.248) (end -0.494 -0.248)
      (stroke (width 0.15) (type solid)) (layer "B.Fab"))
    (fp_line (start 0.504 0.25) (end 0.504 -0.248)
      (stroke (width 0.15) (type solid)) (layer "B.Fab"))
    (pad "1" smd roundrect (at -0.48 0 180) (size 0.59 0.64) (layers "B.Cu" "B.Paste" "B.Mask") (roundrect_rratio 0.25)
      (net 9 "/Power/TPS_3V3") (pintype "passive"))
    (pad "2" smd roundrect (at 0.48 0 180) (size 0.59 0.64) (layers "B.Cu" "B.Paste" "B.Mask") (roundrect_rratio 0.25)
      (net 1 "GND") (pintype "passive"))
  )

  (footprint "antmicro-footprints:R_0402_1005Metric" (layer "B.Cu")
    (at 140.34 61.03 -90)
    (descr "Resistor SMD 0402")
    (tags "resistor SMD 0402")
    (property "Author" "Antmicro")
    (property "License" "Apache-2.0")
    (property "MPN" "CR0402-FX-3301GLF")
    (property "Manufacturer" "Bourns")
    (property "Sheetfile" "tb.kicad_sch")
    (property "Sheetname" "TB Controller")
    (property "Tolerance" "1%")
    (property "Val" "3k3")
    (property "ki_description" "SMD Chip Resistor, 3.3 kohm, ± 1%, 63 mW, 0402 [1005 Metric], Thick Film, General Purpose")
    (property "ki_keywords" "0402, SMT, RESISTOR, PASSIVE")
    (attr smd)
    (fp_text reference "R53" (at -1.086 -1.392 90) (layer "B.SilkS")
        (effects (font (size 0.7 0.7) (thickness 0.15)) (justify left bottom mirror))
    )
    (fp_text value "R_3k3_0402" (at -1.011843 -1.772047 90) (layer "B.Fab")
        (effects (font (size 0.7 0.7) (thickness 0.15)) (justify left bottom mirror))
    )
    (fp_text user "${REFERENCE}" (at -0.95 -3.168 90) (layer "B.Fab") hide
        (effects (font (size 0.7 0.7) (thickness 0.15)) (justify left bottom mirror))
    )
    (fp_text user "Author: Antmicro" (at -0.95 -4.169 90) (layer "B.Fab") hide
        (effects (font (size 0.7 0.7) (thickness 0.15)) (justify left bottom mirror))
    )
    (fp_text user "License: Apache-2.0" (at -0.95 -5.169 90) (layer "B.Fab") hide
        (effects (font (size 0.7 0.7) (thickness 0.15)) (justify left bottom mirror))
    )
    (fp_rect (start -0.925 0.47) (end 0.925 -0.47)
      (stroke (width 0.05) (type default)) (fill none) (layer "B.CrtYd"))
    (fp_rect (start -0.5 0.25) (end 0.5 -0.25)
      (stroke (width 0.15) (type solid)) (fill none) (layer "B.Fab"))
    (pad "1" smd roundrect (at -0.48 0 270) (size 0.59 0.64) (layers "B.Cu" "B.Paste" "B.Mask") (roundrect_rratio 0.25)
      (net 2 "3V3_SYS") (pintype "passive"))
    (pad "2" smd roundrect (at 0.48 0 270) (size 0.59 0.64) (layers "B.Cu" "B.Paste" "B.Mask") (roundrect_rratio 0.25)
      (net 89 "/TB Controller/FLASH_HOLD") (pintype "passive"))
  )

  (footprint "antmicro-footprints:R_0402_1005Metric" (layer "B.Cu")
    (at 111.715 83.68)
    (descr "Resistor SMD 0402")
    (tags "resistor SMD 0402")
    (property "Author" "Antmicro")
    (property "License" "Apache-2.0")
    (property "MPN" "CR0402-FX-1003GLF")
    (property "Manufacturer" "Bourns")
    (property "Sheetfile" "power.kicad_sch")
    (property "Sheetname" "Power")
    (property "Tolerance" "1%")
    (property "Val" "100k")
    (property "dnp" "")
    (property "ki_description" "SMD Chip Resistor, 100 kohm, ± 1%, 62.5 mW, 0402 [1005 Metric], Thick Film, General Purpose")
    (property "ki_keywords" "0402, SMT, RESISTOR, PASSIVE")
    (attr smd)
    (fp_text reference "R24" (at 1.061 -4.686 180) (layer "B.SilkS")
        (effects (font (size 0.7 0.7) (thickness 0.15)) (justify left bottom mirror))
    )
    (fp_text value "R_100k_0402" (at -1.011843 -1.772047 180) (layer "B.Fab")
        (effects (font (size 0.7 0.7) (thickness 0.15)) (justify left bottom mirror))
    )
    (fp_text user "Author: Antmicro" (at -0.95 -4.169 180) (layer "B.Fab") hide
        (effects (font (size 0.7 0.7) (thickness 0.15)) (justify left bottom mirror))
    )
    (fp_text user "${REFERENCE}" (at -0.95 -3.168 180) (layer "B.Fab") hide
        (effects (font (size 0.7 0.7) (thickness 0.15)) (justify left bottom mirror))
    )
    (fp_text user "License: Apache-2.0" (at -0.95 -5.169 180) (layer "B.Fab") hide
        (effects (font (size 0.7 0.7) (thickness 0.15)) (justify left bottom mirror))
    )
    (fp_rect (start -0.925 0.47) (end 0.925 -0.47)
      (stroke (width 0.05) (type default)) (fill none) (layer "B.CrtYd"))
    (fp_rect (start -0.5 0.25) (end 0.5 -0.25)
      (stroke (width 0.15) (type solid)) (fill none) (layer "B.Fab"))
    (pad "1" smd roundrect (at -0.48 0) (size 0.59 0.64) (layers "B.Cu" "B.Paste" "B.Mask") (roundrect_rratio 0.25)
      (net 1 "GND") (pintype "passive"))
    (pad "2" smd roundrect (at 0.48 0) (size 0.59 0.64) (layers "B.Cu" "B.Paste" "B.Mask") (roundrect_rratio 0.25)
      (net 159 "Net-(U1-SYNC{slash}MODE)") (pintype "passive"))
  )

  (footprint "antmicro-footprints:C_0402_1005Metric" (layer "B.Cu")
    (at 154.91 59.47 90)
    (descr "Capacitor SMD 0402")
    (tags "capacitor SMD 0402")
    (property "Author" "Antmicro")
    (property "Dielectric" "")
    (property "License" "Apache-2.0")
    (property "MPN" "C1005X5R1A225K050BC")
    (property "Manufacturer" "TDK")
    (property "Sheetfile" "power.kicad_sch")
    (property "Sheetname" "Power")
    (property "Val" "2u2")
    (property "Voltage" "")
    (property "ki_description" "SMD Multilayer Ceramic Capacitor, 2.2 µF, 10 V, 0402 [1005 Metric], ± 10%, X5R, C")
    (property "ki_keywords" "0402, SMT, CAPACITOR, PASSIVE, CERAMIC, MLCC")
    (attr smd)
    (fp_text reference "C36" (at 4.86 -5.558 270) (layer "B.SilkS")
        (effects (font (size 0.7 0.7) (thickness 0.15)) (justify left bottom mirror))
    )
    (fp_text value "C_2u2_0402" (at -1.022927 -2.155213 270) (layer "B.Fab")
        (effects (font (size 0.7 0.7) (thickness 0.15)) (justify left bottom mirror))
    )
    (fp_text user "Author: Antmicro" (at -0.939 -3.399 270) (layer "B.Fab") hide
        (effects (font (size 0.7 0.7) (thickness 0.15)) (justify left bottom mirror))
    )
    (fp_text user "${REFERENCE}" (at -0.939 -4.599 270) (layer "B.Fab") hide
        (effects (font (size 0.7 0.7) (thickness 0.15)) (justify left bottom mirror))
    )
    (fp_text user "License: Apache-2.0" (at -0.939 -5.799 270) (layer "B.Fab") hide
        (effects (font (size 0.7 0.7) (thickness 0.15)) (justify left bottom mirror))
    )
    (fp_rect (start -0.925 0.47) (end 0.925 -0.47)
      (stroke (width 0.05) (type default)) (fill none) (layer "B.CrtYd"))
    (fp_line (start -0.494 -0.248) (end -0.494 0.25)
      (stroke (width 0.15) (type solid)) (layer "B.Fab"))
    (fp_line (start -0.494 0.25) (end 0.504 0.25)
      (stroke (width 0.15) (type solid)) (layer "B.Fab"))
    (fp_line (start 0.504 -0.248) (end -0.494 -0.248)
      (stroke (width 0.15) (type solid)) (layer "B.Fab"))
    (fp_line (start 0.504 0.25) (end 0.504 -0.248)
      (stroke (width 0.15) (type solid)) (layer "B.Fab"))
    (pad "1" smd roundrect (at -0.48 0 90) (size 0.59 0.64) (layers "B.Cu" "B.Paste" "B.Mask") (roundrect_rratio 0.25)
      (net 103 "Net-(U3-LDO_1V8D)") (pintype "passive"))
    (pad "2" smd roundrect (at 0.48 0 90) (size 0.59 0.64) (layers "B.Cu" "B.Paste" "B.Mask") (roundrect_rratio 0.25)
      (net 1 "GND") (pintype "passive"))
  )

  (footprint "antmicro-footprints:C_0402_1005Metric" (layer "B.Cu")
    (at 141.15 74.482 -90)
    (descr "Capacitor SMD 0402")
    (tags "capacitor SMD 0402")
    (property "Author" "Antmicro")
    (property "Dielectric" "X5R")
    (property "License" "Apache-2.0")
    (property "MPN" "GRM155R61H104KE14D")
    (property "Manufacturer" "Murata")
    (property "Sheetfile" "tb-power.kicad_sch")
    (property "Sheetname" "Thunderbolt Controller - Power")
    (property "Val" "100n")
    (property "Voltage" "50V")
    (property "ki_description" "SMD Multilayer Ceramic Capacitor, 0.1 µF, 50 V, 0402 [1005 Metric], ± 10%, X5R, GRM Series")
    (property "ki_keywords" "0402, SMT, CAPACITOR, PASSIVE, CERAMIC, MLCC")
    (attr smd)
    (fp_text reference "C91" (at -5.521 -1.471 90) (layer "B.SilkS")
        (effects (font (size 0.7 0.7) (thickness 0.15)) (justify left bottom mirror))
    )
    (fp_text value "C_100n_0402" (at -1.022927 -2.155213 90) (layer "B.Fab")
        (effects (font (size 0.7 0.7) (thickness 0.15)) (justify left bottom mirror))
    )
    (fp_text user "${REFERENCE}" (at -0.939 -4.599 90) (layer "B.Fab") hide
        (effects (font (size 0.7 0.7) (thickness 0.15)) (justify left bottom mirror))
    )
    (fp_text user "License: Apache-2.0" (at -0.939 -5.799 90) (layer "B.Fab") hide
        (effects (font (size 0.7 0.7) (thickness 0.15)) (justify left bottom mirror))
    )
    (fp_text user "Author: Antmicro" (at -0.939 -3.399 90) (layer "B.Fab") hide
        (effects (font (size 0.7 0.7) (thickness 0.15)) (justify left bottom mirror))
    )
    (fp_rect (start -0.925 0.47) (end 0.925 -0.47)
      (stroke (width 0.05) (type default)) (fill none) (layer "B.CrtYd"))
    (fp_line (start -0.494 -0.248) (end -0.494 0.25)
      (stroke (width 0.15) (type solid)) (layer "B.Fab"))
    (fp_line (start -0.494 0.25) (end 0.504 0.25)
      (stroke (width 0.15) (type solid)) (layer "B.Fab"))
    (fp_line (start 0.504 -0.248) (end -0.494 -0.248)
      (stroke (width 0.15) (type solid)) (layer "B.Fab"))
    (fp_line (start 0.504 0.25) (end 0.504 -0.248)
      (stroke (width 0.15) (type solid)) (layer "B.Fab"))
    (pad "1" smd roundrect (at -0.48 0 270) (size 0.59 0.64) (layers "B.Cu" "B.Paste" "B.Mask") (roundrect_rratio 0.25)
      (net 1 "GND") (pintype "passive"))
    (pad "2" smd roundrect (at 0.48 0 270) (size 0.59 0.64) (layers "B.Cu" "B.Paste" "B.Mask") (roundrect_rratio 0.25)
      (net 2 "3V3_SYS") (pintype "passive"))
  )

  (footprint "antmicro-footprints:R_0402_1005Metric" (layer "B.Cu")
    (at 132.1 68.77 90)
    (descr "Resistor SMD 0402")
    (tags "resistor SMD 0402")
    (property "Author" "Antmicro")
    (property "License" "Apache-2.0")
    (property "MPN" "CR0402-FX-1002GLF")
    (property "Manufacturer" "Bourns")
    (property "Sheetfile" "tb.kicad_sch")
    (property "Sheetname" "TB Controller")
    (property "Tolerance" "1%")
    (property "Val" "10k")
    (property "ki_description" "SMD Chip Resistor, 10 kohm, ± 1%, 62.5 mW, 0402 [1005 Metric], Thick Film, General Purpose")
    (property "ki_keywords" "0402, SMT, RESISTOR, PASSIVE")
    (attr smd)
    (fp_text reference "R78" (at 1.079 -2.678 270) (layer "B.SilkS")
        (effects (font (size 0.7 0.7) (thickness 0.15)) (justify left bottom mirror))
    )
    (fp_text value "R_10k_0402" (at -1.011843 -1.772047 270) (layer "B.Fab")
        (effects (font (size 0.7 0.7) (thickness 0.15)) (justify left bottom mirror))
    )
    (fp_text user "License: Apache-2.0" (at -0.95 -5.169 270) (layer "B.Fab") hide
        (effects (font (size 0.7 0.7) (thickness 0.15)) (justify left bottom mirror))
    )
    (fp_text user "${REFERENCE}" (at -0.95 -3.168 270) (layer "B.Fab") hide
        (effects (font (size 0.7 0.7) (thickness 0.15)) (justify left bottom mirror))
    )
    (fp_text user "Author: Antmicro" (at -0.95 -4.169 270) (layer "B.Fab") hide
        (effects (font (size 0.7 0.7) (thickness 0.15)) (justify left bottom mirror))
    )
    (fp_rect (start -0.925 0.47) (end 0.925 -0.47)
      (stroke (width 0.05) (type default)) (fill none) (layer "B.CrtYd"))
    (fp_rect (start -0.5 0.25) (end 0.5 -0.25)
      (stroke (width 0.15) (type solid)) (fill none) (layer "B.Fab"))
    (pad "1" smd roundrect (at -0.48 0 90) (size 0.59 0.64) (layers "B.Cu" "B.Paste" "B.Mask") (roundrect_rratio 0.25)
      (net 193 "Net-(U4C-GPIO_4)") (pintype "passive"))
    (pad "2" smd roundrect (at 0.48 0 90) (size 0.59 0.64) (layers "B.Cu" "B.Paste" "B.Mask") (roundrect_rratio 0.25)
      (net 1 "GND") (pintype "passive"))
  )

  (footprint "antmicro-footprints:Fiducial_1mm_Mask3mm" (layer "B.Cu")
    (at 102 91 180)
    (descr "Circular Fiducial, 1.5mm bare copper, 3mm soldermask opening")
    (tags "fiducial")
    (property "Author" "Antmicro")
    (property "License" "Apache-2.0")
    (property "Sheetfile" "thunderbolt-pcie-adapter.kicad_sch")
    (property "Sheetname" "")
    (property "exclude_from_bom" "")
    (property "ki_description" "Fiducial mask")
    (attr through_hole exclude_from_bom)
    (fp_text reference "FID5" (at -0.616 -2.599) (layer "B.SilkS")
        (effects (font (size 0.7 0.7) (thickness 0.15)) (justify left bottom mirror))
    )
    (fp_text value "Fiducial_1mm_Mask3mm" (at 0 -2.603) (layer "B.Fab")
        (effects (font (size 0.7 0.7) (thickness 0.15)) (justify left bottom mirror))
    )
    (fp_text user "License: Apache-2.0" (at -1.25 -7.003) (layer "B.Fab") hide
        (effects (font (size 0.7 0.7) (thickness 0.15)) (justify left bottom mirror))
    )
    (fp_text user "Author: Antmicro" (at -1.25 -5.803) (layer "B.Fab") hide
        (effects (font (size 0.7 0.7) (thickness 0.15)) (justify left bottom mirror))
    )
    (fp_text user "${REFERENCE}" (at -1.25 -4.603) (layer "B.Fab") hide
        (effects (font (size 0.7 0.7) (thickness 0.15)) (justify left bottom mirror))
    )
    (fp_circle (center 0 0) (end 1.5 0)
      (stroke (width 0.05) (type solid)) (fill none) (layer "B.CrtYd"))
    (fp_circle (center 0 0) (end 1.5 0)
      (stroke (width 0.15) (type solid)) (fill none) (layer "B.Fab"))
    (pad "" smd circle (at 0 0 180) (size 1 1) (layers "B.Cu" "B.Mask")
      (solder_mask_margin 1) (clearance 1))
  )

  (footprint "antmicro-footprints:C_0402_1005Metric" (layer "B.Cu")
    (at 130.9 77.9)
    (descr "Capacitor SMD 0402")
    (tags "capacitor SMD 0402")
    (property "Author" "Antmicro")
    (property "Dielectric" "")
    (property "License" "Apache-2.0")
    (property "MPN" "C1005X6S1A105K050BC")
    (property "Manufacturer" "TDK")
    (property "Sheetfile" "tb-power.kicad_sch")
    (property "Sheetname" "Thunderbolt Controller - Power")
    (property "Val" "1u")
    (property "Voltage" "")
    (property "ki_description" "SMD Multilayer Ceramic Capacitor, 1 µF, 10 V, 0402 [1005 Metric], ± 10%, X6S, C")
    (property "ki_keywords" "0402, SMT, CAPACITOR, PASSIVE, CERAMIC, MLCC")
    (attr smd)
    (fp_text reference "C60" (at 17.309 7.571 180) (layer "B.SilkS")
        (effects (font (size 0.7 0.7) (thickness 0.15)) (justify left bottom mirror))
    )
    (fp_text value "C_1u_0402" (at -1.022927 -2.155213 180) (layer "B.Fab")
        (effects (font (size 0.7 0.7) (thickness 0.15)) (justify left bottom mirror))
    )
    (fp_text user "${REFERENCE}" (at -0.939 -4.599 180) (layer "B.Fab") hide
        (effects (font (size 0.7 0.7) (thickness 0.15)) (justify left bottom mirror))
    )
    (fp_text user "License: Apache-2.0" (at -0.939 -5.799 180) (layer "B.Fab") hide
        (effects (font (size 0.7 0.7) (thickness 0.15)) (justify left bottom mirror))
    )
    (fp_text user "Author: Antmicro" (at -0.939 -3.399 180) (layer "B.Fab") hide
        (effects (font (size 0.7 0.7) (thickness 0.15)) (justify left bottom mirror))
    )
    (fp_rect (start -0.925 0.47) (end 0.925 -0.47)
      (stroke (width 0.05) (type default)) (fill none) (layer "B.CrtYd"))
    (fp_line (start -0.494 -0.248) (end -0.494 0.25)
      (stroke (width 0.15) (type solid)) (layer "B.Fab"))
    (fp_line (start -0.494 0.25) (end 0.504 0.25)
      (stroke (width 0.15) (type solid)) (layer "B.Fab"))
    (fp_line (start 0.504 -0.248) (end -0.494 -0.248)
      (stroke (width 0.15) (type solid)) (layer "B.Fab"))
    (fp_line (start 0.504 0.25) (end 0.504 -0.248)
      (stroke (width 0.15) (type solid)) (layer "B.Fab"))
    (pad "1" smd roundrect (at -0.48 0) (size 0.59 0.64) (layers "B.Cu" "B.Paste" "B.Mask") (roundrect_rratio 0.25)
      (net 1 "GND") (pintype "passive"))
    (pad "2" smd roundrect (at 0.48 0) (size 0.59 0.64) (layers "B.Cu" "B.Paste" "B.Mask") (roundrect_rratio 0.25)
      (net 107 "Net-(C54-Pad2)") (pintype "passive"))
  )

  (footprint "antmicro-footprints:C_0402_1005Metric" (layer "B.Cu")
    (at 165.2 77.912922 90)
    (descr "Capacitor SMD 0402")
    (tags "capacitor SMD 0402")
    (property "Author" "Antmicro")
    (property "Dielectric" "X5R")
    (property "License" "Apache-2.0")
    (property "MPN" "GRM155R61H104KE14D")
    (property "Manufacturer" "Murata")
    (property "Sheetfile" "connectors.kicad_sch")
    (property "Sheetname" "Connectors")
    (property "Val" "100n")
    (property "Voltage" "50V")
    (property "ki_description" "SMD Multilayer Ceramic Capacitor, 0.1 µF, 50 V, 0402 [1005 Metric], ± 10%, X5R, GRM Series")
    (property "ki_keywords" "0402, SMT, CAPACITOR, PASSIVE, CERAMIC, MLCC")
    (attr smd)
    (fp_text reference "C5" (at 0.696922 -0.608 270) (layer "B.SilkS")
        (effects (font (size 0.7 0.7) (thickness 0.15)) (justify left bottom mirror))
    )
    (fp_text value "C_100n_0402" (at -1.022927 -2.155213 270) (layer "B.Fab")
        (effects (font (size 0.7 0.7) (thickness 0.15)) (justify left bottom mirror))
    )
    (fp_text user "License: Apache-2.0" (at -0.939 -5.799 270) (layer "B.Fab") hide
        (effects (font (size 0.7 0.7) (thickness 0.15)) (justify left bottom mirror))
    )
    (fp_text user "Author: Antmicro" (at -0.939 -3.399 270) (layer "B.Fab") hide
        (effects (font (size 0.7 0.7) (thickness 0.15)) (justify left bottom mirror))
    )
    (fp_text user "${REFERENCE}" (at -0.939 -4.599 270) (layer "B.Fab") hide
        (effects (font (size 0.7 0.7) (thickness 0.15)) (justify left bottom mirror))
    )
    (fp_rect (start -0.925 0.47) (end 0.925 -0.47)
      (stroke (width 0.05) (type default)) (fill none) (layer "B.CrtYd"))
    (fp_line (start -0.494 -0.248) (end -0.494 0.25)
      (stroke (width 0.15) (type solid)) (layer "B.Fab"))
    (fp_line (start -0.494 0.25) (end 0.504 0.25)
      (stroke (width 0.15) (type solid)) (layer "B.Fab"))
    (fp_line (start 0.504 -0.248) (end -0.494 -0.248)
      (stroke (width 0.15) (type solid)) (layer "B.Fab"))
    (fp_line (start 0.504 0.25) (end 0.504 -0.248)
      (stroke (width 0.15) (type solid)) (layer "B.Fab"))
    (pad "1" smd roundrect (at -0.48 0 90) (size 0.59 0.64) (layers "B.Cu" "B.Paste" "B.Mask") (roundrect_rratio 0.25)
      (net 1 "GND") (pintype "passive"))
    (pad "2" smd roundrect (at 0.48 0 90) (size 0.59 0.64) (layers "B.Cu" "B.Paste" "B.Mask") (roundrect_rratio 0.25)
      (net 3 "5V0_USB") (pintype "passive"))
  )

  (footprint "antmicro-footprints:R_0402_1005Metric" (layer "B.Cu")
    (at 111.095 86.169999 90)
    (descr "Resistor SMD 0402")
    (tags "resistor SMD 0402")
    (property "Author" "Antmicro")
    (property "License" "Apache-2.0")
    (property "MPN" "CR0402-FX-1202GLF")
    (property "Manufacturer" "Bourns")
    (property "Sheetfile" "power.kicad_sch")
    (property "Sheetname" "Power")
    (property "Tolerance" "1%")
    (property "Val" "12k")
    (property "ki_description" "SMD Chip Resistor, 12 kohm, ± 1%, 62.5 mW, 0402 [1005 Metric], Thick Film, General Purpose")
    (property "ki_keywords" "0402, SMT, RESISTOR, PASSIVE")
    (attr smd)
    (fp_text reference "R25" (at -2.984001 0.411 90) (layer "B.SilkS")
        (effects (font (size 0.7 0.7) (thickness 0.15)) (justify right bottom mirror))
    )
    (fp_text value "R_12k_0402" (at -1.011843 -1.772047 90) (layer "B.Fab")
        (effects (font (size 0.7 0.7) (thickness 0.15)) (justify right bottom mirror))
    )
    (fp_text user "License: Apache-2.0" (at -0.95 -5.169 90) (layer "B.Fab") hide
        (effects (font (size 0.7 0.7) (thickness 0.15)) (justify right bottom mirror))
    )
    (fp_text user "Author: Antmicro" (at -0.95 -4.169 90) (layer "B.Fab") hide
        (effects (font (size 0.7 0.7) (thickness 0.15)) (justify right bottom mirror))
    )
    (fp_text user "${REFERENCE}" (at -0.95 -3.168 90) (layer "B.Fab") hide
        (effects (font (size 0.7 0.7) (thickness 0.15)) (justify right bottom mirror))
    )
    (fp_rect (start -0.925 0.47) (end 0.925 -0.47)
      (stroke (width 0.05) (type default)) (fill none) (layer "B.CrtYd"))
    (fp_rect (start -0.5 0.25) (end 0.5 -0.25)
      (stroke (width 0.15) (type solid)) (fill none) (layer "B.Fab"))
    (pad "1" smd roundrect (at -0.48 0 90) (size 0.59 0.64) (layers "B.Cu" "B.Paste" "B.Mask") (roundrect_rratio 0.25)
      (net 7 "Net-(C30-Pad2)") (pintype "passive"))
    (pad "2" smd roundrect (at 0.48 0 90) (size 0.59 0.64) (layers "B.Cu" "B.Paste" "B.Mask") (roundrect_rratio 0.25)
      (net 160 "Net-(U1-VC)") (pintype "passive"))
  )

  (footprint "antmicro-footprints:R_0402_1005Metric" (layer "B.Cu")
    (at 155.41 62.97)
    (descr "Resistor SMD 0402")
    (tags "resistor SMD 0402")
    (property "Author" "Antmicro")
    (property "License" "Apache-2.0")
    (property "MPN" "ERA-2ARB153X")
    (property "Manufacturer" "Panasonic")
    (property "Sheetfile" "power.kicad_sch")
    (property "Sheetname" "Power")
    (property "Tolerance" "0.1%")
    (property "Val" "15k")
    (property "ki_description" "SMD Chip Resistor, 15 kohm, ± 0.1%, 62.5 mW, 0402 [1005 Metric], Metal Film (Thin Film)")
    (property "ki_keywords" "0402, SMT, RESISTOR, PASSIVE")
    (attr smd)
    (fp_text reference "R35" (at 2.897664 0.40289 180) (layer "B.SilkS")
        (effects (font (size 0.7 0.7) (thickness 0.15)) (justify left bottom mirror))
    )
    (fp_text value "R_15k_0.1%_0402" (at -1.011843 -1.772047 180) (layer "B.Fab")
        (effects (font (size 0.7 0.7) (thickness 0.15)) (justify left bottom mirror))
    )
    (fp_text user "${REFERENCE}" (at -0.95 -3.168 180) (layer "B.Fab") hide
        (effects (font (size 0.7 0.7) (thickness 0.15)) (justify left bottom mirror))
    )
    (fp_text user "Author: Antmicro" (at -0.95 -4.169 180) (layer "B.Fab") hide
        (effects (font (size 0.7 0.7) (thickness 0.15)) (justify left bottom mirror))
    )
    (fp_text user "License: Apache-2.0" (at -0.95 -5.169 180) (layer "B.Fab") hide
        (effects (font (size 0.7 0.7) (thickness 0.15)) (justify left bottom mirror))
    )
    (fp_rect (start -0.925 0.47) (end 0.925 -0.47)
      (stroke (width 0.05) (type default)) (fill none) (layer "B.CrtYd"))
    (fp_rect (start -0.5 0.25) (end 0.5 -0.25)
      (stroke (width 0.15) (type solid)) (fill none) (layer "B.Fab"))
    (pad "1" smd roundrect (at -0.48 0) (size 0.59 0.64) (layers "B.Cu" "B.Paste" "B.Mask") (roundrect_rratio 0.25)
      (net 168 "Net-(U3-R_OSC)") (pintype "passive"))
    (pad "2" smd roundrect (at 0.48 0) (size 0.59 0.64) (layers "B.Cu" "B.Paste" "B.Mask") (roundrect_rratio 0.25)
      (net 1 "GND") (pintype "passive"))
  )

  (footprint "antmicro-footprints:C_0402_1005Metric" (layer "B.Cu")
    (at 134.8 78.875)
    (descr "Capacitor SMD 0402")
    (tags "capacitor SMD 0402")
    (property "Author" "Antmicro")
    (property "Dielectric" "")
    (property "License" "Apache-2.0")
    (property "MPN" "C1005X6S1A105K050BC")
    (property "Manufacturer" "TDK")
    (property "Sheetfile" "tb-power.kicad_sch")
    (property "Sheetname" "Thunderbolt Controller - Power")
    (property "Val" "1u")
    (property "Voltage" "")
    (property "ki_description" "SMD Multilayer Ceramic Capacitor, 1 µF, 10 V, 0402 [1005 Metric], ± 10%, X6S, C")
    (property "ki_keywords" "0402, SMT, CAPACITOR, PASSIVE, CERAMIC, MLCC")
    (attr smd)
    (fp_text reference "C74" (at 17.6 7.612 180) (layer "B.SilkS")
        (effects (font (size 0.7 0.7) (thickness 0.15)) (justify left bottom mirror))
    )
    (fp_text value "C_1u_0402" (at -1.022927 -2.155213 180) (layer "B.Fab")
        (effects (font (size 0.7 0.7) (thickness 0.15)) (justify left bottom mirror))
    )
    (fp_text user "Author: Antmicro" (at -0.939 -3.399 180) (layer "B.Fab") hide
        (effects (font (size 0.7 0.7) (thickness 0.15)) (justify left bottom mirror))
    )
    (fp_text user "License: Apache-2.0" (at -0.939 -5.799 180) (layer "B.Fab") hide
        (effects (font (size 0.7 0.7) (thickness 0.15)) (justify left bottom mirror))
    )
    (fp_text user "${REFERENCE}" (at -0.939 -4.599 180) (layer "B.Fab") hide
        (effects (font (size 0.7 0.7) (thickness 0.15)) (justify left bottom mirror))
    )
    (fp_rect (start -0.925 0.47) (end 0.925 -0.47)
      (stroke (width 0.05) (type default)) (fill none) (layer "B.CrtYd"))
    (fp_line (start -0.494 -0.248) (end -0.494 0.25)
      (stroke (width 0.15) (type solid)) (layer "B.Fab"))
    (fp_line (start -0.494 0.25) (end 0.504 0.25)
      (stroke (width 0.15) (type solid)) (layer "B.Fab"))
    (fp_line (start 0.504 -0.248) (end -0.494 -0.248)
      (stroke (width 0.15) (type solid)) (layer "B.Fab"))
    (fp_line (start 0.504 0.25) (end 0.504 -0.248)
      (stroke (width 0.15) (type solid)) (layer "B.Fab"))
    (pad "1" smd roundrect (at -0.48 0) (size 0.59 0.64) (layers "B.Cu" "B.Paste" "B.Mask") (roundrect_rratio 0.25)
      (net 1 "GND") (pintype "passive"))
    (pad "2" smd roundrect (at 0.48 0) (size 0.59 0.64) (layers "B.Cu" "B.Paste" "B.Mask") (roundrect_rratio 0.25)
      (net 112 "Net-(U4A-VCC0P9_SVR_SENSE)") (pintype "passive"))
  )

  (footprint "antmicro-footprints:NetTie-2_SMD_Pad0.127mm" (layer "B.Cu")
    (at 116.16 86.35 -135)
    (descr "Net tie, 2 pin, 0.127mm  SMD pads")
    (tags "net tie")
    (property "Author" "Antmicro")
    (property "License" "Apache-2.0")
    (property "MPN" "")
    (property "Manufacturer" "")
    (property "Sheetfile" "power.kicad_sch")
    (property "Sheetname" "Power")
    (property "exclude_from_bom" "")
    (property "ki_description" "Net tie, 2 pins")
    (attr through_hole exclude_from_pos_files exclude_from_bom)
    (net_tie_pad_groups "1, 2")
    (fp_text reference "TP10" (at -0.128 1.345 45) (layer "B.SilkS") hide
        (effects (font (size 0.7 0.7) (thickness 0.15)) (justify left bottom mirror))
    )
    (fp_text value "Net-Tie_P0.127mm" (at 0 -1.199 45) (layer "B.Fab")
        (effects (font (size 0.7 0.7) (thickness 0.15)) (justify left bottom mirror))
    )
    (fp_text user "License: Apache-2.0" (at -0.128 -5.6 45) (layer "B.Fab") hide
        (effects (font (size 0.7 0.7) (thickness 0.15)) (justify left bottom mirror))
    )
    (fp_text user "${REFERENCE}" (at -0.128 -3.2 45) (layer "B.Fab") hide
        (effects (font (size 0.7 0.7) (thickness 0.15)) (justify left bottom mirror))
    )
    (fp_text user "Author: Antmicro" (at -0.128 -4.4 45) (layer "B.Fab") hide
        (effects (font (size 0.7 0.7) (thickness 0.15)) (justify left bottom mirror))
    )
    (fp_poly
      (pts
        (xy -0.0635 0.0635)
        (xy 0.0625 0.0635)
        (xy 0.0625 -0.0635)
        (xy -0.0635 -0.0635)
      )

      (stroke (width 0) (type solid)) (fill solid) (layer "B.Cu"))
    (fp_poly
      (pts
        (xy 0.2 0.16)
        (xy 0.29 0.07)
        (xy 0.29 -0.07)
        (xy 0.2 -0.16)
        (xy -0.2 -0.16)
        (xy -0.29 -0.07)
        (xy -0.29 0.06)
        (xy -0.19 0.16)
      )

      (stroke (width 0.05) (type solid)) (fill none) (layer "B.CrtYd"))
    (pad "1" smd roundrect (at -0.127 0 45) (size 0.127 0.127) (layers "B.Cu") (roundrect_rratio 0.5)
      (chamfer_ratio 0) (chamfer top_left bottom_left)
      (net 75 "Net-(C32-Pad2)") (pinfunction "1") (pintype "passive"))
    (pad "2" smd roundrect (at 0.126 0 225) (size 0.127 0.127) (layers "B.Cu") (roundrect_rratio 0.5)
      (chamfer_ratio 0) (chamfer top_left bottom_left)
      (net 84 "/Power/I_SENSE_P") (pinfunction "2") (pintype "passive"))
  )

  (footprint "antmicro-footprints:R_0402_1005Metric" (layer "B.Cu")
    (at 137.225 66.82 -90)
    (descr "Resistor SMD 0402")
    (tags "resistor SMD 0402")
    (property "Author" "Antmicro")
    (property "License" "Apache-2.0")
    (property "MPN" "CR0402-FX-2201GLF")
    (property "Manufacturer" "Bourns")
    (property "Sheetfile" "tb.kicad_sch")
    (property "Sheetname" "TB Controller")
    (property "Tolerance" "1%")
    (property "Val" "2k2")
    (property "ki_description" "SMD Chip Resistor, 2.2 kohm, ± 1%, 62.5 mW, 0402 [1005 Metric], Thick Film, General Purpose")
    (property "ki_keywords" "0402, SMT, RESISTOR, PASSIVE")
    (attr smd)
    (fp_text reference "R59" (at -3.066 -0.325 90) (layer "B.SilkS")
        (effects (font (size 0.7 0.7) (thickness 0.15)) (justify left bottom mirror))
    )
    (fp_text value "R_2k2_0402" (at -1.011843 -1.772047 90) (layer "B.Fab")
        (effects (font (size 0.7 0.7) (thickness 0.15)) (justify left bottom mirror))
    )
    (fp_text user "License: Apache-2.0" (at -0.95 -5.169 90) (layer "B.Fab") hide
        (effects (font (size 0.7 0.7) (thickness 0.15)) (justify left bottom mirror))
    )
    (fp_text user "Author: Antmicro" (at -0.95 -4.169 90) (layer "B.Fab") hide
        (effects (font (size 0.7 0.7) (thickness 0.15)) (justify left bottom mirror))
    )
    (fp_text user "${REFERENCE}" (at -0.95 -3.168 90) (layer "B.Fab") hide
        (effects (font (size 0.7 0.7) (thickness 0.15)) (justify left bottom mirror))
    )
    (fp_rect (start -0.925 0.47) (end 0.925 -0.47)
      (stroke (width 0.05) (type default)) (fill none) (layer "B.CrtYd"))
    (fp_rect (start -0.5 0.25) (end 0.5 -0.25)
      (stroke (width 0.15) (type solid)) (fill none) (layer "B.Fab"))
    (pad "1" smd roundrect (at -0.48 0 270) (size 0.59 0.64) (layers "B.Cu" "B.Paste" "B.Mask") (roundrect_rratio 0.25)
      (net 1 "GND") (pintype "passive"))
    (pad "2" smd roundrect (at 0.48 0 270) (size 0.59 0.64) (layers "B.Cu" "B.Paste" "B.Mask") (roundrect_rratio 0.25)
      (net 173 "Net-(U4C-DPSNK0_DDC_DATA)") (pintype "passive"))
  )

  (footprint "antmicro-footprints:C_0402_1005Metric" (layer "B.Cu")
    (at 157.41 63.97 180)
    (descr "Capacitor SMD 0402")
    (tags "capacitor SMD 0402")
    (property "Author" "Antmicro")
    (property "Dielectric" "")
    (property "License" "Apache-2.0")
    (property "MPN" "CC0402KRX5R6BB224")
    (property "Manufacturer" "YAGEO")
    (property "Sheetfile" "power.kicad_sch")
    (property "Sheetname" "Power")
    (property "Val" "220n")
    (property "Voltage" "")
    (property "ki_description" "SMD Multilayer Ceramic Capacitor, 0.22 µF, 10 V, 0402 [1005 Metric], ± 10%, X5R, CC Series")
    (property "ki_keywords" "0402, SMT, CAPACITOR, PASSIVE, MLCC, CERAMIC")
    (attr smd)
    (fp_text reference "C31" (at -0.987545 -1.435686) (layer "B.SilkS")
        (effects (font (size 0.7 0.7) (thickness 0.15)) (justify left bottom mirror))
    )
    (fp_text value "C_220n_0402" (at -1.022927 -2.155213) (layer "B.Fab")
        (effects (font (size 0.7 0.7) (thickness 0.15)) (justify left bottom mirror))
    )
    (fp_text user "Author: Antmicro" (at -0.939 -3.399) (layer "B.Fab") hide
        (effects (font (size 0.7 0.7) (thickness 0.15)) (justify left bottom mirror))
    )
    (fp_text user "${REFERENCE}" (at -0.939 -4.599) (layer "B.Fab") hide
        (effects (font (size 0.7 0.7) (thickness 0.15)) (justify left bottom mirror))
    )
    (fp_text user "License: Apache-2.0" (at -0.939 -5.799) (layer "B.Fab") hide
        (effects (font (size 0.7 0.7) (thickness 0.15)) (justify left bottom mirror))
    )
    (fp_rect (start -0.925 0.47) (end 0.925 -0.47)
      (stroke (width 0.05) (type default)) (fill none) (layer "B.CrtYd"))
    (fp_line (start -0.494 -0.248) (end -0.494 0.25)
      (stroke (width 0.15) (type solid)) (layer "B.Fab"))
    (fp_line (start -0.494 0.25) (end 0.504 0.25)
      (stroke (width 0.15) (type solid)) (layer "B.Fab"))
    (fp_line (start 0.504 -0.248) (end -0.494 -0.248)
      (stroke (width 0.15) (type solid)) (layer "B.Fab"))
    (fp_line (start 0.504 0.25) (end 0.504 -0.248)
      (stroke (width 0.15) (type solid)) (layer "B.Fab"))
    (pad "1" smd roundrect (at -0.48 0 180) (size 0.59 0.64) (layers "B.Cu" "B.Paste" "B.Mask") (roundrect_rratio 0.25)
      (net 1 "GND") (pintype "passive"))
    (pad "2" smd roundrect (at 0.48 0 180) (size 0.59 0.64) (layers "B.Cu" "B.Paste" "B.Mask") (roundrect_rratio 0.25)
      (net 98 "Net-(U3-SS)") (pintype "passive"))
  )

  (footprint "antmicro-footprints:C_0402_1005Metric" (layer "B.Cu")
    (at 139.175 81.3 90)
    (descr "Capacitor SMD 0402")
    (tags "capacitor SMD 0402")
    (property "Author" "Antmicro")
    (property "Dielectric" "")
    (property "License" "Apache-2.0")
    (property "MPN" "C1005X6S1A105K050BC")
    (property "Manufacturer" "TDK")
    (property "Sheetfile" "tb-power.kicad_sch")
    (property "Sheetname" "Thunderbolt Controller - Power")
    (property "Val" "1u")
    (property "Voltage" "")
    (property "ki_description" "SMD Multilayer Ceramic Capacitor, 1 µF, 10 V, 0402 [1005 Metric], ± 10%, X6S, C")
    (property "ki_keywords" "0402, SMT, CAPACITOR, PASSIVE, CERAMIC, MLCC")
    (attr smd)
    (fp_text reference "C81" (at -6.584 16.781 270) (layer "B.SilkS")
        (effects (font (size 0.7 0.7) (thickness 0.15)) (justify left bottom mirror))
    )
    (fp_text value "C_1u_0402" (at -1.022927 -2.155213 270) (layer "B.Fab")
        (effects (font (size 0.7 0.7) (thickness 0.15)) (justify left bottom mirror))
    )
    (fp_text user "Author: Antmicro" (at -0.939 -3.399 270) (layer "B.Fab") hide
        (effects (font (size 0.7 0.7) (thickness 0.15)) (justify left bottom mirror))
    )
    (fp_text user "${REFERENCE}" (at -0.939 -4.599 270) (layer "B.Fab") hide
        (effects (font (size 0.7 0.7) (thickness 0.15)) (justify left bottom mirror))
    )
    (fp_text user "License: Apache-2.0" (at -0.939 -5.799 270) (layer "B.Fab") hide
        (effects (font (size 0.7 0.7) (thickness 0.15)) (justify left bottom mirror))
    )
    (fp_rect (start -0.925 0.47) (end 0.925 -0.47)
      (stroke (width 0.05) (type default)) (fill none) (layer "B.CrtYd"))
    (fp_line (start -0.494 -0.248) (end -0.494 0.25)
      (stroke (width 0.15) (type solid)) (layer "B.Fab"))
    (fp_line (start -0.494 0.25) (end 0.504 0.25)
      (stroke (width 0.15) (type solid)) (layer "B.Fab"))
    (fp_line (start 0.504 -0.248) (end -0.494 -0.248)
      (stroke (width 0.15) (type solid)) (layer "B.Fab"))
    (fp_line (start 0.504 0.25) (end 0.504 -0.248)
      (stroke (width 0.15) (type solid)) (layer "B.Fab"))
    (pad "1" smd roundrect (at -0.48 0 90) (size 0.59 0.64) (layers "B.Cu" "B.Paste" "B.Mask") (roundrect_rratio 0.25)
      (net 1 "GND") (pintype "passive"))
    (pad "2" smd roundrect (at 0.48 0 90) (size 0.59 0.64) (layers "B.Cu" "B.Paste" "B.Mask") (roundrect_rratio 0.25)
      (net 112 "Net-(U4A-VCC0P9_SVR_SENSE)") (pintype "passive"))
  )

  (footprint "antmicro-footprints:R_0402_1005Metric" (layer "B.Cu")
    (at 155.91 59.47 90)
    (descr "Resistor SMD 0402")
    (tags "resistor SMD 0402")
    (property "Author" "Antmicro")
    (property "License" "Apache-2.0")
    (property "MPN" "CR0402-FX-1003GLF")
    (property "Manufacturer" "Bourns")
    (property "Sheetfile" "power.kicad_sch")
    (property "Sheetname" "Power")
    (property "Tolerance" "1%")
    (property "Val" "100k")
    (property "ki_description" "SMD Chip Resistor, 100 kohm, ± 1%, 62.5 mW, 0402 [1005 Metric], Thick Film, General Purpose")
    (property "ki_keywords" "0402, SMT, RESISTOR, PASSIVE")
    (attr smd)
    (fp_text reference "R29" (at 4.86 -5.542 270) (layer "B.SilkS")
        (effects (font (size 0.7 0.7) (thickness 0.15)) (justify left bottom mirror))
    )
    (fp_text value "R_100k_0402" (at -1.011843 -1.772047 270) (layer "B.Fab")
        (effects (font (size 0.7 0.7) (thickness 0.15)) (justify left bottom mirror))
    )
    (fp_text user "License: Apache-2.0" (at -0.95 -5.169 270) (layer "B.Fab") hide
        (effects (font (size 0.7 0.7) (thickness 0.15)) (justify left bottom mirror))
    )
    (fp_text user "Author: Antmicro" (at -0.95 -4.169 270) (layer "B.Fab") hide
        (effects (font (size 0.7 0.7) (thickness 0.15)) (justify left bottom mirror))
    )
    (fp_text user "${REFERENCE}" (at -0.95 -3.168 270) (layer "B.Fab") hide
        (effects (font (size 0.7 0.7) (thickness 0.15)) (justify left bottom mirror))
    )
    (fp_rect (start -0.925 0.47) (end 0.925 -0.47)
      (stroke (width 0.05) (type default)) (fill none) (layer "B.CrtYd"))
    (fp_rect (start -0.5 0.25) (end 0.5 -0.25)
      (stroke (width 0.15) (type solid)) (fill none) (layer "B.Fab"))
    (pad "1" smd roundrect (at -0.48 0 90) (size 0.59 0.64) (layers "B.Cu" "B.Paste" "B.Mask") (roundrect_rratio 0.25)
      (net 162 "Net-(U3-DEBUG_CTL2(GPIO17,_I2CADDR_B5))") (pintype "passive"))
    (pad "2" smd roundrect (at 0.48 0 90) (size 0.59 0.64) (layers "B.Cu" "B.Paste" "B.Mask") (roundrect_rratio 0.25)
      (net 9 "/Power/TPS_3V3") (pintype "passive"))
  )

  (footprint "antmicro-footprints:R_0402_1005Metric" (layer "B.Cu")
    (at 145.62 74.959999)
    (descr "Resistor SMD 0402")
    (tags "resistor SMD 0402")
    (property "Author" "Antmicro")
    (property "License" "Apache-2.0")
    (property "MPN" "CR0402-FX-1004GLF")
    (property "Manufacturer" "Bourns")
    (property "Sheetfile" "tb.kicad_sch")
    (property "Sheetname" "TB Controller")
    (property "Tolerance" "1%")
    (property "Val" "1M")
    (property "ki_description" "SMD Chip Resistor, 1 Mohm, ± 1%, 62.5 mW, 0402 [1005 Metric], Thick Film, General Purpose")
    (property "ki_keywords" "0402, SMT, RESISTOR, PASSIVE")
    (attr smd)
    (fp_text reference "R54" (at 3.097 0.351001 180) (layer "B.SilkS")
        (effects (font (size 0.7 0.7) (thickness 0.15)) (justify left bottom mirror))
    )
    (fp_text value "R_1M_0402" (at -1.011843 -1.772047 180) (layer "B.Fab")
        (effects (font (size 0.7 0.7) (thickness 0.15)) (justify left bottom mirror))
    )
    (fp_text user "${REFERENCE}" (at -0.95 -3.168 180) (layer "B.Fab") hide
        (effects (font (size 0.7 0.7) (thickness 0.15)) (justify left bottom mirror))
    )
    (fp_text user "License: Apache-2.0" (at -0.95 -5.169 180) (layer "B.Fab") hide
        (effects (font (size 0.7 0.7) (thickness 0.15)) (justify left bottom mirror))
    )
    (fp_text user "Author: Antmicro" (at -0.95 -4.169 180) (layer "B.Fab") hide
        (effects (font (size 0.7 0.7) (thickness 0.15)) (justify left bottom mirror))
    )
    (fp_rect (start -0.925 0.47) (end 0.925 -0.47)
      (stroke (width 0.05) (type default)) (fill none) (layer "B.CrtYd"))
    (fp_rect (start -0.5 0.25) (end 0.5 -0.25)
      (stroke (width 0.15) (type solid)) (fill none) (layer "B.Fab"))
    (pad "1" smd roundrect (at -0.48 0) (size 0.59 0.64) (layers "B.Cu" "B.Paste" "B.Mask") (roundrect_rratio 0.25)
      (net 1 "GND") (pintype "passive"))
    (pad "2" smd roundrect (at 0.48 0) (size 0.59 0.64) (layers "B.Cu" "B.Paste" "B.Mask") (roundrect_rratio 0.25)
      (net 66 "LSX_P2R") (pintype "passive"))
  )

  (footprint "antmicro-footprints:C_0402_1005Metric" (layer "B.Cu")
    (at 138.2 81.3 90)
    (descr "Capacitor SMD 0402")
    (tags "capacitor SMD 0402")
    (property "Author" "Antmicro")
    (property "Dielectric" "")
    (property "License" "Apache-2.0")
    (property "MPN" "C1005X6S1A105K050BC")
    (property "Manufacturer" "TDK")
    (property "Sheetfile" "tb-power.kicad_sch")
    (property "Sheetname" "Thunderbolt Controller - Power")
    (property "Val" "1u")
    (property "Voltage" "")
    (property "ki_description" "SMD Multilayer Ceramic Capacitor, 1 µF, 10 V, 0402 [1005 Metric], ± 10%, X6S, C")
    (property "ki_keywords" "0402, SMT, CAPACITOR, PASSIVE, CERAMIC, MLCC")
    (attr smd)
    (fp_text reference "C84" (at -6.584 16.867 270) (layer "B.SilkS")
        (effects (font (size 0.7 0.7) (thickness 0.15)) (justify left bottom mirror))
    )
    (fp_text value "C_1u_0402" (at -1.022927 -2.155213 270) (layer "B.Fab")
        (effects (font (size 0.7 0.7) (thickness 0.15)) (justify left bottom mirror))
    )
    (fp_text user "License: Apache-2.0" (at -0.939 -5.799 270) (layer "B.Fab") hide
        (effects (font (size 0.7 0.7) (thickness 0.15)) (justify left bottom mirror))
    )
    (fp_text user "Author: Antmicro" (at -0.939 -3.399 270) (layer "B.Fab") hide
        (effects (font (size 0.7 0.7) (thickness 0.15)) (justify left bottom mirror))
    )
    (fp_text user "${REFERENCE}" (at -0.939 -4.599 270) (layer "B.Fab") hide
        (effects (font (size 0.7 0.7) (thickness 0.15)) (justify left bottom mirror))
    )
    (fp_rect (start -0.925 0.47) (end 0.925 -0.47)
      (stroke (width 0.05) (type default)) (fill none) (layer "B.CrtYd"))
    (fp_line (start -0.494 -0.248) (end -0.494 0.25)
      (stroke (width 0.15) (type solid)) (layer "B.Fab"))
    (fp_line (start -0.494 0.25) (end 0.504 0.25)
      (stroke (width 0.15) (type solid)) (layer "B.Fab"))
    (fp_line (start 0.504 -0.248) (end -0.494 -0.248)
      (stroke (width 0.15) (type solid)) (layer "B.Fab"))
    (fp_line (start 0.504 0.25) (end 0.504 -0.248)
      (stroke (width 0.15) (type solid)) (layer "B.Fab"))
    (pad "1" smd roundrect (at -0.48 0 90) (size 0.59 0.64) (layers "B.Cu" "B.Paste" "B.Mask") (roundrect_rratio 0.25)
      (net 1 "GND") (pintype "passive"))
    (pad "2" smd roundrect (at 0.48 0 90) (size 0.59 0.64) (layers "B.Cu" "B.Paste" "B.Mask") (roundrect_rratio 0.25)
      (net 112 "Net-(U4A-VCC0P9_SVR_SENSE)") (pintype "passive"))
  )
  (gr_line (start 123.95 100) (end 170 100)
    (stroke (width 0.12) (type solid)) (layer "Edge.Cuts"))
  (gr_arc (start 122.049448 94.976052) (mid 122.9995 94.026) (end 123.949552 94.976052)
    (stroke (width 0.12) (type solid)) (layer "Edge.Cuts"))
  (gr_line (start 123.95 100) (end 123.949552 94.976052)
    (stroke (width 0.12) (type solid)) (layer "Edge.Cuts"))
  (gr_line (start 100 100) (end 100 50)
    (stroke (width 0.12) (type solid)) (layer "Edge.Cuts"))
  (gr_line (start 122.05 100) (end 122.049448 94.976052)
    (stroke (width 0.12) (type solid)) (layer "Edge.Cuts"))
  (gr_line (start 122.05 100) (end 100 100)
    (stroke (width 0.12) (type solid)) (layer "Edge.Cuts"))
  (gr_line (start 170 50) (end 170 100)
    (stroke (width 0.12) (type solid)) (layer "Edge.Cuts"))
  (gr_line (start 100 50) (end 170 50)
    (stroke (width 0.12) (type solid)) (layer "Edge.Cuts"))

  (segment (start 136.425 83.425) (end 136.1 83.1) (width 0.1) (layer "F.Cu") (net 1))
  (segment (start 138.05 79.2) (end 138.375 78.875) (width 0.1) (layer "F.Cu") (net 1))
  (segment (start 138.94 84.45) (end 138.94 84.234) (width 0.1) (layer "F.Cu") (net 1))
  (segment (start 124.5 97.075046) (end 124.5 94.545046) (width 0.4) (layer "F.Cu") (net 1))
  (segment (start 138.02 84.91) (end 138.02 84.45) (width 0.1) (layer "F.Cu") (net 1))
  (segment (start 139.025 78.225) (end 138.7 77.9) (width 0.1) (layer "F.Cu") (net 1))
  (segment (start 132.85 81.15) (end 132.525 80.825) (width 0.1) (layer "F.Cu") (net 1))
  (segment (start 136.1 82.450001) (end 136.425 82.775) (width 0.1) (layer "F.Cu") (net 1))
  (segment (start 132.85 77.25) (end 132.525 76.925) (width 0.1) (layer "F.Cu") (net 1))
  (segment (start 133.5 82.45) (end 133.825 82.775) (width 0.1) (layer "F.Cu") (net 1))
  (segment (start 155.39 65.35) (end 155.39 65.23) (width 0.1) (layer "F.Cu") (net 1))
  (segment (start 124.5 94.545046) (end 125 94.045046) (width 0.4) (layer "F.Cu") (net 1))
  (segment (start 138.375 76.275) (end 138.05 76.6) (width 0.1) (layer "F.Cu") (net 1))
  (segment (start 138.05 75.95) (end 137.725 76.275) (width 0.1) (layer "F.Cu") (net 1))
  (segment (start 116.659001 63.095) (end 116.659001 62.300499) (width 0.25) (layer "F.Cu") (net 1))
  (segment (start 133.88 75.25) (end 133.88 74.79) (width 0.1) (layer "F.Cu") (net 1))
  (segment (start 132.2 81.8) (end 132.525 81.475) (width 0.1) (layer "F.Cu") (net 1))
  (segment (start 137.4 77.25) (end 138.05 76.6) (width 0.1) (layer "F.Cu") (net 1))
  (segment (start 139.184 81.69) (end 138.81 81.69) (width 0.1) (layer "F.Cu") (net 1))
  (segment (start 130.2 84.45) (end 129.74 84.45) (width 0.1) (layer "F.Cu") (net 1))
  (segment (start 138.375 78.875) (end 138.05 78.55) (width 0.1) (layer "F.Cu") (net 1))
  (segment (start 139.184 81.966) (end 139.184 81.69) (width 0.1) (layer "F.Cu") (net 1))
  (segment (start 114.5 94.75) (end 115.35 93.9) (width 0.6) (layer "F.Cu") (net 1))
  (segment (start 135.45 76.6) (end 135.125 76.275) (width 0.1) (layer "F.Cu") (net 1))
  (segment (start 136.5 94.55) (end 137 94.05) (width 0.4) (layer "F.Cu") (net 1))
  (segment (start 132.2 81.15) (end 131.55 80.5) (width 0.1) (layer "F.Cu") (net 1))
  (segment (start 147.335 71.59) (end 147.5 71.425) (width 0.1) (layer "F.Cu") (net 1))
  (segment (start 134.8 76.6) (end 134.475 76.275) (width 0.1) (layer "F.Cu") (net 1))
  (segment (start 139.4 78.01) (end 139.185 78.225) (width 0.1) (layer "F.Cu") (net 1))
  (segment (start 138.05 79.2) (end 137.725 78.875) (width 0.1) (layer "F.Cu") (net 1))
  (segment (start 157.89 61.18) (end 158.08 61.37) (width 0.1) (layer "F.Cu") (net 1))
  (segment (start 130.66 84.91) (end 130.66 84.45) (width 0.1) (layer "F.Cu") (net 1))
  (segment (start 138.86 82.61) (end 138.7 82.45) (width 0.1) (layer "F.Cu") (net 1))
  (segment (start 136.1 83.1) (end 135.775 82.775) (width 0.1) (layer "F.Cu") (net 1))
  (segment (start 132.2 81.8) (end 132.525 82.125) (width 0.1) (layer "F.Cu") (net 1))
  (segment (start 136.18 84.234) (end 135.934 84.234) (width 0.1) (layer "F.Cu") (net 1))
  (segment (start 155.27 64.97) (end 155.13 64.97) (width 0.1) (layer "F.Cu") (net 1))
  (segment (start 131.55 78.55) (end 132.2 77.9) (width 0.1) (layer "F.Cu") (net 1))
  (segment (start 138.7 82.45) (end 138.375 82.125) (width 0.1) (layer "F.Cu") (net 1))
  (segment (start 134.34 84.21) (end 134.475 84.075) (width 0.1) (layer "F.Cu") (net 1))
  (segment (start 135.45 83.75) (end 135.775 83.425) (width 0.1) (layer "F.Cu") (net 1))
  (segment (start 131.55 76.6) (end 131.875 76.275) (width 0.1) (layer "F.Cu") (net 1))
  (segment (start 139.86 80.77) (end 140.281123 80.77) (width 0.1) (layer "F.Cu") (net 1))
  (segment (start 133.175 76.275) (end 133.5 76.6) (width 0.1) (layer "F.Cu") (net 1))
  (segment (start 134.475 80.175) (end 134.15 79.85) (width 0.1) (layer "F.Cu") (net 1))
  (segment (start 136.1 83.1) (end 135.775 83.425) (width 0.1) (layer "F.Cu") (net 1))
  (segment (start 139.86 83.53) (end 139.4 83.53) (width 0.1) (layer "F.Cu") (net 1))
  (segment (start 130.2 78.01) (end 130.66 78.47) (width 0.1) (layer "F.Cu") (net 1))
  (segment (start 132.2 77.9) (end 131.875 77.575) (width 0.1) (layer "F.Cu") (net 1))
  (segment (start 137.725 81.475) (end 138.05 81.8) (width 0.1) (layer "F.Cu") (net 1))
  (segment (start 138.05 81.15) (end 137.725 81.475) (width 0.1) (layer "F.Cu") (net 1))
  (segment (start 138.375 79.525) (end 138.7 79.85) (width 0.1) (layer "F.Cu") (net 1))
  (segment (start 157.89 62.85) (end 157.64 62.6) (width 0.1) (layer "F.Cu") (net 1))
  (segment (start 112.137 79.338) (end 112.79602 79.338) (width 0.1) (layer "F.Cu") (net 1))
  (segment (start 132.2 83.75) (end 132.5 84.05) (width 0.1) (layer "F.Cu") (net 1))
  (segment (start 154.89 64.85) (end 155.01 64.97) (width 0.1) (layer "F.Cu") (net 1))
  (segment (start 132.2 83.75) (end 131.716 84.234) (width 0.1) (layer "F.Cu") (net 1))
  (segment (start 135.26 83.94) (end 134.99 83.94) (width 0.1) (layer "F.Cu") (net 1))
  (segment (start 134.15 83.75) (end 134.475 83.425) (width 0.1) (layer "F.Cu") (net 1))
  (segment (start 161.776 80.404922) (end 161.625 80.253922) (width 0.1) (layer "F.Cu") (net 1))
  (segment (start 139.4 79.85) (end 139.86 79.85) (width 0.1) (layer "F.Cu") (net 1))
  (segment (start 139.025 80.825) (end 138.7 80.5) (width 0.1) (layer "F.Cu") (net 1))
  (segment (start 132.85 82.45) (end 132.525 82.125) (width 0.1) (layer "F.Cu") (net 1))
  (segment (start 134.8 83.75) (end 134.475 83.425) (width 0.1) (layer "F.Cu") (net 1))
  (segment (start 129.74 82.61) (end 129.99 82.61) (width 0.1) (layer "F.Cu") (net 1))
  (segment (start 132.85 76.6) (end 132.525 76.275) (width 0.1) (layer "F.Cu") (net 1))
  (segment (start 102.725001 87.940001) (end 102.39 87.940001) (width 0.1) (layer "F.Cu") (net 1))
  (segment (start 139.4 78.01) (end 139.86 78.01) (width 0.1) (layer "F.Cu") (net 1))
  (segment (start 139.025 78.875) (end 138.7 78.55) (width 0.1) (layer "F.Cu") (net 1))
  (segment (start 156.89 63.35) (end 156.64 63.1) (width 0.1) (layer "F.Cu") (net 1))
  (segment (start 111.110001 66.055) (end 113.470001 66.055) (width 0.25) (layer "F.Cu") (net 1))
  (segment (start 135.72 75.25) (end 135.72 74.79) (width 0.1) (layer "F.Cu") (net 1))
  (segment (start 114.5 97.075046) (end 114.5 94.75) (width 0.6) (layer "F.Cu") (net 1))
  (segment (start 139.4 81.69) (end 139.184 81.69) (width 0.1) (layer "F.Cu") (net 1))
  (segment (start 156.89 62.35) (end 157.14 62.6) (width 0.1) (layer "F.Cu") (net 1))
  (segment (start 103.685 88.9) (end 102.725001 87.940001) (width 0.1) (layer "F.Cu") (net 1))
  (segment (start 130.2 84.45) (end 130.66 84.45) (width 0.1) (layer "F.Cu") (net 1))
  (segment (start 131.55 83.75) (end 131.55 84.204) (width 0.1) (layer "F.Cu") (net 1))
  (segment (start 135.45 80.5) (end 135.125 80.825) (width 0.1) (layer "F.Cu") (net 1))
  (segment (start 130.68 83.53) (end 130.9 83.75) (width 0.1) (layer "F.Cu") (net 1))
  (segment (start 157.89 63.35) (end 157.64 63.1) (width 0.1) (layer "F.Cu") (net 1))
  (segment (start 136.1 84.154) (end 136.1 83.75) (width 0.1) (layer "F.Cu") (net 1))
  (segment (start 157.89 62.85) (end 157.64 63.1) (width 0.1) (layer "F.Cu") (net 1))
  (segment (start 156.39 63.85) (end 156.39 63.35) (width 0.1) (layer "F.Cu") (net 1))
  (segment (start 130.2 79.85) (end 129.984 79.85) (width 0.1) (layer "F.Cu") (net 1))
  (segment (start 139.5 97.075046) (end 139.5 94.545046) (width 0.4) (layer "F.Cu") (net 1))
  (segment (start 132.525 76.275) (end 132.2 76.6) (width 0.1) (layer "F.Cu") (net 1))
  (segment (start 127.5 94.55) (end 128 94.05) (width 0.4) (layer "F.Cu") (net 1))
  (segment (start 132.85 80.5) (end 132.525 80.825) (width 0.1) (layer "F.Cu") (net 1))
  (segment (start 130.74 78.55) (end 130.66 78.47) (width 0.1) (layer "F.Cu") (net 1))
  (segment (start 157.39 62.35) (end 157.14 62.6) (width 0.1) (layer "F.Cu") (net 1))
  (segment (start 138.375 82.125) (end 138.7 81.8) (width 0.1) (layer "F.Cu") (net 1))
  (segment (start 135.26 84.45) (end 135.26 83.94) (width 0.1) (layer "F.Cu") (net 1))
  (segment (start 133.5 83.1) (end 133.825 82.775) (width 0.1) (layer "F.Cu") (net 1))
  (segment (start 138.7 77.25) (end 138.375 76.925) (width 0.1) (layer "F.Cu") (net 1))
  (segment (start 138.975 80.125) (end 138.975 80.225) (width 0.1) (layer "F.Cu") (net 1))
  (segment (start 132.85 78.55) (end 132.525 78.225) (width 0.1) (layer "F.Cu") (net 1))
  (segment (start 139.184 81.69) (end 139.184 81.634) (width 0.1) (layer "F.Cu") (net 1))
  (segment (start 131.58 84.91) (end 131.58 84.45) (width 0.1) (layer "F.Cu") (net 1))
  (segment (start 136.1 82.45) (end 135.775 82.125) (width 0.1) (layer "F.Cu") (net 1))
  (segment (start 138.975 82.175) (end 139.025 82.125) (width 0.1) (layer "F.Cu") (net 1))
  (segment (start 130.2 80.77) (end 130.66 80.31) (width 0.1) (layer "F.Cu") (net 1))
  (segment (start 137.4 76.6) (end 137.725 76.275) (width 0.1) (layer "F.Cu") (net 1))
  (segment (start 134.15 77.9) (end 134.475 78.225) (width 0.1) (layer "F.Cu") (net 1))
  (segment (start 134.8 83.75) (end 134.475 84.075) (width 0.1) (layer "F.Cu") (net 1))
  (segment (start 130.2 75.25) (end 130.2 74.79) (width 0.1) (layer "F.Cu") (net 1))
  (segment (start 107.868394 79.338) (end 107.842109 79.311715) (width 0.1) (layer "F.Cu") (net 1))
  (segment (start 139.025 82.125) (end 139.184 81.966) (width 0.1) (layer "F.Cu") (net 1))
  (segment (start 134.34 84.45) (end 134.34 84.21) (width 0.1) (layer "F.Cu") (net 1))
  (segment (start 132.5 97.075046) (end 132.5 94.55) (width 0.4) (layer "F.Cu") (net 1))
  (segment (start 136.75 83.75) (end 137.1 84.1) (width 0.1) (layer "F.Cu") (net 1))
  (segment (start 139.86 78.93) (end 139.4 78.93) (width 0.1) (layer "F.Cu") (net 1))
  (segment (start 139.025 80.825) (end 138.7 81.149999) (width 0.1) (layer "F.Cu") (net 1))
  (segment (start 138.05 75.95) (end 138.375 76.275) (width 0.1) (layer "F.Cu") (net 1))
  (segment (start 132.85 81.15) (end 132.525 81.475) (width 0.1) (layer "F.Cu") (net 1))
  (segment (start 138.375 78.875) (end 138.7 78.55) (width 0.1) (layer "F.Cu") (net 1))
  (segment (start 131.384 84.234) (end 131.58 84.234) (width 0.1) (layer "F.Cu") (net 1))
  (segment (start 132.96 74.31) (end 132.95 74.3) (width 0.1) (layer "F.Cu") (net 1))
  (segment (start 154.89 65.35) (end 154.89 65.21) (width 0.1) (layer "F.Cu") (net 1))
  (segment (start 138.375 76.925) (end 138.05 76.6) (width 0.1) (layer "F.Cu") (net 1))
  (segment (start 156.39 62.35) (end 156.64 62.6) (width 0.1) (layer "F.Cu") (net 1))
  (segment (start 139.86 74.79) (end 139.4 74.79) (width 0.1) (layer "F.Cu") (net 1))
  (segment (start 116.659001 63.095) (end 116.659001 63.686) (width 0.25) (layer "F.Cu") (net 1))
  (segment (start 136.1 83.75) (end 135.775 83.425) (width 0.1) (layer "F.Cu") (net 1))
  (segment (start 138.05 78.55) (end 138.7 77.9) (width 0.1) (layer "F.Cu") (net 1))
  (segment (start 135.72 74.79) (end 135.72 74.72) (width 0.1) (layer "F.Cu") (net 1))
  (segment (start 156.89 62.85) (end 157.14 62.6) (width 0.1) (layer "F.Cu") (net 1))
  (segment (start 154.89 65.21) (end 155.13 64.97) (width 0.1) (layer "F.Cu") (net 1))
  (segment (start 130.66 83.99) (end 130.66 84.234) (width 0.1) (layer "F.Cu") (net 1))
  (segment (start 130.2 78.01) (end 129.345 78.01) (width 0.1) (layer "F.Cu") (net 1))
  (segment (start 137.4 81.8) (end 137.725 81.475) (width 0.1) (layer "F.Cu") (net 1))
  (segment (start 133.42 84.91) (end 133.42 84.45) (width 0.1) (layer "F.Cu") (net 1))
  (segment (start 132.2 76.6) (end 132.525 76.925) (width 0.1) (layer "F.Cu") (net 1))
  (segment (start 132.5 84.45) (end 132.5 84.234) (width 0.1) (layer "F.Cu") (net 1))
  (segment (start 140.5 94.545046) (end 141 94.045046) (width 0.4) (layer "F.Cu") (net 1))
  (segment (start 138.05 77.25) (end 137.4 76.6) (width 0.1) (layer "F.Cu") (net 1))
  (segment (start 136.425 80.175) (end 136.75 79.85) (width 0.1) (layer "F.Cu") (net 1))
  (segment (start 129.74 80.77) (end 130.2 80.77) (width 0.1) (layer "F.Cu") (net 1))
  (segment (start 136.75 76.6) (end 136.425 76.275) (width 0.1) (layer "F.Cu") (net 1))
  (segment (start 138.975 82.185) (end 138.975 82.175) (width 0.1) (layer "F.Cu") (net 1))
  (segment (start 131.55 77.25) (end 131.875 77.575) (width 0.1) (layer "F.Cu") (net 1))
  (segment (start 137.1 84.1) (end 137.1 84.234) (width 0.1) (layer "F.Cu") (net 1))
  (segment (start 136.1 83.75) (end 136.425 83.425) (width 0.1) (layer "F.Cu") (net 1))
  (segment (start 138.7 82.45) (end 138.975 82.175) (width 0.1) (layer "F.Cu") (net 1))
  (segment (start 138.05 78.55) (end 137.725 78.875) (width 0.1) (layer "F.Cu") (net 1))
  (segment (start 136.1 79.85) (end 136.425 80.175) (width 0.1) (layer "F.Cu") (net 1))
  (segment (start 133.825 80.825) (end 134.15 81.15) (width 0.1) (layer "F.Cu") (net 1))
  (segment (start 112.79602 79.338) (end 112.803808 79.330212) (width 0.1) (layer "F.Cu") (net 1))
  (segment (start 138.05 77.9) (end 138.7 77.25) (width 0.1) (layer "F.Cu") (net 1))
  (segment (start 131.55 80.5) (end 130.9 80.5) (width 0.1) (layer "F.Cu") (net 1))
  (segment (start 131.716 84.234) (end 131.58 84.234) (width 0.1) (layer "F.Cu") (net 1))
  (segment (start 129.345 78.01) (end 129.343 78.012) (width 0.1) (layer "F.Cu") (net 1))
  (segment (start 134.475 76.275) (end 134.15 76.6) (width 0.1) (layer "F.Cu") (net 1))
  (segment (start 157.89 61.56) (end 158.08 61.37) (width 0.1) (layer "F.Cu") (net 1))
  (segment (start 161.651 71.754922) (end 161.625 71.728922) (width 0.1) (layer "F.Cu") (net 1))
  (segment (start 162.085 80.404922) (end 161.776 80.404922) (width 0.1) (layer "F.Cu") (net 1))
  (segment (start 138.375 79.525) (end 138.05 79.2) (width 0.1) (layer "F.Cu") (net 1))
  (segment (start 158.27 61.97) (end 157.89 62.35) (width 0.1) (layer "F.Cu") (net 1))
  (segment (start 132.85 81.8) (end 132.525 81.475) (width 0.1) (layer "F.Cu") (net 1))
  (segment (start 129.74 81.69) (end 129.99 81.69) (width 0.1) (layer "F.Cu") (net 1))
  (segment (start 136.425 78.225) (end 136.1 77.9) (width 0.1) (layer "F.Cu") (net 1))
  (segment (start 139.86 82.61) (end 139.4 82.61) (width 0.1) (layer "F.Cu") (net 1))
  (segment (start 139.184 82.61) (end 138.86 82.61) (width 0.1) (layer "F.Cu") (net 1))
  (segment (start 157.89 62.35) (end 157.64 62.6) (width 0.1) (layer "F.Cu") (net 1))
  (segment (start 129.74 75.25) (end 129.74 74.79) (width 0.1) (layer "F.Cu") (net 1))
  (segment (start 138.05 81.15) (end 138.375 81.475) (width 0.1) (layer "F.Cu") (net 1))
  (segment (start 136.18 84.91) (end 136.18 84.45) (width 0.1) (layer "F.Cu") (net 1))
  (segment (start 132.2 78.55) (end 132.525 78.225) (width 0.1) (layer "F.Cu") (net 1))
  (segment (start 137.4 76.6) (end 137.075 76.275) (width 0.1) (layer "F.Cu") (net 1))
  (segment (start 134.8 79.2) (end 134.475 78.875) (width 0.1) (layer "F.Cu") (net 1))
  (segment (start 136.64 74.7) (end 136.19 74.25) (width 0.1) (layer "F.Cu") (net 1))
  (segment (start 139.4 80.77) (end 139.86 80.77) (width 0.1) (layer "F.Cu") (net 1))
  (segment (start 138.375 78.875) (end 138.7 79.2) (width 0.1) (layer "F.Cu") (net 1))
  (segment (start 133.5 84.154) (end 133.42 84.234) (width 0.1) (layer "F.Cu") (net 1))
  (segment (start 131.55 76.6) (end 131.875 76.925) (width 0.1) (layer "F.Cu") (net 1))
  (segment (start 134.8 83.1) (end 134.475 83.425) (width 0.1) (layer "F.Cu") (net 1))
  (segment (start 134.15 83.75) (end 134.475 84.075) (width 0.1) (layer "F.Cu") (net 1))
  (segment (start 134.15 78.55) (end 134.475 78.875) (width 0.1) (layer "F.Cu") (net 1))
  (segment (start 138.02 84.45) (end 138.02 84.234) (width 0.1) (layer "F.Cu") (net 1))
  (segment (start 156.89 62.85) (end 156.64 63.1) (width 0.1) (layer "F.Cu") (net 1))
  (segment (start 139.86 81.69) (end 139.4 81.69) (width 0.1) (layer "F.Cu") (net 1))
  (segment (start 132.2 81.15) (end 132.525 81.475) (width 0.1) (layer "F.Cu") (net 1))
  (segment (start 139.4 78.93) (end 139.08 78.93) (width 0.1) (layer "F.Cu") (net 1))
  (segment (start 157.39 62.35) (end 157.64 62.6) (width 0.1) (layer "F.Cu") (net 1))
  (segment (start 132.2 76.6) (end 131.875 76.925) (width 0.1) (layer "F.Cu") (net 1))
  (segment (start 137.1 84.45) (end 137.1 84.234) (width 0.1) (layer "F.Cu") (net 1))
  (segment (start 130.2 77.09) (end 129.984 77.09) (width 0.1) (layer "F.Cu") (net 1))
  (segment (start 132.5 94.55) (end 133 94.05) (width 0.4) (layer "F.Cu") (net 1))
  (segment (start 116.659001 63.686) (end 116.659001 62.986) (width 0.25) (layer "F.Cu") (net 1))
  (segment (start 130.2 78.93) (end 130.66 78.47) (width 0.1) (layer "F.Cu") (net 1))
  (segment (start 131.55 77.25) (end 131.875 76.925) (width 0.1) (layer "F.Cu") (net 1))
  (segment (start 155.894 63.97) (end 155.894 63.854) (width 0.1) (layer "F.Cu") (net 1))
  (segment (start 136.1 81.15) (end 136.75 80.5) (width 0.1) (layer "F.Cu") (net 1))
  (segment (start 133.42 84.45) (end 133.42 84.234) (width 0.1) (layer "F.Cu") (net 1))
  (segment (start 135.5 97.075046) (end 135.5 94.55) (width 0.4) (layer "F.Cu") (net 1))
  (segment (start 132.2 81.15) (end 132.525 80.825) (width 0.1) (layer "F.Cu") (net 1))
  (segment (start 138.975 80.225) (end 138.7 80.5) (width 0.1) (layer "F.Cu") (net 1))
  (segment (start 134.8 79.2) (end 134.475 79.525) (width 0.1) (layer "F.Cu") (net 1))
  (segment (start 132.85 77.25) (end 132.525 77.575) (width 0.1) (layer "F.Cu") (net 1))
  (segment (start 137.1 84.91) (end 137.1 84.45) (width 0.1) (layer "F.Cu") (net 1))
  (segment (start 156.89 62.35) (end 156.64 62.6) (width 0.1) (layer "F.Cu") (net 1))
  (segment (start 140.5 97.075046) (end 140.5 94.545046) (width 0.4) (layer "F.Cu") (net 1))
  (segment (start 157.39 62.85) (end 157.64 62.6) (width 0.1) (layer "F.Cu") (net 1))
  (segment (start 134.8 79.85) (end 134.475 79.525) (width 0.1) (layer "F.Cu") (net 1))
  (segment (start 132.85 83.75) (end 133.334 84.234) (width 0.1) (layer "F.Cu") (net 1))
  (segment (start 134.99 83.94) (end 134.8 83.75) (width 0.1) (layer "F.Cu") (net 1))
  (segment (start 134.475 76.925) (end 134.8 76.6) (width 0.1) (layer "F.Cu") (net 1))
  (segment (start 157.14 63.1) (end 156.89 62.85) (width 0.1) (layer "F.Cu") (net 1))
  (segment (start 138.94 84.040331) (end 138.94 84.234) (width 0.1) (layer "F.Cu") (net 1))
  (segment (start 131.55 84.204) (end 131.58 84.234) (width 0.1) (layer "F.Cu") (net 1))
  (segment (start 132.85 77.9) (end 132.525 77.575) (width 0.1) (layer "F.Cu") (net 1))
  (segment (start 158.31 61.85) (end 158.43 61.97) (width 0.1) (layer "F.Cu") (net 1))
  (segment (start 138.94 84.91) (end 138.94 84.45) (width 0.1) (layer "F.Cu") (net 1))
  (segment (start 136.1 76.6) (end 135.775 76.275) (width 0.1) (layer "F.Cu") (net 1))
  (segment (start 130.2 78.93) (end 129.984 78.93) (width 0.1) (layer "F.Cu") (net 1))
  (segment (start 157.89 61.85) (end 157.89 61.56) (width 0.1) (layer "F.Cu") (net 1))
  (segment (start 135.775 76.275) (end 135.45 76.6) (width 0.1) (layer "F.Cu") (net 1))
  (segment (start 136.75 83.75) (end 136.425 83.425) (width 0.1) (layer "F.Cu") (net 1))
  (segment (start 132.5 84.91) (end 132.5 84.45) (width 0.1) (layer "F.Cu") (net 1))
  (segment (start 138.81 81.69) (end 138.7 81.8) (width 0.1) (layer "F.Cu") (net 1))
  (segment (start 132.2 77.9) (end 132.525 77.575) (width 0.1) (layer "F.Cu") (net 1))
  (segment (start 140.281123 80.77) (end 140.445623 80.6055) (width 0.1) (layer "F.Cu") (net 1))
  (segment (start 135.72 74.72) (end 136.19 74.25) (width 0.1) (layer "F.Cu") (net 1))
  (segment (start 157.39 63.35) (end 157.14 63.1) (width 0.1) (layer "F.Cu") (net 1))
  (segment (start 139.4 83.53) (end 139.4 83.580331) (width 0.1) (layer "F.Cu") (net 1))
  (segment (start 129.74 83.53) (end 130.2 83.53) (width 0.1) (layer "F.Cu") (net 1))
  (segment (start 136.18 84.234) (end 136.1 84.154) (width 0.1) (layer "F.Cu") (net 1))
  (segment (start 135.125 76.275) (end 134.8 76.6) (width 0.1) (layer "F.Cu") (net 1))
  (segment (start 132.2 77.25) (end 131.875 76.925) (width 0.1) (layer "F.Cu") (net 1))
  (segment (start 134.15 78.55) (end 134.475 78.225) (width 0.1) (layer "F.Cu") (net 1))
  (segment (start 130.2 74.79) (end 129.74 74.79) (width 0.1) (layer "F.Cu") (net 1))
  (segment (start 134.15 80.5) (end 133.825 80.825) (width 0.1) (layer "F.Cu") (net 1))
  (segment (start 112.47 84.962) (end 112.137 84.962) (width 0.1) (layer "F.Cu") (net 1))
  (segment (start 156.89 62.85) (end 156.64 62.6) (width 0.1) (layer "F.Cu") (net 1))
  (segment (start 138.7 79.2) (end 139.025 78.875) (width 0.1) (layer "F.Cu") (net 1))
  (segment (start 136.64 75.25) (end 136.64 74.79) (width 0.1) (layer "F.Cu") (net 1))
  (segment (start 136.1 80.5) (end 136.425 80.175) (width 0.1) (layer "F.Cu") (net 1))
  (segment (start 134.15 79.2) (end 134.475 79.525) (width 0.1) (layer "F.Cu") (net 1))
  (segment (start 132.85 76.6) (end 132.525 76.925) (width 0.1) (layer "F.Cu") (net 1))
  (segment (start 130.2 79.85) (end 130.66 80.31) (width 0.1) (layer "F.Cu") (net 1))
  (segment (start 134.15 80.5) (end 134.475 80.175) (width 0.1) (layer "F.Cu") (net 1))
  (segment (start 154.39 65.35) (end 154.51 65.35) (width 0.1) (layer "F.Cu") (net 1))
  (segment (start 139.4 75.25) (end 139.4 74.79) (width 0.1) (layer "F.Cu") (net 1))
  (segment (start 115.130001 65.79) (end 114.865001 66.055) (width 0.25) (layer "F.Cu") (net 1))
  (segment (start 139.08 80.77) (end 139.025 80.825) (width 0.1) (layer "F.Cu") (net 1))
  (segment (start 146.575 71.59) (end 147.335 71.59) (width 0.1) (layer "F.Cu") (net 1))
  (segment (start 131.55 77.9) (end 131.875 77.575) (width 0.1) (layer "F.Cu") (net 1))
  (segment (start 139.86 84.45) (end 139.4 84.45) (width 0.1) (layer "F.Cu") (net 1))
  (segment (start 132.2 77.9) (end 132.525 78.225) (width 0.1) (layer "F.Cu") (net 1))
  (segment (start 132.2 77.25) (end 132.525 77.575) (width 0.1) (layer "F.Cu") (net 1))
  (segment (start 134.15 77.9) (end 134.475 77.575) (width 0.1) (layer "F.Cu") (net 1))
  (segment (start 136.425 76.275) (end 136.1 76.6) (width 0.1) (layer "F.Cu") (net 1))
  (segment (start 134.15 79.2) (end 134.475 78.875) (width 0.1) (layer "F.Cu") (net 1))
  (segment (start 108.513 84.962) (end 108.512024 84.962) (width 0.1) (layer "F.Cu") (net 1))
  (segment (start 139.4 80.77) (end 139.08 80.77) (width 0.1) (layer "F.Cu") (net 1))
  (segment (start 136.18 84.45) (end 136.18 84.234) (width 0.1) (layer "F.Cu") (net 1))
  (segment (start 139.025 78.225) (end 138.7 78.549999) (width 0.1) (layer "F.Cu") (net 1))
  (segment (start 156.39 63.35) (end 156.64 63.1) (width 0.1) (layer "F.Cu") (net 1))
  (segment (start 135.45 81.15) (end 135.125 80.825) (width 0.1) (layer "F.Cu") (net 1))
  (segment (start 138.7 76.6) (end 138.375 76.275) (width 0.1) (layer "F.Cu") (net 1))
  (segment (start 139.4 82.61) (end 139.184 82.61) (width 0.1) (layer "F.Cu") (net 1))
  (segment (start 155.01 64.97) (end 155.13 64.97) (width 0.1) (layer "F.Cu") (net 1))
  (segment (start 134.8 75.25) (end 134.8 74.79) (width 0.1) (layer "F.Cu") (net 1))
  (segment (start 136.1 80.5) (end 135.45 81.15) (width 0.1) (layer "F.Cu") (net 1))
  (segment (start 135.26 83.94) (end 135.45 83.75) (width 0.1) (layer "F.Cu") (net 1))
  (segment (start 130.9 83.75) (end 130.66 83.99) (width 0.1) (layer "F.Cu") (net 1))
  (segment (start 156.39 62.85) (end 156.64 63.1) (width 0.1) (layer "F.Cu") (net 1))
  (segment (start 135.45 80.5) (end 136.1 81.15) (width 0.1) (layer "F.Cu") (net 1))
  (segment (start 136.75 81.8) (end 137.075 81.475) (width 0.1) (layer "F.Cu") (net 1))
  (segment (start 138.7 77.9) (end 138.05 77.25) (width 0.1) (layer "F.Cu") (net 1))
  (segment (start 157.89 61.85) (end 157.89 62.35) (width 0.1) (layer "F.Cu") (net 1))
  (segment (start 156.39 62.85) (end 156.64 62.6) (width 0.1) (layer "F.Cu") (net 1))
  (segment (start 137.1 84.05) (end 137.1 84.234) (width 0.1) (layer "F.Cu") (net 1))
  (segment (start 138.375 79.525) (end 138.7 79.2) (width 0.1) (layer "F.Cu") (net 1))
  (segment (start 133.5 83.75) (end 133.5 84.154) (width 0.1) (layer "F.Cu") (net 1))
  (segment (start 137.725 78.875) (end 137.4 78.55) (width 0.1) (layer "F.Cu") (net 1))
  (segment (start 158.43 61.97) (end 158.27 61.97) (width 0.1) (layer "F.Cu") (net 1))
  (segment (start 138.375 76.925) (end 138.05 77.25) (width 0.1) (layer "F.Cu") (net 1))
  (segment (start 139.4 83.580331) (end 138.94 84.040331) (width 0.1) (layer "F.Cu") (net 1))
  (segment (start 162.085 71.754922) (end 161.651 71.754922) (width 0.1) (layer "F.Cu") (net 1))
  (segment (start 143.5 97.075046) (end 143.5 94.545046) (width 0.4) (layer "F.Cu") (net 1))
  (segment (start 157.39 63.35) (end 157.64 63.1) (width 0.1) (layer "F.Cu") (net 1))
  (segment (start 155.894 63.854) (end 155.89 63.85) (width 0.1) (layer "F.Cu") (net 1))
  (segment (start 138.05 81.8) (end 138.375 82.125) (width 0.1) (layer "F.Cu") (net 1))
  (segment (start 132.96 75.25) (end 132.96 74.31) (width 0.1) (layer "F.Cu") (net 1))
  (segment (start 136.1 83.1) (end 136.425 82.775) (width 0.1) (layer "F.Cu") (net 1))
  (segment (start 136.75 81.15) (end 136.1 80.5) (width 0.1) (layer "F.Cu") (net 1))
  (segment (start 135.5 94.55) (end 135 94.05) (width 0.4) (layer "F.Cu") (net 1))
  (segment (start 137.075 76.275) (end 136.75 76.6) (width 0.1) (layer "F.Cu") (net 1))
  (segment (start 132.85 81.8) (end 132.525 82.125) (width 0.1) (layer "F.Cu") (net 1))
  (segment (start 135.934 84.234) (end 135.45 83.75) (width 0.1) (layer "F.Cu") (net 1))
  (segment (start 134.15 76.6) (end 134.475 76.925) (width 0.1) (layer "F.Cu") (net 1))
  (segment (start 136.64 74.79) (end 136.64 74.7) (width 0.1) (layer "F.Cu") (net 1))
  (segment (start 139.4 79.85) (end 139.25 79.85) (width 0.1) (layer "F.Cu") (net 1))
  (segment (start 139.4 84.45) (end 138.94 84.45) (width 0.1) (layer "F.Cu") (net 1))
  (segment (start 108.750002 66.055) (end 111.110001 66.055) (width 0.25) (layer "F.Cu") (net 1))
  (segment (start 134.15 79.85) (end 134.475 79.525) (width 0.1) (layer "F.Cu") (net 1))
  (segment (start 155.39 65.23) (end 155.13 64.97) (width 0.1) (layer "F.Cu") (net 1))
  (segment (start 137.4 83.75) (end 137.1 84.05) (width 0.1) (layer "F.Cu") (net 1))
  (segment (start 139.184 81.634) (end 138.7 81.15) (width 0.1) (layer "F.Cu") (net 1))
  (segment (start 131.875 76.275) (end 132.2 76.6) (width 0.1) (layer "F.Cu") (net 1))
  (segment (start 130.2 83.53) (end 130.68 83.53) (width 0.1) (layer "F.Cu") (net 1))
  (segment (start 138.375 76.925) (end 138.7 76.6) (width 0.1) (layer "F.Cu") (net 1))
  (segment (start 156.89 63.35) (end 157.14 63.1) (width 0.1) (layer "F.Cu") (net 1))
  (segment (start 130.85 80.5) (end 130.66 80.31) (width 0.1) (layer "F.Cu") (net 1))
  (segment (start 138.7 81.8) (end 139.025 82.125) (width 0.1) (layer "F.Cu") (net 1))
  (segment (start 132.2 77.25) (end 132.525 76.925) (width 0.1) (layer "F.Cu") (net 1))
  (segment (start 157.89 60.85) (end 157.89 61.18) (width 0.1) (layer "F.Cu") (net 1))
  (segment (start 137.725 76.275) (end 138.05 76.6) (width 0.1) (layer "F.Cu") (net 1))
  (segment (start 139.08 78.93) (end 139.025 78.875) (width 0.1) (layer "F.Cu") (net 1))
  (segment (start 127.5 97.075046) (end 127.5 94.55) (width 0.4) (layer "F.Cu") (net 1))
  (segment (start 132.5 84.05) (end 132.5 84.234) (width 0.1) (layer "F.Cu") (net 1))
  (segment (start 139.185 78.225) (end 139.025 78.225) (width 0.1) (layer "F.Cu") (net 1))
  (segment (start 154.274 60.35) (end 153.91 59.986) (width 0.1) (layer "F.Cu") (net 1))
  (segment (start 135.26 84.91) (end 135.26 84.45) (width 0.1) (layer "F.Cu") (net 1))
  (segment (start 157.39 62.85) (end 157.14 62.6) (width 0.1) (layer "F.Cu") (net 1))
  (segment (start 139.25 79.85) (end 138.975 80.125) (width 0.1) (layer "F.Cu") (net 1))
  (segment (start 136.75 81.15) (end 137.075 81.475) (width 0.1) (layer "F.Cu") (net 1))
  (segment (start 139.5 94.545046) (end 139 94.045046) (width 0.4) (layer "F.Cu") (net 1))
  (segment (start 157.89 61.85) (end 158.31 61.85) (width 0.1) (layer "F.Cu") (net 1))
  (segment (start 138.7 78.55) (end 138.05 77.9) (width 0.1) (layer "F.Cu") (net 1))
  (segment (start 138.7 81.15) (end 138.375 81.475) (width 0.1) (layer "F.Cu") (net 1))
  (segment (start 139.4 82.61) (end 138.975 82.185) (width 0.1) (layer "F.Cu") (net 1))
  (segment (start 130.9 83.75) (end 131.384 84.234) (width 0.1) (layer "F.Cu") (net 1))
  (segment (start 131.55 77.9) (end 132.2 78.55) (width 0.1) (layer "F.Cu") (net 1))
  (segment (start 134.15 80.5) (end 133.825 80.175) (width 0.1) (layer "F.Cu") (net 1))
  (segment (start 133.334 84.234) (end 133.42 84.234) (width 0.1) (layer "F.Cu") (net 1))
  (segment (start 136.75 80.5) (end 136.425 80.175) (width 0.1) (layer "F.Cu") (net 1))
  (segment (start 130.9 80.5) (end 130.85 80.5) (width 0.1) (layer "F.Cu") (net 1))
  (segment (start 157.64 63.1) (end 157.39 62.85) (width 0.1) (layer "F.Cu") (net 1))
  (segment (start 143.5 94.545046) (end 144 94.045046) (width 0.4) (layer "F.Cu") (net 1))
  (segment (start 134.34 84.91) (end 134.34 84.45) (width 0.1) (layer "F.Cu") (net 1))
  (segment (start 129.74 75.25) (end 130.2 75.25) (width 0.1) (layer "F.Cu") (net 1))
  (segment (start 108.512024 84.962) (end 108.111337 85.362687) (width 0.1) (layer "F.Cu") (net 1))
  (segment (start 114.865001 66.055) (end 113.470001 66.055) (width 0.25) (layer "F.Cu") (net 1))
  (segment (start 158.89 64.85) (end 158.39 64.85) (width 0.1) (layer "F.Cu") (net 1))
  (segment (start 138.375 81.475) (end 138.7 81.8) (width 0.1) (layer "F.Cu") (net 1))
  (segment (start 154.39 60.35) (end 154.274 60.35) (width 0.1) (layer "F.Cu") (net 1))
  (segment (start 132.85 77.9) (end 132.525 78.225) (width 0.1) (layer "F.Cu") (net 1))
  (segment (start 132.85 76.6) (end 133.175 76.275) (width 0.1) (layer "F.Cu") (net 1))
  (segment (start 155.39 64.85) (end 155.27 64.97) (width 0.1) (layer "F.Cu") (net 1))
  (segment (start 133.825 80.175) (end 134.15 79.85) (width 0.1) (layer "F.Cu") (net 1))
  (segment (start 137.075 81.475) (end 137.4 81.8) (width 0.1) (layer "F.Cu") (net 1))
  (segment (start 136.5 97.075046) (end 136.5 94.55) (width 0.4) (layer "F.Cu") (net 1))
  (segment (start 130.9 78.55) (end 130.74 78.55) (width 0.1) (layer "F.Cu") (net 1))
  (segment (start 131.55 82.45) (end 132.2 81.8) (width 0.1) (layer "F.Cu") (net 1))
  (segment (start 136.1 82.45) (end 135.775 82.775) (width 0.1) (layer "F.Cu") (net 1))
  (segment (start 132.2 77.25) (end 131.875 77.575) (width 0.1) (layer "F.Cu") (net 1))
  (segment (start 154.89 65.35) (end 154.51 65.35) (width 0.1) (layer "F.Cu") (net 1))
  (segment (start 132.85 80.5) (end 133.175 80.175) (width 0.1) (layer "F.Cu") (net 1))
  (segment (start 138.7 79.85) (end 138.975 80.125) (width 0.1) (layer "F.Cu") (net 1))
  (segment (start 136.75 77.9) (end 136.425 78.225) (width 0.1) (layer "F.Cu") (net 1))
  (segment (start 108.513 79.338) (end 107.868394 79.338) (width 0.1) (layer "F.Cu") (net 1))
  (segment (start 138.05 81.8) (end 138.375 81.475) (width 0.1) (layer "F.Cu") (net 1))
  (segment (start 134.475 80.175) (end 134.8 79.85) (width 0.1) (layer "F.Cu") (net 1))
  (segment (start 157.14 63.1) (end 157.39 62.85) (width 0.1) (layer "F.Cu") (net 1))
  (segment (start 139.4 77.09) (end 139.86 77.09) (width 0.1) (layer "F.Cu") (net 1))
  (segment (start 130.5 97.075046) (end 130.5 94.05) (width 0.4) (layer "F.Cu") (net 1))
  (segment (start 116.659001 62.300499) (end 116.66 62.2995) (width 0.25) (layer "F.Cu") (net 1))
  (via (at 121.799 75.171) (size 0.45) (drill 0.1) (layers "F.Cu" "B.Cu") (net 1))
  (via (at 107.34 91.61) (size 0.45) (drill 0.1) (layers "F.Cu" "B.Cu") (net 1))
  (via (at 162.25 91) (size 0.45) (drill 0.1) (layers "F.Cu" "B.Cu") (net 1))
  (via (at 111.241 80.65) (size 0.45) (drill 0.1) (layers "F.Cu" "B.Cu") (net 1))
  (via (at 158.259249 73.969249) (size 0.45) (drill 0.1) (layers "F.Cu" "B.Cu") (net 1))
  (via (at 138.51019 87.87981) (size 0.45) (drill 0.1) (layers "F.Cu" "B.Cu") (net 1))
  (via (at 138.225 70.235) (size 0.45) (drill 0.1) (layers "F.Cu" "B.Cu") (net 1))
  (via (at 115.299999 93.29) (size 0.45) (drill 0.1) (layers "F.Cu" "B.Cu") (net 1))
  (via (at 140.08981 87.42019) (size 0.45) (drill 0.1) (layers "F.Cu" "B.Cu") (net 1))
  (via (at 161.625 80.253922) (size 0.45) (drill 0.1) (layers "F.Cu" "B.Cu") (net 1))
  (via (at 116.720002 79.2) (size 0.45) (drill 0.1) (layers "F.Cu" "B.Cu") (net 1))
  (via (at 139.58333 51.099998) (size 0.45) (drill 0.1) (layers "F.Cu" "B.Cu") (net 1))
  (via (at 116 54) (size 0.45) (drill 0.1) (layers "F.Cu" "B.Cu") (net 1))
  (via (at 135.349998 57.100001) (size 0.45) (drill 0.1) (layers "F.Cu" "B.Cu") (net 1))
  (via (at 129.984 79.85) (size 0.45) (drill 0.1) (layers "F.Cu" "B.Cu") (net 1))
  (via (at 124.5 69) (size 0.45) (drill 0.1) (layers "F.Cu" "B.Cu") (net 1))
  (via (at 134.03981 90.32981) (size 0.45) (drill 0.1) (layers "F.Cu" "B.Cu") (net 1))
  (via (at 115.130001 59.39) (size 0.45) (drill 0.1) (layers "F.Cu" "B.Cu") (net 1))
  (via (at 163.71 66.77) (size 0.45) (drill 0.1) (layers "F.Cu" "B.Cu") (net 1))
  (via (at 148 60) (size 0.45) (drill 0.1) (layers "F.Cu" "B.Cu") (net 1))
  (via (at 134.433856 64.202) (size 0.45) (drill 0.1) (layers "F.Cu" "B.Cu") (net 1))
  (via (at 108.530001 67.89) (size 0.45) (drill 0.1) (layers "F.Cu" "B.Cu") (net 1))
  (via (at 110.65 83.2025) (size 0.45) (drill 0.1) (layers "F.Cu" "B.Cu") (net 1))
  (via (at 161.625 80.803922) (size 0.45) (drill 0.1) (layers "F.Cu" "B.Cu") (net 1))
  (via (at 116.630001 57.79) (size 0.45) (drill 0.1) (layers "F.Cu" "B.Cu") (net 1))
  (via (at 152.539619 83.450287) (size 0.45) (drill 0.1) (layers "F.Cu" "B.Cu") (net 1))
  (via (at 103.335 77.3125) (size 0.45) (drill 0.1) (layers "F.Cu" "B.Cu") (net 1))
  (via (at 137.466664 57.100001) (size 0.45) (drill 0.1) (layers "F.Cu" "B.Cu") (net 1))
  (via (at 158.43 61.97) (size 0.45) (drill 0.1) (layers "F.Cu" "B.Cu") (net 1))
  (via (at 155.5 69.5) (size 0.45) (drill 0.1) (layers "F.Cu" "B.Cu") (net 1))
  (via (at 137.1 84.234) (size 0.45) (drill 0.1) (layers "F.Cu" "B.Cu") (net 1))
  (via (at 124.099 76.97) (size 0.45) (drill 0.1) (layers "F.Cu" "B.Cu") (net 1))
  (via (at 136.12019 89.88981) (size 0.45) (drill 0.1) (layers "F.Cu" "B.Cu") (net 1))
  (via (at 129 55.1) (size 0.45) (drill 0.1) (layers "F.Cu" "B.Cu") (net 1))
  (via (at 102.39 87.940001) (size 0.45) (drill 0.1) (layers "F.Cu" "B.Cu") (net 1))
  (via (at 135 94.05) (size 0.45) (drill 0.1) (layers "F.Cu" "B.Cu") (net 1))
  (via (at 138.94 84.234) (size 0.45) (drill 0.1) (layers "F.Cu" "B.Cu") (net 1))
  (via (at 162.175 70.628922) (size 0.45) (drill 0.1) (layers "F.Cu" "B.Cu") (net 1))
  (via (at 148.05 57.100001) (size 0.45) (drill 0.1) (layers "F.Cu" "B.Cu") (net 1))
  (via (at 110 54) (size 0.45) (drill 0.1) (layers "F.Cu" "B.Cu") (net 1))
  (via (at 129.99 82.61) (size 0.45) (drill 0.1) (layers "F.Cu" "B.Cu") (net 1))
  (via (at 158 69) (size 0.45) (drill 0.1) (layers "F.Cu" "B.Cu") (net 1))
  (via (at 107 69) (size 0.45) (drill 0.1) (layers "F.Cu" "B.Cu") (net 1))
  (via (at 141.15 76.914) (size 0.45) (drill 0.1) (layers "F.Cu" "B.Cu") (net 1))
  (via (at 110 82.475) (size 0.45) (drill 0.1) (layers "F.Cu" "B.Cu") (net 1))
  (via (at 135.775 82.125) (size 0.45) (drill 0.1) (layers "F.Cu" "B.Cu") (net 1))
  (via (at 157.14 63.1) (size 0.45) (drill 0.1) (layers "F.Cu" "B.Cu") (net 1))
  (via (at 158.684953 80.852843) (size 0.45) (drill 0.1) (layers "F.Cu" "B.Cu") (net 1))
  (via (at 104.735 77.3125) (size 0.45) (drill 0.1) (layers "F.Cu" "B.Cu") (net 1))
  (via (at 154 96) (size 0.45) (drill 0.1) (layers "F.Cu" "B.Cu") (net 1))
  (via (at 162.725 70.628922) (size 0.45) (drill 0.1) (layers "F.Cu" "B.Cu") (net 1))
  (via (at 113 51) (size 0.45) (drill 0.1) (layers "F.Cu" "B.Cu") (net 1))
  (via (at 162.879249 69.21925) (size 0.45) (drill 0.1) (layers "F.Cu" "B.Cu") (net 1))
  (via (at 105.295 77.3125) (size 0.45) (drill 0.1) (layers "F.Cu" "B.Cu") (net 1))
  (via (at 152.945 65.42) (size 0.45) (drill 0.1) (layers "F.Cu" "B.Cu") (net 1))
  (via (at 110 80.365) (size 0.45) (drill 0.1) (layers "F.Cu" "B.Cu") (net 1))
  (via (at 116.630001 59.39) (size 0.45) (drill 0.1) (layers "F.Cu" "B.Cu") (net 1))
  (via (at 115.975001 79.2) (size 0.45) (drill 0.1) (layers "F.Cu" "B.Cu") (net 1))
  (via (at 134.475 80.175) (size 0.45) (drill 0.1) (layers "F.Cu" "B.Cu") (net 1))
  (via (at 133.175 80.175) (size 0.45) (drill 0.1) (layers "F.Cu" "B.Cu") (net 1))
  (via (at 129 51.099998) (size 0.45) (drill 0.1) (layers "F.Cu" "B.Cu") (net 1))
  (via (at 169 63) (size 0.45) (drill 0.1) (layers "F.Cu" "B.Cu") (net 1))
  (via (at 116 72) (size 0.45) (drill 0.1) (layers "F.Cu" "B.Cu") (net 1))
  (via (at 103.335 76.7525) (size 0.45) (drill 0.1) (layers "F.Cu" "B.Cu") (net 1))
  (via (at 160.91 58.985) (size 0.45) (drill 0.1) (layers "F.Cu" "B.Cu") (net 1))
  (via (at 160.516 74.928922) (size 0.45) (drill 0.1) (layers "F.Cu" "B.Cu") (net 1))
  (via (at 116.330001 67.39) (size 0.45) (drill 0.1) (layers "F.Cu" "B.Cu") (net 1))
  (via (at 161.04 66.77) (size 0.45) (drill 0.1) (layers "F.Cu" "B.Cu") (net 1))
  (via (at 162.799999 91.55) (size 0.45) (drill 0.1) (layers "F.Cu" "B.Cu") (net 1))
  (via (at 145 63) (size 0.45) (drill 0.1) (layers "F.Cu" "B.Cu") (net 1))
  (via (at 143.56019 79.175144) (size 0.45) (drill 0.1) (layers "F.Cu" "B.Cu") (net 1))
  (via (at 129.99 81.69) (size 0.45) (drill 0.1) (layers "F.Cu" "B.Cu") (net 1))
  (via (at 162.872312 67.677688) (size 0.45) (drill 0.1) (layers "F.Cu" "B.Cu") (net 1))
  (via (at 154.274953 74.679619) (size 0.45) (drill 0.1) (layers "F.Cu" "B.Cu") (net 1))
  (via (at 155.235334 84.79) (size 0.45) (drill 0.1) (layers "F.Cu" "B.Cu") (net 1))
  (via (at 132.95 74.3) (size 0.45) (drill 0.1) (layers "F.Cu" "B.Cu") (net 1))
  (via (at 160 96) (size 0.45) (drill 0.1) (layers "F.Cu" "B.Cu") (net 1))
  (via (at 169 82.3) (size 0.45) (drill 0.1) (layers "F.Cu" "B.Cu") (net 1))
  (via (at 135.125 76.275) (size 0.45) (drill 0.1) (layers "F.Cu" "B.Cu") (net 1))
  (via (at 156.64 62.6) (size 0.45) (drill 0.1) (layers "F.Cu" "B.Cu") (net 1))
  (via (at 101 57) (size 0.45) (drill 0.1) (layers "F.Cu" "B.Cu") (net 1))
  (via (at 110.830001 67.39) (size 0.45) (drill 0.1) (layers "F.Cu" "B.Cu") (net 1))
  (via (at 116.130001 57.79) (size 0.45) (drill 0.1) (layers "F.Cu" "B.Cu") (net 1))
  (via (at 131.805863 88.470862) (size 0.45) (drill 0.1) (layers "F.Cu" "B.Cu") (net 1))
  (via (at 109.399 80.65) (size 0.45) (drill 0.1) (layers "F.Cu" "B.Cu") (net 1))
  (via (at 169 69) (size 0.45) (drill 0.1) (layers "F.Cu" "B.Cu") (net 1))
  (via (at 115.630001 58.89) (size 0.45) (drill 0.1) (layers "F.Cu" "B.Cu") (net 1))
  (via (at 130.5 94.05) (size 0.45) (drill 0.1) (layers "F.Cu" "B.Cu") (net 1))
  (via (at 161.7 91) (size 0.45) (drill 0.1) (layers "F.Cu" "B.Cu") (net 1))
  (via (at 105.295 76.7525) (size 0.45) (drill 0.1) (layers "F.Cu" "B.Cu") (net 1))
  (via (at 151 51) (size 0.45) (drill 0.1) (layers "F.Cu" "B.Cu") (net 1))
  (via (at 153.639619 75.314953) (size 0.45) (drill 0.1) (layers "F.Cu" "B.Cu") (net 1))
  (via (at 125.764856 78.77981) (size 0.45) (drill 0.1) (layers "F.Cu" "B.Cu") (net 1))
  (via (at 113.230001 67.39) (size 0.45) (drill 0.1) (layers "F.Cu" "B.Cu") (net 1))
  (via (at 115.130001 65.79) (size 0.45) (drill 0.1) (layers "F.Cu" "B.Cu") (net 1))
  (via (at 110.65 80.365) (size 0.45) (drill 0.1) (layers "F.Cu" "B.Cu") (net 1))
  (via (at 104.73 75.52) (size 0.45) (drill 0.1) (layers "F.Cu" "B.Cu") (net 1))
  (via (at 152 70.5) (size 0.45) (drill 0.1) (layers "F.Cu" "B.Cu") (net 1))
  (via (at 130.66 84.234) (size 0.45) (drill 0.1) (layers "F.Cu" "B.Cu") (net 1))
  (via (at 160.516 76.928922) (size 0.45) (drill 0.1) (layers "F.Cu" "B.Cu") (net 1))
  (via (at 154.6 85.425334) (size 0.45) (drill 0.1) (layers "F.Cu" "B.Cu") (net 1))
  (via (at 110 83.2025) (size 0.45) (drill 0.1) (layers "F.Cu" "B.Cu") (net 1))
  (via (at 130.66 78.47) (size 0.45) (drill 0.1) (layers "F.Cu" "B.Cu") (net 1))
  (via (at 101 87) (size 0.45) (drill 0.1) (layers "F.Cu" "B.Cu") (net 1))
  (via (at 144.655144 78.08019) (size 0.45) (drill 0.1) (layers "F.Cu" "B.Cu") (net 1))
  (via (at 145.933328 51.099998) (size 0.45) (drill 0.1) (layers "F.Cu" "B.Cu") (net 1))
  (via (at 163 57) (size 0.45) (drill 0.1) (layers "F.Cu" "B.Cu") (net 1))
  (via (at 113.125 86.655) (size 0.45) (drill 0.1) (layers "F.Cu" "B.Cu") (net 1))
  (via (at 157 93) (size 0.45) (drill 0.1) (layers "F.Cu" "B.Cu") (net 1))
  (via (at 143.3 73) (size 0.45) (drill 0.1) (layers "F.Cu" "B.Cu") (net 1))
  (via (at 105.730001 67.39) (size 0.45) (drill 0.1) (layers "F.Cu" "B.Cu") (net 1))
  (via (at 139.86 74.79) (size 0.45) (drill 0.1) (layers "F.Cu" "B.Cu") (net 1))
  (via (at 133.825 80.175) (size 0.45) (drill 0.1) (layers "F.Cu" "B.Cu") (net 1))
  (via (at 160 54) (size 0.45) (drill 0.1) (layers "F.Cu" "B.Cu") (net 1))
  (via (at 131.116666 57.100001) (size 0.45) (drill 0.1) (layers "F.Cu" "B.Cu") (net 1))
  (via (at 162.25 91.549999) (size 0.45) (drill 0.1) (layers "F.Cu" "B.Cu") (net 1))
  (via (at 129 57.100001) (size 0.45) (drill 0.1) (layers "F.Cu" "B.Cu") (net 1))
  (via (at 136.425 78.225) (size 0.45) (drill 0.1) (layers "F.Cu" "B.Cu") (net 1))
  (via (at 111.330001 67.39) (size 0.45) (drill 0.1) (layers "F.Cu" "B.Cu") (net 1))
  (via (at 113.770003 79.2) (size 0.45) (drill 0.1) (layers "F.Cu" "B.Cu") (net 1))
  (via (at 114.79 93.8) (size 0.45) (drill 0.1) (layers "F.Cu" "B.Cu") (net 1))
  (via (at 157 51) (size 0.45) (drill 0.1) (layers "F.Cu" "B.Cu") (net 1))
  (via (at 135.775 76.275) (size 0.45) (drill 0.1) (layers "F.Cu" "B.Cu") (net 1))
  (via (at 104.73 74.96) (size 0.45) (drill 0.1) (layers "F.Cu" "B.Cu") (net 1))
  (via (at 151 99) (size 0.45) (drill 0.1) (layers "F.Cu" "B.Cu") (net 1))
  (via (at 137.466664 51.099998) (size 0.45) (drill 0.1) (layers "F.Cu" "B.Cu") (net 1))
  (via (at 129.74 84.45) (size 0.45) (drill 0.1) (layers "F.Cu" "B.Cu") (net 1))
  (via (at 157.14 62.6) (size 0.45) (drill 0.1) (layers "F.Cu" "B.Cu") (net 1))
  (via (at 133.233332 51.099998) (size 0.45) (drill 0.1) (layers "F.Cu" "B.Cu") (net 1))
  (via (at 153.18 73.584666) (size 0.45) (drill 0.1) (layers "F.Cu" "B.Cu") (net 1))
  (via (at 114.16 83.68) (size 0.45) (drill 0.1) (layers "F.Cu" "B.Cu") (net 1))
  (via (at 132.46019 89.87019) (size 0.45) (drill 0.1) (layers "F.Cu" "B.Cu") (net 1))
  (via (at 111.23 83.68) (size 0.45) (drill 0.1) (layers "F.Cu" "B.Cu") (net 1))
  (via (at 132.5 84.234) (size 0.45) (drill 0.1) (layers "F.Cu" "B.Cu") (net 1))
  (via (at 161.625 71.178922) (size 0.45) (drill 0.1) (layers "F.Cu" "B.Cu") (net 1))
  (via (at 169 51) (size 0.45) (drill 0.1) (layers "F.Cu" "B.Cu") (net 1))
  (via (at 161.625 72.278922) (size 0.45) (drill 0.1) (layers "F.Cu" "B.Cu") (net 1))
  (via (at 136.19 74.25) (size 0.45) (drill 0.1) (layers "F.Cu" "B.Cu") (net 1))
  (via (at 142.5 73) (size 0.45) (drill 0.1) (layers "F.Cu" "B.Cu") (net 1))
  (via (at 116 78) (size 0.45) (drill 0.1) (layers "F.Cu" "B.Cu") (net 1))
  (via (at 129.343 78.012) (size 0.45) (drill 0.1) (layers "F.Cu" "B.Cu") (net 1))
  (via (at 131.245863 89.030862) (size 0.45) (drill 0.1) (layers "F.Cu" "B.Cu") (net 1))
  (via (at 141.699996 51.099998) (size 0.45) (drill 0.1) (layers "F.Cu" "B.Cu") (net 1))
  (via (at 136.175 68.285) (size 0.45) (drill 0.1) (layers "F.Cu" "B.Cu") (net 1))
  (via (at 113 88.25) (size 0.45) (drill 0.1) (layers "F.Cu" "B.Cu") (net 1))
  (via (at 163.349999 90.45) (size 0.45) (drill 0.1) (layers "F.Cu" "B.Cu") (net 1))
  (via (at 125.182356 83.47981) (size 0.45) (drill 0.1) (layers "F.Cu" "B.Cu") (net 1))
  (via (at 163 51) (size 0.45) (drill 0.1) (layers "F.Cu" "B.Cu") (net 1))
  (via (at 105.955 84.94) (size 0.45) (drill 0.1) (layers "F.Cu" "B.Cu") (net 1))
  (via (at 132.525 81.475) (size 0.45) (drill 0.1) (layers "F.Cu" "B.Cu") (net 1))
  (via (at 148.05 51.099998) (size 0.45) (drill 0.1) (layers "F.Cu" "B.Cu") (net 1))
  (via (at 158.259249 72.415751) (size 0.45) (drill 0.1) (layers "F.Cu" "B.Cu") (net 1))
  (via (at 122.025 79.2) (size 0.45) (drill 0.1) (layers "F.Cu" "B.Cu") (net 1))
  (via (at 115.830001 67.39) (size 0.45) (drill 0.1) (layers "F.Cu" "B.Cu") (net 1))
  (via (at 158.08 61.37) (size 0.45) (drill 0.1) (layers "F.Cu" "B.Cu") (net 1))
  (via (at 151.154953 80.819619) (size 0.45) (drill 0.1) (layers "F.Cu" "B.Cu") (net 1))
  (via (at 134.475 78.875) (size 0.45) (drill 0.1) (layers "F.Cu" "B.Cu") (net 1))
  (via (at 163.275 70.628922) (size 0.45) (drill 0.1) (layers "F.Cu" "B.Cu") (net 1))
  (via (at 107 51) (size 0.45) (drill 0.1) (layers "F.Cu" "B.Cu") (net 1))
  (via (at 103.545 84.94) (size 0.45) (drill 0.1) (layers "F.Cu" "B.Cu") (net 1))
  (via (at 128 60) (size 0.45) (drill 0.1) (layers "F.Cu" "B.Cu") (net 1))
  (via (at 130.786243 87.451242) (size 0.45) (drill 0.1) (layers "F.Cu" "B.Cu") (net 1))
  (via (at 128.5 86) (size 0.45) (drill 0.1) (layers "F.Cu" "B.Cu") (net 1))
  (via (at 158.049619 81.488177) (size 0.45) (drill 0.1) (layers "F.Cu" "B.Cu") (net 1))
  (via (at 134.8 74.79) (size 0.45) (drill 0.1) (layers "F.Cu" "B.Cu") (net 1))
  (via (at 135.175 70.235) (size 0.45) (drill 0.1) (layers "F.Cu" "B.Cu") (net 1))
  (via (at 110.65 81.0925) (size 0.45) (drill 0.1) (layers "F.Cu" "B.Cu") (net 1))
  (via (at 139.025 78.875) (size 0.45) (drill 0.1) (layers "F.Cu" "B.Cu") (net 1))
  (via (at 143.672192 91.52051) (size 0.45) (drill 0.1) (layers "F.Cu" "B.Cu") (net 1))
  (via (at 132.1 68.285) (size 0.45) (drill 0.1) (layers "F.Cu" "B.Cu") (net 1))
  (via (at 144 69) (size 0.45) (drill 0.1) (layers "F.Cu" "B.Cu") (net 1))
  (via (at 116.130001 58.89) (size 0.45) (drill 0.1) (layers "F.Cu" "B.Cu") (net 1))
  (via (at 161.7 91.55) (size 0.45) (drill 0.1) (layers "F.Cu" "B.Cu") (net 1))
  (via (at 132.525 76.925) (size 0.45) (drill 0.1) (layers "F.Cu" "B.Cu") (net 1))
  (via (at 105.955 84.38) (size 0.45) (drill 0.1) (layers "F.Cu" "B.Cu") (net 1))
  (via (at 113.230001 67.89) (size 0.45) (drill 0.1) (layers "F.Cu" "B.Cu") (net 1))
  (via (at 133.125 66.335) (size 0.45) (drill 0.1) (layers "F.Cu" "B.Cu") (net 1))
  (via (at 131.28 64.02) (size 0.45) (drill 0.1) (layers "F.Cu" "B.Cu") (net 1))
  (via (at 161.04 66.03) (size 0.45) (drill 0.1) (layers "F.Cu" "B.Cu") (net 1))
  (via (at 107.842109 79.311715) (size 0.45) (drill 0.1) (layers "F.Cu" "B.Cu") (net 1))
  (via (at 163 99) (size 0.45) (drill 0.1) (layers "F.Cu" "B.Cu") (net 1))
  (via (at 143.317931 88.62208) (size 0.45) (drill 0.1) (layers "F.Cu" "B.Cu") (net 1))
  (via (at 115.130001 57.79) (size 0.45) (drill 0.1) (layers "F.Cu" "B.Cu") (net 1))
  (via (at 154.73 59.14) (size 0.45) (drill 0.1) (layers "F.Cu" "B.Cu") (net 1))
  (via (at 113.730001 67.89) (size 0.45) (drill 0.1) (layers "F.Cu" "B.Cu") (net 1))
  (via (at 102.775 77.3125) (size 0.45) (drill 0.1) (layers "F.Cu" "B.Cu") (net 1))
  (via (at 166 84) (size 0.45) (drill 0.1) (layers "F.Cu" "B.Cu") (net 1))
  (via (at 132.525 77.575) (size 0.45) (drill 0.1) (layers "F.Cu" "B.Cu") (net 1))
  (via (at 151.444666 82.355334) (size 0.45) (drill 0.1) (layers "F.Cu" "B.Cu") (net 1))
  (via (at 133.175 76.275) (size 0.45) (drill 0.1) (layers "F.Cu" "B.Cu") (net 1))
  (via (at 127.705 76.83) (size 0.45) (drill 0.1) (layers "F.Cu" "B.Cu") (net 1))
  (via (at 109.399 83.67) (size 0.45) (drill 0.1) (layers "F.Cu" "B.Cu") (net 1))
  (via (at 144 94.045046) (size 0.45) (drill 0.1) (layers "F.Cu" "B.Cu") (net 1))
  (via (at 115.299999 93.8) (size 0.45) (drill 0.1) (layers "F.Cu" "B.Cu") (net 1))
  (via (at 109.030001 67.89) (size 0.45) (drill 0.1) (layers "F.Cu" "B.Cu") (net 1))
  (via (at 115.809998 93.29) (size 0.45) (drill 0.1) (layers "F.Cu" "B.Cu") (net 1))
  (via (at 144.8 69) (size 0.45) (drill 0.1) (layers "F.Cu" "B.Cu") (net 1))
  (via (at 169 93) (size 0.45) (drill 0.1) (layers "F.Cu" "B.Cu") (net 1))
  (via (at 149 73.5) (size 0.45) (drill 0.1) (layers "F.Cu" "B.Cu") (net 1))
  (via (at 150.519619 81.454953) (size 0.45) (drill 0.1) (layers "F.Cu" "B.Cu") (net 1))
  (via (at 125 51) (size 0.45) (drill 0.1) (layers "F.Cu" "B.Cu") (net 1))
  (via (at 136.18 84.234) (size 0.45) (drill 0.1) (layers "F.Cu" "B.Cu") (net 1))
  (via (at 105.730001 67.89) (size 0.45) (drill 0.1) (layers "F.Cu" "B.Cu") (net 1))
  (via (at 113 60) (size 0.45) (drill 0.1) (layers "F.Cu" "B.Cu") (net 1))
  (via (at 163.349999 91) (size 0.45) (drill 0.1) (layers "F.Cu" "B.Cu") (net 1))
  (via (at 106.230001 67.39) (size 0.45) (drill 0.1) (layers "F.Cu" "B.Cu") (net 1))
  (via (at 136.425 83.425) (size 0.45) (drill 0.1) (layers "F.Cu" "B.Cu") (net 1))
  (via (at 149.4 63.2) (size 0.45) (drill 0.1) (layers "F.Cu" "B.Cu") (net 1))
  (via (at 152.544666 74.22) (size 0.45) (drill 0.1) (layers "F.Cu" "B.Cu") (net 1))
  (via (at 163 93) (size 0.45) (drill 0.1) (layers "F.Cu" "B.Cu") (net 1))
  (via (at 122 81) (size 0.45) (drill 0.1) (layers "F.Cu" "B.Cu") (net 1))
  (via (at 131.875 76.925) (size 0.45) (drill 0.1) (layers "F.Cu" "B.Cu") (net 1))
  (via (at 119 56) (size 0.45) (drill 0.1) (layers "F.Cu" "B.Cu") (net 1))
  (via (at 107 57) (size 0.45) (drill 0.1) (layers "F.Cu" "B.Cu") (net 1))
  (via (at 136.57981 88.31019) (size 0.45) (drill 0.1) (layers "F.Cu" "B.Cu") (net 1))
  (via (at 162.799999 91) (size 0.45) (drill 0.1) (layers "F.Cu" "B.Cu") (net 1))
  (via (at 115.299999 92.78) (size 0.45) (drill 0.1) (layers "F.Cu" "B.Cu") (net 1))
  (via (at 125.712 63.6) (size 0.45) (drill 0.1) (layers "F.Cu" "B.Cu") (net 1))
  (via (at 133.125 70.235) (size 0.45) (drill 0.1) (layers "F.Cu" "B.Cu") (net 1))
  (via (at 159.91 58.986) (size 0.45) (drill 0.1) (layers "F.Cu" "B.Cu") (net 1))
  (via (at 126 88.5) (size 0.45) (drill 0.1) (layers "F.Cu" "B.Cu") (net 1))
  (via (at 134.475 77.575) (size 0.45) (drill 0.1) (layers "F.Cu" "B.Cu") (net 1))
  (via (at 131.05 70.235) (size 0.45) (drill 0.1) (layers "F.Cu" "B.Cu") (net 1))
  (via (at 130.226243 88.011242) (size 0.45) (drill 0.1) (layers "F.Cu" "B.Cu") (net 1))
  (via (at 131.875 76.275) (size 0.45) (drill 0.1) (layers "F.Cu" "B.Cu") (net 1))
  (via (at 105.29 75.52) (size 0.45) (drill 0.1) (layers "F.Cu" "B.Cu") (net 1))
  (via (at 137.225 66.335) (size 0.45) (drill 0.1) (layers "F.Cu" "B.Cu") (net 1))
  (via (at 148 96) (size 0.45) (drill 0.1) (layers "F.Cu" "B.Cu") (net 1))
  (via (at 130.05 66.335) (size 0.45) (drill 0.1) (layers "F.Cu" "B.Cu") (net 1))
  (via (at 134.475 83.425) (size 0.45) (drill 0.1) (layers "F.Cu" "B.Cu") (net 1))
  (via (at 161.7 90.45) (size 0.45) (drill 0.1) (layers "F.Cu" "B.Cu") (net 1))
  (via (at 108.530001 67.39) (size 0.45) (drill 0.1) (layers "F.Cu" "B.Cu") (net 1))
  (via (at 151 87) (size 0.45) (drill 0.1) (layers "F.Cu" "B.Cu") (net 1))
  (via (at 105.395 84.38) (size 0.45) (drill 0.1) (layers "F.Cu" "B.Cu") (net 1))
  (via (at 133.42 84.234) (size 0.45) (drill 0.1) (layers "F.Cu" "B.Cu") (net 1))
  (via (at 139.52981 86.86019) (size 0.45) (drill 0.1) (layers "F.Cu" "B.Cu") (net 1))
  (via (at 101 51) (size 0.45) (drill 0.1) (layers "F.Cu" "B.Cu") (net 1))
  (via (at 102.985 84.38) (size 0.45) (drill 0.1) (layers "F.Cu" "B.Cu") (net 1))
  (via (at 158.89 64.85) (size 0.45) (drill 0.1) (layers "F.Cu" "B.Cu") (net 1))
  (via (at 133 94.05) (size 0.45) (drill 0.1) (layers "F.Cu" "B.Cu") (net 1))
  (via (at 126.85981 77.684856) (size 0.45) (drill 0.1) (layers "F.Cu" "B.Cu") (net 1))
  (via (at 114.79 93.29) (size 0.45) (drill 0.1) (layers "F.Cu" "B.Cu") (net 1))
  (via (at 156.64 63.1) (size 0.45) (drill 0.1) (layers "F.Cu" "B.Cu") (net 1))
  (via (at 107 99) (size 0.45) (drill 0.1) (layers "F.Cu" "B.Cu") (net 1))
  (via (at 116.130001 59.39) (size 0.45) (drill 0.1) (layers "F.Cu" "B.Cu") (net 1))
  (via (at 115.630001 57.79) (size 0.45) (drill 0.1) (layers "F.Cu" "B.Cu") (net 1))
  (via (at 142.17 77.9) (size 0.45) (drill 0.1) (layers "F.Cu" "B.Cu") (net 1))
  (via (at 101 75) (size 0.45) (drill 0.1) (layers "F.Cu" "B.Cu") (net 1))
  (via (at 129.984 78.93) (size 0.45) (drill 0.1) (layers "F.Cu" "B.Cu") (net 1))
  (via (at 113.730001 67.39) (size 0.45) (drill 0.1) (layers "F.Cu" "B.Cu") (net 1))
  (via (at 131.116666 51.099998) (size 0.45) (drill 0.1) (layers "F.Cu" "B.Cu") (net 1))
  (via (at 101 99) (size 0.45) (drill 0.1) (layers "F.Cu" "B.Cu") (net 1))
  (via (at 137.075 81.475) (size 0.45) (drill 0.1) (layers "F.Cu" "B.Cu") (net 1))
  (via (at 161 84) (size 0.45) (drill 0.1) (layers "F.Cu" "B.Cu") (net 1))
  (via (at 138.975 80.125) (size 0.45) (drill 0.1) (layers "F.Cu" "B.Cu") (net 1))
  (via (at 119 69) (size 0.45) (drill 0.1) (layers "F.Cu" "B.Cu") (net 1))
  (via (at 132.075 70.235) (size 0.45) (drill 0.1) (layers "F.Cu" "B.Cu") (net 1))
  (via (at 163.349999 91.55) (size 0.45) (drill 0.1) (layers "F.Cu" "B.Cu") (net 1))
  (via (at 148.05 53.043666) (size 0.45) (drill 0.1) (layers "F.Cu" "B.Cu") (net 1))
  (via (at 169 87) (size 0.45) (drill 0.1) (layers "F.Cu" "B.Cu") (net 1))
  (via (at 109.030001 67.39) (size 0.45) (drill 0.1) (layers "F.Cu" "B.Cu") (net 1))
  (via (at 138.375 76.925) (size 0.45) (drill 0.1) (layers "F.Cu" "B.Cu") (net 1))
  (via (at 135.125 80.825) (size 0.45) (drill 0.1) (layers "F.Cu" "B.Cu") (net 1))
  (via (at 147.5 71.425) (size 0.45) (drill 0.1) (layers "F.Cu" "B.Cu") (net 1))
  (via (at 137.725 81.475) (size 0.45) (drill 0.1) (layers "F.Cu" "B.Cu") (net 1))
  (via (at 113 69) (size 0.45) (drill 0.1) (layers "F.Cu" "B.Cu") (net 1))
  (via (at 131.075 68.285) (size 0.45) (drill 0.1) (layers "F.Cu" "B.Cu") (net 1))
  (via (at 140.445623 80.6055) (size 0.45) (drill 0.1) (layers "F.Cu" "B.Cu") (net 1))
  (via (at 131.075 66.335) (size 0.45) (drill 0.1) (layers "F.Cu" "B.Cu") (net 1))
  (via (at 137 94.05) (size 0.45) (drill 0.1) (layers "F.Cu" "B.Cu") (net 1))
  (via (at 119 75) (size 0.45) (drill 0.1) (layers "F.Cu" "B.Cu") (net 1))
  (via (at 112.115 86.654) (size 0.45) (drill 0.1) (layers "F.Cu" "B.Cu") (net 1))
  (via (at 157 87) (size 0.45) (drill 0.1) (layers "F.Cu" "B.Cu") (net 1))
  (via (at 143.15 76.916) (size 0.45) (drill 0.1) (layers "F.Cu" "B.Cu") (net 1))
  (via (at 151 67) (size 0.45) (drill 0.1) (layers "F.Cu" "B.Cu") (net 1))
  (via (at 106.230001 67.89) (size 0.45) (drill 0.1) (layers "F.Cu" "B.Cu") (net 1))
  (via (at 148.05 55.033332) (size 0.45) (drill 0.1) (layers "F.Cu" "B.Cu") (net 1))
  (via (at 139 94.045046) (size 0.45) (drill 0.1) (layers "F.Cu" "B.Cu") (net 1))
  (via (at 135.2 68.285) (size 0.45) (drill 0.1) (layers "F.Cu" "B.Cu") (net 1))
  (via (at 137.13981 88.87019) (size 0.45) (drill 0.1) (layers "F.Cu" "B.Cu") (net 1))
  (via (at 110.65 82.475) (size 0.45) (drill 0.1) (layers "F.Cu" "B.Cu") (net 1))
  (via (at 106.47 82.660001) (size 0.45) (drill 0.1) (layers "F.Cu" "B.Cu") (net 1))
  (via (at 133.88 74.79) (size 0.45) (drill 0.1) (layers "F.Cu" "B.Cu") (net 1))
  (via (at 103.545 84.38) (size 0.45) (drill 0.1) (layers "F.Cu" "B.Cu") (net 1))
  (via (at 148 90) (size 0.45) (drill 0.1) (layers "F.Cu" "B.Cu") (net 1))
  (via (at 157.360751 73.969249) (size 0.45) (drill 0.1) (layers "F.Cu" "B.Cu") (net 1))
  (via (at 139.07019 88.43981) (size 0.45) (drill 0.1) (layers "F.Cu" "B.Cu") (net 1))
  (via (at 132.525 76.275) (size 0.45) (drill 0.1) (layers "F.Cu" "B.Cu") (net 1))
  (via (at 115.130001 58.89) (size 0.45) (drill 0.1) (layers "F.Cu" "B.Cu") (net 1))
  (via (at 145 87) (size 0.45) (drill 0.1) (layers "F.Cu" "B.Cu") (net 1))
  (via (at 138.225 66.335) (size 0.45) (drill 0.1) (layers "F.Cu" "B.Cu") (net 1))
  (via (at 161.625 70.628922) (size 0.45) (drill 0.1) (layers "F.Cu" "B.Cu") (net 1))
  (via (at 114.159 84.69) (size 0.45) (drill 0.1) (layers "F.Cu" "B.Cu") (net 1))
  (via (at 122 54) (size 0.45) (drill 0.1) (layers "F.Cu" "B.Cu") (net 1))
  (via (at 151 93) (size 0.45) (drill 0.1) (layers "F.Cu" "B.Cu") (net 1))
  (via (at 101 81) (size 0.45) (drill 0.1) (layers "F.Cu" "B.Cu") (net 1))
  (via (at 110.830001 67.89) (size 0.45) (drill 0.1) (layers "F.Cu" "B.Cu") (net 1))
  (via (at 139.58333 57.100001) (size 0.45) (drill 0.1) (layers "F.Cu" "B.Cu") (net 1))
  (via (at 114.79 92.78) (size 0.45) (drill 0.1) (layers "F.Cu" "B.Cu") (net 1))
  (via (at 110 96) (size 0.45) (drill 0.1) (layers "F.Cu" "B.Cu") (net 1))
  (via (at 133.233332 57.100001) (size 0.45) (drill 0.1) (layers "F.Cu" "B.Cu") (net 1))
  (via (at 115.630001 57.29) (size 0.45) (drill 0.1) (layers "F.Cu" "B.Cu") (net 1))
  (via (at 166 66) (size 0.45) (drill 0.1) (layers "F.Cu" "B.Cu") (net 1))
  (via (at 130.025 68.285) (size 0.45) (drill 0.1) (layers "F.Cu" "B.Cu") (net 1))
  (via (at 101 93) (size 0.45) (drill 0.1) (layers "F.Cu" "B.Cu") (net 1))
  (via (at 153.174953 82.814953) (size 0.45) (drill 0.1) (layers "F.Cu" "B.Cu") (net 1))
  (via (at 138.02 84.234) (size 0.45) (drill 0.1) (layers "F.Cu" "B.Cu") (net 1))
  (via (at 162.725 81.353922) (size 0.45) (drill 0.1) (layers "F.Cu" "B.Cu") (net 1))
  (via (at 116.330001 67.89) (size 0.45) (drill 0.1) (layers "F.Cu" "B.Cu") (net 1))
  (via (at 126.912644 83.02019) (size 0.45) (drill 0.1) (layers "F.Cu" "B.Cu") (net 1))
  (via (at 163.71 66.03) (size 0.45) (drill 0.1) (layers "F.Cu" "B.Cu") (net 1))
  (via (at 161.78 66.77) (size 0.45) (drill 0.1) (layers "F.Cu" "B.Cu") (net 1))
  (via (at 134.475 76.925) (size 0.45) (drill 0.1) (layers "F.Cu" "B.Cu") (net 1))
  (via (at 116.659001 63.095) (size 0.45) (drill 0.1) (layers "F.Cu" "B.Cu") (net 1))
  (via (at 117.46 61.88) (size 0.45) (drill 0.1) (layers "F.Cu" "B.Cu") (net 1))
  (via (at 138.375 76.275) (size 0.45) (drill 0.1) (layers "F.Cu" "B.Cu") (net 1))
  (via (at 153.505047 84.330381) (size 0.45) (drill 0.1) (layers "F.Cu" "B.Cu") (net 1))
  (via (at 162.97 66.77) (size 0.45) (drill 0.1) (layers "F.Cu" "B.Cu") (net 1))
  (via (at 115.299999 94.31) (size 0.45) (drill 0.1) (layers "F.Cu" "B.Cu") (net 1))
  (via (at 115.245004 79.2) (size 0.45) (drill 0.1) (layers "F.Cu" "B.Cu") (net 1))
  (via (at 140.3 66.335) (size 0.45) (drill 0.1) (layers "F.Cu" "B.Cu") (net 1))
  (via (at 115.809998 92.78) (size 0.45) (drill 0.1) (layers "F.Cu" "B.Cu") (net 1))
  (via (at 131.58 84.234) (size 0.45) (drill 0.1) (layers "F.Cu" "B.Cu") (net 1))
  (via (at 169 57) (size 0.45) (drill 0.1) (layers "F.Cu" "B.Cu") (net 1))
  (via (at 102.775 76.7525) (size 0.45) (drill 0.1) (layers "F.Cu" "B.Cu") (net 1))
  (via (at 166 90) (size 0.45) (drill 0.1) (layers "F.Cu" "B.Cu") (net 1))
  (via (at 103.5 66) (size 0.45) (drill 0.1) (layers "F.Cu" "B.Cu") (net 1))
  (via (at 136.425 76.275) (size 0.45) (drill 0.1) (layers "F.Cu" "B.Cu") (net 1))
  (via (at 142.3 79.9) (size 0.45) (drill 0.1) (layers "F.Cu" "B.Cu") (net 1))
  (via (at 161.625 81.353922) (size 0.45) (drill 0.1) (layers "F.Cu" "B.Cu") (net 1))
  (via (at 161.78 66.03) (size 0.45) (drill 0.1) (layers "F.Cu" "B.Cu") (net 1))
  (via (at 117.449999 79.2) (size 0.45) (drill 0.1) (layers "F.Cu" "B.Cu") (net 1))
  (via (at 103.5 60) (size 0.45) (drill 0.1) (layers "F.Cu" "B.Cu") (net 1))
  (via (at 153.91 59.986) (size 0.45) (drill 0.1) (layers "F.Cu" "B.Cu") (net 1))
  (via (at 119 84) (size 0.45) (drill 0.1) (layers "F.Cu" "B.Cu") (net 1))
  (via (at 114.5 79.2) (size 0.45) (drill 0.1) (layers "F.Cu" "B.Cu") (net 1))
  (via (at 157.360751 72.420752) (size 0.45) (drill 0.1) (layers "F.Cu" "B.Cu") (net 1))
  (via (at 101 69) (size 0.45) (drill 0.1) (layers "F.Cu" "B.Cu") (net 1))
  (via (at 116.630001 57.29) (size 0.45) (drill 0.1) (layers "F.Cu" "B.Cu") (net 1))
  (via (at 104 90) (size 0.45) (drill 0.1) (layers "F.Cu" "B.Cu") (net 1))
  (via (at 157 55.5) (size 0.45) (drill 0.1) (layers "F.Cu" "B.Cu") (net 1))
  (via (at 129 53.099999) (size 0.45) (drill 0.1) (layers "F.Cu" "B.Cu") (net 1))
  (via (at 122 72) (size 0.45) (drill 0.1) (layers "F.Cu" "B.Cu") (net 1))
  (via (at 139.184 81.69) (size 0.45) (drill 0.1) (layers "F.Cu" "B.Cu") (net 1))
  (via (at 156.954666 80.393224) (size 0.45) (drill 0.1) (layers "F.Cu" "B.Cu") (net 1))
  (via (at 157.91 58.986) (size 0.45) (drill 0.1) (layers "F.Cu" "B.Cu") (net 1))
  (via (at 137.6 63.6) (size 0.45) (drill 0.1) (layers "F.Cu" "B.Cu") (net 1))
  (via (at 142.5 69) (size 0.45) (drill 0.1) (layers "F.Cu" "B.Cu") (net 1))
  (via (at 111.241 82.67) (size 0.45) (drill 0.1) (layers "F.Cu" "B.Cu") (net 1))
  (via (at 157.64 62.6) (size 0.45) (drill 0.1) (layers "F.Cu" "B.Cu") (net 1))
  (via (at 139.86 78.01) (size 0.45) (drill 0.1) (layers "F.Cu" "B.Cu") (net 1))
  (via (at 141.3 66.335) (size 0.45) (drill 0.1) (layers "F.Cu" "B.Cu") (net 1))
  (via (at 118.925 79.2) (size 0.45) (drill 0.1) (layers "F.Cu" "B.Cu") (net 1))
  (via (at 129.984 77.09) (size 0.45) (drill 0.1) (layers "F.Cu" "B.Cu") (net 1))
  (via (at 138.69 61.52) (size 0.45) (drill 0.1) (layers "F.Cu" "B.Cu") (net 1))
  (via (at 108.111337 85.362687) (size 0.45) (drill 0.1) (layers "F.Cu" "B.Cu") (net 1))
  (via (at 128 94.05) (size 0.45) (drill 0.1) (layers "F.Cu" "B.Cu") (net 1))
  (via (at 116.319997 92.78) (size 0.45) (drill 0.1) (layers "F.Cu" "B.Cu") (net 1))
  (via (at 136.425 80.175) (size 0.45) (drill 0.1) (layers "F.Cu" "B.Cu") (net 1))
  (via (at 111.330001 67.89) (size 0.45) (drill 0.1) (layers "F.Cu" "B.Cu") (net 1))
  (via (at 143.3 69) (size 0.45) (drill 0.1) (layers "F.Cu" "B.Cu") (net 1))
  (via (at 158.06 63.95) (size 0.45) (drill 0.1) (layers "F.Cu" "B.Cu") (net 1))
  (via (at 162.25 90.45) (size 0.45) (drill 0.1) (layers "F.Cu" "B.Cu") (net 1))
  (via (at 141.699996 57.100001) (size 0.45) (drill 0.1) (layers "F.Cu" "B.Cu") (net 1))
  (via (at 145.135 76.96) (size 0.45) (drill 0.1) (layers "F.Cu" "B.Cu") (net 1))
  (via (at 115.830001 67.89) (size 0.45) (drill 0.1) (layers "F.Cu" "B.Cu") (net 1))
  (via (at 155.894 63.97) (size 0.45) (drill 0.1) (layers "F.Cu" "B.Cu") (net 1))
  (via (at 118.195003 79.2) (size 0.45) (drill 0.1) (layers "F.Cu" "B.Cu") (net 1))
  (via (at 162.8 90.45) (size 0.45) (drill 0.1) (layers "F.Cu" "B.Cu") (net 1))
  (via (at 143.816662 51.099998) (size 0.45) (drill 0.1) (layers "F.Cu" "B.Cu") (net 1))
  (via (at 102.985 84.94) (size 0.45) (drill 0.1) (layers "F.Cu" "B.Cu") (net 1))
  (via (at 135.349998 51.099998) (size 0.45) (drill 0.1) (layers "F.Cu" "B.Cu") (net 1))
  (via (at 144.8 73) (size 0.45) (drill 0.1) (layers "F.Cu" "B.Cu") (net 1))
  (via (at 151.955 62.9745) (size 0.45) (drill 0.1) (layers "F.Cu" "B.Cu") (net 1))
  (via (at 133.02019 89.31019) (size 0.45) (drill 0.1) (layers "F.Cu" "B.Cu") (net 1))
  (via (at 151 57) (size 0.45) (drill 0.1) (layers "F.Cu" "B.Cu") (net 1))
  (via (at 137.225 68.285) (size 0.45) (drill 0.1) (layers "F.Cu" "B.Cu") (net 1))
  (via (at 166 60) (size 0.45) (drill 0.1) (layers "F.Cu" "B.Cu") (net 1))
  (via (at 101 63) (size 0.45) (drill 0.1) (layers "F.Cu" "B.Cu") (net 1))
  (via (at 133.825 82.775) (size 0.45) (drill 0.1) (layers "F.Cu" "B.Cu") (net 1))
  (via (at 105.29 74.96) (size 0.45) (drill 0.1) (layers "F.Cu" "B.Cu") (net 1))
  (via (at 112.803808 79.330212) (size 0.45) (drill 0.1) (layers "F.Cu" "B.Cu") (net 1))
  (via (at 135.56019 89.32981) (size 0.45) (drill 0.1) (layers "F.Cu" "B.Cu") (net 1))
  (via (at 150.06 79.724666) (size 0.45) (drill 0.1) (layers "F.Cu" "B.Cu") (net 1))
  (via (at 109.399 82.67) (size 0.45) (drill 0.1) (layers "F.Cu" "B.Cu") (net 1))
  (via (at 134.475 76.275) (size 0.45) (drill 0.1) (layers "F.Cu" "B.Cu") (net 1))
  (via (at 163 60) (size 0.45) (drill 0.1) (layers "F.Cu" "B.Cu") (net 1))
  (via (at 157.59 79.75789) (size 0.45) (drill 0.1) (layers "F.Cu" "B.Cu") (net 1))
  (via (at 105.395 84.94) (size 0.45) (drill 0.1) (layers "F.Cu" "B.Cu") (net 1))
  (via (at 154 54) (size 0.45) (drill 0.1) (layers "F.Cu" "B.Cu") (net 1))
  (via (at 154.51 65.35) (size 0.45) (drill 0.1) (layers "F.Cu" "B.Cu") (net 1))
  (via (at 157 99) (size 0.45) (drill 0.1) (layers "F.Cu" "B.Cu") (net 1))
  (via (at 139.3 66.335) (size 0.45) (drill 0.1) (layers "F.Cu" "B.Cu") (net 1))
  (via (at 169 99) (size 0.45) (drill 0.1) (layers "F.Cu" "B.Cu") (net 1))
  (via (at 142.325 66.335) (size 0.45) (drill 0.1) (layers "F.Cu" "B.Cu") (net 1))
  (via (at 145.933328 57.100001) (size 0.45) (drill 0.1) (layers "F.Cu" "B.Cu") (net 1))
  (via (at 141 94.045046) (size 0.45) (drill 0.1) (layers "F.Cu" "B.Cu") (net 1))
  (via (at 161.625 71.728922) (size 0.45) (drill 0.1) (layers "F.Cu" "B.Cu") (net 1))
  (via (at 152.926 62.9745) (size 0.45) (drill 0.1) (layers "F.Cu" "B.Cu") (net 1))
  (via (at 126.27731 82.384856) (size 0.45) (drill 0.1) (layers "F.Cu" "B.Cu") (net 1))
  (via (at 130.025 70.235) (size 0.45) (drill 0.1) (layers "F.Cu" "B.Cu") (net 1))
  (via (at 152.08 81.72) (size 0.45) (drill 0.1) (layers "F.Cu" "B.Cu") (net 1))
  (via (at 155.13 64.97) (size 0.45) (drill 0.1) (layers "F.Cu" "B.Cu") (net 1))
  (via (at 139.86 77.09) (size 0.45) (drill 0.1) (layers "F.Cu" "B.Cu") (net 1))
  (via (at 137.725 76.275) (size 0.45) (drill 0.1) (layers "F.Cu" "B.Cu") (net 1))
  (via (at 145 93) (size 0.45) (drill 0.1) (layers "F.Cu" "B.Cu") (net 1))
  (via (at 116.130001 57.29) (size 0.45) (drill 0.1) (layers "F.Cu" "B.Cu") (net 1))
  (via (at 137.075 76.275) (size 0.45) (drill 0.1) (layers "F.Cu" "B.Cu") (net 1))
  (via (at 162.97 66.03) (size 0.45) (drill 0.1) (layers "F.Cu" "B.Cu") (net 1))
  (via (at 161.987688 69.212313) (size 0.45) (drill 0.1) (layers "F.Cu" "B.Cu") (net 1))
  (via (at 112.47 84.962) (size 0.45) (drill 0.1) (layers "F.Cu" "B.Cu") (net 1))
  (via (at 157.64 63.1) (size 0.45) (drill 0.1) (layers "F.Cu" "B.Cu") (net 1))
  (via (at 162.175 81.353922) (size 0.45) (drill 0.1) (layers "F.Cu" "B.Cu") (net 1))
  (via (at 154 90) (size 0.45) (drill 0.1) (layers "F.Cu" "B.Cu") (net 1))
  (via (at 126.5 80.5) (size 0.45) (drill 0.1) (layers "F.Cu" "B.Cu") (net 1))
  (via (at 115.630001 59.39) (size 0.45) (drill 0.1) (layers "F.Cu" "B.Cu") (net 1))
  (via (at 144 73) (size 0.45) (drill 0.1) (layers "F.Cu" "B.Cu") (net 1))
  (via (at 116.630001 58.89) (size 0.45) (drill 0.1) (layers "F.Cu" "B.Cu") (net 1))
  (via (at 149.424666 80.36) (size 0.45) (drill 0.1) (layers "F.Cu" "B.Cu") (net 1))
  (via (at 110 81.0925) (size 0.45) (drill 0.1) (layers "F.Cu" "B.Cu") (net 1))
  (via (at 154.140381 83.695047) (size 0.45) (drill 0.1) (layers "F.Cu" "B.Cu") (net 1))
  (via (at 125 57) (size 0.45) (drill 0.1) (layers "F.Cu" "B.Cu") (net 1))
  (via (at 114.79 94.31) (size 0.45) (drill 0.1) (layers "F.Cu" "B.Cu") (net 1))
  (via (at 125 94.045046) (size 0.45) (drill 0.1) (layers "F.Cu" "B.Cu") (net 1))
  (via (at 129.74 74.79) (size 0.45) (drill 0.1) (layers "F.Cu" "B.Cu") (net 1))
  (via (at 163.275 81.353922) (size 0.45) (drill 0.1) (layers "F.Cu" "B.Cu") (net 1))
  (via (at 161.980751 67.670751) (size 0.45) (drill 0.1) (layers "F.Cu" "B.Cu") (net 1))
  (via (at 143.816662 57.100001) (size 0.45) (drill 0.1) (layers "F.Cu" "B.Cu") (net 1))
  (via (at 113 57) (size 0.45) (drill 0.1) (layers "F.Cu" "B.Cu") (net 1))
  (via (at 104.735 76.7525) (size 0.45) (drill 0.1) (layers "F.Cu" "B.Cu") (net 1))
  (via (at 125.81769 84.115144) (size 0.45) (drill 0.1) (layers "F.Cu" "B.Cu") (net 1))
  (via (at 137.725 78.875) (size 0.45) (drill 0.1) (layers "F.Cu" "B.Cu") (net 1))
  (via (at 161.625 79.703922) (size 0.45) (drill 0.1) (layers "F.Cu" "B.Cu") (net 1))
  (via (at 133.47981 90.88981) (size 0.45) (drill 0.1) (layers "F.Cu" "B.Cu") (net 1))
  (via (at 134.475 84.075) (size 0.45) (drill 0.1) (layers "F.Cu" "B.Cu") (net 1))
  (via (at 115.130001 57.29) (size 0.45) (drill 0.1) (layers "F.Cu" "B.Cu") (net 1))
  (via (at 119 51) (size 0.45) (drill 0.1) (layers "F.Cu" "B.Cu") (net 1))
  (segment (start 115.440001 64.16) (end 115.471002 64.16) (width 0.25) (layer "B.Cu") (net 1))
  (segment (start 144.5 97.08) (end 144.5 94.545046) (width 0.4) (layer "B.Cu") (net 1))
  (segment (start 132.366 78.875) (end 132.366 77.9) (width 0.25) (layer "B.Cu") (net 1))
  (segment (start 144.15 73.998) (end 145.097 73.998) (width 0.25) (layer "B.Cu") (net 1))
  (segment (start 114.5 97.08) (end 114.5 94.75) (width 0.6) (layer "B.Cu") (net 1))
  (segment (start 157.14 63.1) (end 157.14 62.6) (width 0.25) (layer "B.Cu") (net 1))
  (segment (start 152.946 65.419) (end 152.945 65.42) (width 0.1) (layer "B.Cu") (net 1))
  (segment (start 142.15 73.35) (end 142.15 73.998) (width 0.25) (layer "B.Cu") (net 1))
  (segment (start 142.17 77.9) (end 142.17 76.934) (width 0.25) (layer "B.Cu") (net 1))
  (segment (start 130.66 78.144) (end 130.416 77.9) (width 0.25) (layer "B.Cu") (net 1))
  (segment (start 135.175 68.285) (end 136.2 68.285) (width 0.25) (layer "B.Cu") (net 1))
  (segment (start 116.659001 62.941) (end 117.395001 62.205) (width 0.25) (layer "B.Cu") (net 1))
  (segment (start 141.15 73.998) (end 142.15 73.998) (width 0.25) (layer "B.Cu") (net 1))
  (segment (start 137.5 94.55) (end 137 94.05) (width 0.4) (layer "B.Cu") (net 1))
  (segment (start 134.15 79.85) (end 134.316 79.85) (width 0.25) (layer "B.Cu") (net 1))
  (segment (start 136.275 79.866) (end 136.275 80.025) (width 0.25) (layer "B.Cu") (net 1))
  (segment (start 158.08 61.62) (end 158.43 61.97) (width 0.25) (layer "B.Cu") (net 1))
  (segment (start 152.926 65.401) (end 152.945 65.42) (width 0.25) (layer "B.Cu") (net 1))
  (segment (start 145.135 73.96) (end 145.135 74.959999) (width 0.25) (layer "B.Cu") (net 1))
  (segment (start 128.5 94.55) (end 128 94.05) (width 0.4) (layer "B.Cu") (net 1))
  (segment (start 117.5 93.960003) (end 116.319997 92.78) (width 0.6) (layer "B.Cu") (net 1))
  (segment (start 143.024482 88.916943) (end 143.024482 88.915529) (width 0.4) (layer "B.Cu") (net 1))
  (segment (start 117.46 61.88) (end 117.46 62.140001) (width 0.25) (layer "B.Cu") (net 1))
  (segment (start 132.366 76.925) (end 132.366 77.9) (width 0.25) (layer "B.Cu") (net 1))
  (segment (start 145.135 73.335) (end 145.135 73.96) (width 0.25) (layer "B.Cu") (net 1))
  (segment (start 136.275 80.025) (end 136.425 80.175) (width 0.25) (layer "B.Cu") (net 1))
  (segment (start 143.148 76.914) (end 143.15 76.916) (width 0.25) (layer "B.Cu") (net 1))
  (segment (start 159.91 64.986) (end 158.91 64.986) (width 0.25) (layer "B.Cu") (net 1))
  (segment (start 141.15 77.905) (end 142.165 77.905) (width 0.25) (layer "B.Cu") (net 1))
  (segment (start 125.712 63.6) (end 125.712 62.803) (width 0.1) (layer "B.Cu") (net 1))
  (segment (start 130.66 78.47) (end 130.66 78.631) (width 0.25) (layer "B.Cu") (net 1))
  (segment (start 130.05 68.285) (end 131.075 68.285) (width 0.25) (layer "B.Cu") (net 1))
  (segment (start 107.4305 89.8895) (end 106.83 90.49) (width 0.4) (layer "B.Cu") (net 1))
  (segment (start 138.25 66.335) (end 139.3 66.335) (width 0.25) (layer "B.Cu") (net 1))
  (segment (start 142.15 76.914) (end 143.148 76.914) (width 0.25) (layer "B.Cu") (net 1))
  (segment (start 156.64 62.6) (end 156.64 63.1) (width 0.25) (layer "B.Cu") (net 1))
  (segment (start 132.525 81.475) (end 132.525 81.966) (width 0.25) (layer "B.Cu") (net 1))
  (segment (start 143.15 73.15) (end 143.15 73.998) (width 0.25) (layer "B.Cu") (net 1))
  (segment (start 143.3 73) (end 143.15 73.15) (width 0.25) (layer "B.Cu") (net 1))
  (segment (start 138.5 97.08) (end 138.5 94.545046) (width 0.4) (layer "B.Cu") (net 1))
  (segment (start 115.35 92.235) (end 115.35 93.35) (width 0.4) (layer "B.Cu") (net 1))
  (segment (start 133.5 79.85) (end 133.334 79.85) (width 0.25) (layer "B.Cu") (net 1))
  (segment (start 157.64 63.1) (end 157.14 63.1) (width 0.25) (layer "B.Cu") (net 1))
  (segment (start 125.712 62.803) (end 125.765 62.75) (width 0.1) (layer "B.Cu") (net 1))
  (segment (start 138.2 81.784) (end 137.225 81.784) (width 0.25) (layer "B.Cu") (net 1))
  (segment (start 151.955 62.97) (end 151.955 62.9745) (width 0.1) (layer "B.Cu") (net 1))
  (segment (start 140.3 66.335) (end 141.325 66.335) (width 0.25) (layer "B.Cu") (net 1))
  (segment (start 136.2 68.285) (end 137.225 68.285) (width 0.25) (layer "B.Cu") (net 1))
  (segment (start 129.466 79.85) (end 129.46 79.856) (width 0.25) (layer "B.Cu") (net 1))
  (segment (start 130.05 66.335) (end 131.075 66.335) (width 0.25) (layer "B.Cu") (net 1))
  (segment (start 107.85 91.28) (end 106.83 91.28) (width 0.4) (layer "B.Cu") (net 1))
  (segment (start 151.895 63.97) (end 152.926 63.97) (width 0.25) (layer "B.Cu") (net 1))
  (segment (start 142.15 73.998) (end 143.15 73.998) (width 0.25) (layer "B.Cu") (net 1))
  (segment (start 129.984 79.85) (end 129.466 79.85) (width 0.25) (layer "B.Cu") (net 1))
  (segment (start 127.144 79.856) (end 126.5 80.5) (width 0.25) (layer "B.Cu") (net 1))
  (segment (start 123.482 76.97) (end 124.099 76.97) (width 0.25) (layer "B.Cu") (net 1))
  (segment (start 136.275 83.759) (end 136.275 83.575) (width 0.25) (layer "B.Cu") (net 1))
  (segment (start 141.5 94.545046) (end 141 94.045046) (width 0.4) (layer "B.Cu") (net 1))
  (segment (start 136.266 78.066) (end 136.425 78.225) (width 0.25) (layer "B.Cu") (net 1))
  (segment (start 161.04 66.86) (end 159.945 67.955) (width 0.25) (layer "B.Cu") (net 1))
  (segment (start 117.46 62.140001) (end 117.395001 62.205) (width 0.25) (layer "B.Cu") (net 1))
  (segment (start 144.8 73) (end 145.135 73.335) (width 0.25) (layer "B.Cu") (net 1))
  (segment (start 157.91 58.986) (end 156.911 58.986) (width 0.25) (layer "B.Cu") (net 1))
  (segment (start 136.266 77.9) (end 136.266 78.066) (width 0.25) (layer "B.Cu") (net 1))
  (segment (start 144.5 94.545046) (end 144 94.045046) (width 0.4) (layer "B.Cu") (net 1))
  (segment (start 157.14 62.6) (end 156.64 62.6) (width 0.25) (layer "B.Cu") (net 1))
  (segment (start 125.5 94.545046) (end 125 94.045046) (width 0.4) (layer "B.Cu") (net 1))
  (segment (start 159.945 67.955) (end 159.91 67.955) (width 0.25) (layer "B.Cu") (net 1))
  (segment (start 145.091 76.916) (end 145.135 76.96) (width 0.25) (layer "B.Cu") (net 1))
  (segment (start 134.316 79.85) (end 133.334 79.85) (width 0.25) (layer "B.Cu") (net 1))
  (segment (start 152.926 61.97) (end 152.926 62.97) (width 0.25) (layer "B.Cu") (net 1))
  (segment (start 141.325 66.335) (end 142.325 66.335) (width 0.25) (layer "B.Cu") (net 1))
  (segment (start 138.209 81.793) (end 138.2 81.784) (width 0.25) (layer "B.Cu") (net 1))
  (segment (start 144 73) (end 144.15 73.15) (width 0.25) (layer "B.Cu") (net 1))
  (segment (start 115.440001 66.099) (end 115.439001 66.099) (width 0.25) (layer "B.Cu") (net 1))
  (segment (start 152.926 63.97) (end 152.926 62.97) (width 0.25) (layer "B.Cu") (net 1))
  (segment (start 130.215 82.385) (end 130.215 82.13) (width 0.25) (layer "B.Cu") (net 1))
  (segment (start 107.85 91.28) (end 107.67 91.28) (width 0.4) (layer "B.Cu") (net 1))
  (segment (start 134.5 94.55) (end 135 94.05) (width 0.4) (layer "B.Cu") (net 1))
  (segment (start 139.3 66.335) (end 140.3 66.335) (width 0.25) (layer "B.Cu") (net 1))
  (segment (start 152.926 64.96) (end 152.926 65.401) (width 0.25) (layer "B.Cu") (net 1))
  (segment (start 139.38 61.514) (end 138.696 61.514) (width 0.25) (layer "B.Cu") (net 1))
  (segment (start 165.2 73.908971) (end 163.73 72.438971) (width 0.25) (layer "B.Cu") (net 1))
  (segment (start 144.15 73.15) (end 144.15 73.998) (width 0.25) (layer "B.Cu") (net 1))
  (segment (start 127.505 79.856) (end 127.144 79.856) (width 0.25) (layer "B.Cu") (net 1))
  (segment (start 140.16 77.886) (end 139.198 77.886) (width 0.25) (layer "B.Cu") (net 1))
  (segment (start 137.5 97.08) (end 137.5 94.55) (width 0.4) (layer "B.Cu") (net 1))
  (segment (start 152.946 65.1) (end 152.946 65.419) (width 0.1) (layer "B.Cu") (net 1))
  (segment (start 151.895 62.97) (end 152.926 62.97) (width 0.25) (layer "B.Cu") (net 1))
  (segment (start 157.64 62.6) (end 157.64 63.1) (width 0.25) (layer "B.Cu") (net 1))
  (segment (start 138.7 79.85) (end 138.975 80.125) (width 0.25) (layer "B.Cu") (net 1))
  (segment (start 157.14 62.6) (end 157.64 62.6) (width 0.25) (layer "B.Cu") (net 1))
  (segment (start 132.1 70.235) (end 131.075 70.235) (width 0.25) (layer "B.Cu") (net 1))
  (segment (start 132.525 80.984) (end 132.366 80.825) (width 0.25) (layer "B.Cu") (net 1))
  (segment (start 144.15 76.916) (end 145.091 76.916) (width 0.25) (layer "B.Cu") (net 1))
  (segment (start 156.911 58.986) (end 156.91 58.985) (width 0.25) (layer "B.Cu") (net 1))
  (segment (start 165.2 78.396922) (end 165.2 78.573922) (width 0.25) (layer "B.Cu") (net 1))
  (segment (start 142.5 73) (end 142.15 73.35) (width 0.25) (layer "B.Cu") (net 1))
  (segment (start 138.696 61.514) (end 138.69 61.52) (width 0.25) (layer "B.Cu") (net 1))
  (segment (start 131.075 70.235) (end 130.05 70.235) (width 0.25) (layer "B.Cu") (net 1))
  (segment (start 116.659001 63.095) (end 116.659001 62.941) (width 0.25) (layer "B.Cu") (net 1))
  (segment (start 130.215 82.835) (end 130.215 83.12) (width 0.25) (layer "B.Cu") (net 1))
  (segment (start 137.725 78.875) (end 137.234 78.875) (width 0.25) (layer "B.Cu") (net 1))
  (segment (start 130.66 78.47) (end 130.66 78.144) (width 0.25) (layer "B.Cu") (net 1))
  (segment (start 141.5 97.08) (end 141.5 94.545046) (width 0.4) (layer "B.Cu") (net 1))
  (segment (start 133.5 94.55) (end 133 94.05) (width 0.4) (layer "B.Cu") (net 1))
  (segment (start 156.525 62.6) (end 155.895 61.97) (width 0.25) (layer "B.Cu") (net 1))
  (segment (start 128.5 97.08) (end 128.5 94.55) (width 0.4) (layer "B.Cu") (net 1))
  (segment (start 133.125 70.235) (end 132.1 70.235) (width 0.25) (layer "B.Cu") (net 1))
  (segment (start 134.316 83.75) (end 134.316 82.775) (width 0.25) (layer "B.Cu") (net 1))
  (segment (start 129.984 79.85) (end 130.416 79.85) (width 0.25) (layer "B.Cu") (net 1))
  (segment (start 142.15 76.914) (end 141.15 76.914) (width 0.25) (layer "B.Cu") (net 1))
  (segment (start 122.516 79.2) (end 122.025 79.2) (width 0.25) (layer "B.Cu") (net 1))
  (segment (start 129.99 81.69) (end 130.215 81.915) (width 0.25) (layer "B.Cu") (net 1))
  (segment (start 115.439001 66.099) (end 115.130001 65.79) (width 0.25) (layer "B.Cu") (net 1))
  (segment (start 165.2 73.960922) (end 165.2 73.908971) (width 0.25) (layer "B.Cu") (net 1))
  (segment (start 141.15 77.905) (end 140.179 77.905) (width 0.25) (layer "B.Cu") (net 1))
  (segment (start 134.316 84.725) (end 134.316 83.75) (width 0.25) (layer "B.Cu") (net 1))
  (segment (start 137.225 66.335) (end 138.25 66.335) (width 0.25) (layer "B.Cu") (net 1))
  (segment (start 130.416 80.825) (end 130.416 79.85) (width 0.25) (layer "B.Cu") (net 1))
  (segment (start 132.525 81.475) (end 132.525 80.984) (width 0.25) (layer "B.Cu") (net 1))
  (segment (start 145.135 75.96) (end 145.135 76.96) (width 0.25) (layer "B.Cu") (net 1))
  (segment (start 158.08 61.37) (end 158.08 61.62) (width 0.25) (layer "B.Cu") (net 1))
  (segment (start 140.179 77.905) (end 140.16 77.886) (width 0.25) (layer "B.Cu") (net 1))
  (segment (start 156.025 63.1) (end 155.895 62.97) (width 0.25) (layer "B.Cu") (net 1))
  (segment (start 159.855 67.955) (end 158.91 67.955) (width 0.25) (layer "B.Cu") (net 1))
  (segment (start 158.925 61.97) (end 158.43 61.97) (width 0.25) (layer "B.Cu") (net 1))
  (segment (start 133.825 80.175) (end 134.15 79.85) (width 0.25) (layer "B.Cu") (net 1))
  (segment (start 125.5 97.08) (end 125.5 94.545046) (width 0.4) (layer "B.Cu") (net 1))
  (segment (start 138.2 81.784) (end 139.175 81.784) (width 0.25) (layer "B.Cu") (net 1))
  (segment (start 106.83 91.28) (end 107.01 91.28) (width 0.4) (layer "B.Cu") (net 1))
  (segment (start 132.525 77.575) (end 132.525 78.716) (width 0.25) (layer "B.Cu") (net 1))
  (segment (start 107.4305 89.2) (end 107.4305 89.8895) (width 0.4) (layer "B.Cu") (net 1))
  (segment (start 122.514 75.17) (end 121.8 75.17) (width 0.25) (layer "B.Cu") (net 1))
  (segment (start 129.99 82.61) (end 130.215 82.385) (width 0.25) (layer "B.Cu") (net 1))
  (segment (start 130.66 78.631) (end 130.416 78.875) (width 0.25) (layer "B.Cu") (net 1))
  (segment (start 165.2 78.573922) (end 163.73 80.043922) (width 0.25) (layer "B.Cu") (net 1))
  (segment (start 142.17 76.934) (end 142.15 76.914) (width 0.25) (layer "B.Cu") (net 1))
  (segment (start 145.135 74.959999) (end 145.135 75.96) (width 0.25) (layer "B.Cu") (net 1))
  (segment (start 136.275 83.759) (end 136.275 84.139) (width 0.25) (layer "B.Cu") (net 1))
  (segment (start 141.15 77.905) (end 141.15 76.914) (width 0.25) (layer "B.Cu") (net 1))
  (segment (start 117.15 92.115) (end 117.15 93.35) (width 0.4) (layer "B.Cu") (net 1))
  (segment (start 136.275 83.575) (end 136.425 83.425) (width 0.25) (layer "B.Cu") (net 1))
  (segment (start 138.209 82.725) (end 138.209 81.793) (width 0.25) (layer "B.Cu") (net 1))
  (segment (start 133.825 82.775) (end 134.316 82.775) (width 0.25) (layer "B.Cu") (net 1))
  (segment (start 129.984 78.93) (end 130.361 78.93) (width 0.25) (layer "B.Cu") (net 1))
  (segment (start 106.83 90.49) (end 106.83 91.28) (width 0.4) (layer "B.Cu") (net 1))
  (segment (start 130.215 81.915) (end 130.215 82.13) (width 0.25) (layer "B.Cu") (net 1))
  (segment (start 143.024482 88.915529) (end 143.317931 88.62208) (width 0.4) (layer "B.Cu") (net 1))
  (segment (start 140.445623 80.6055) (end 140.374501 80.6055) (width 0.1) (layer "B.Cu") (net 1))
  (segment (start 138.209 79.85) (end 138.7 79.85) (width 0.25) (layer "B.Cu") (net 1))
  (segment (start 134.5 97.08) (end 134.5 94.55) (width 0.4) (layer "B.Cu") (net 1))
  (segment (start 142.165 77.905) (end 142.17 77.9) (width 0.25) (layer "B.Cu") (net 1))
  (segment (start 154.884 58.986) (end 154.73 59.14) (width 0.1) (layer "B.Cu") (net 1))
  (segment (start 136.275 84.139) (end 136.18 84.234) (width 0.25) (layer "B.Cu") (net 1))
  (segment (start 155.895 62.97) (end 155.895 61.97) (width 0.25) (layer "B.Cu") (net 1))
  (segment (start 133.825 80.175) (end 133.5 79.85) (width 0.25) (layer "B.Cu") (net 1))
  (segment (start 132.525 77.575) (end 132.525 77.084) (width 0.25) (layer "B.Cu") (net 1))
  (segment (start 156.64 63.1) (end 156.025 63.1) (width 0.25) (layer "B.Cu") (net 1))
  (segment (start 132.366 82.125) (end 132.366 80.825) (width 0.25) (layer "B.Cu") (net 1))
  (segment (start 121.8 75.17) (end 121.799 75.171) (width 0.25) (layer "B.Cu") (net 1))
  (segment (start 158.91 64.87) (end 158.89 64.85) (width 0.25) (layer "B.Cu") (net 1))
  (segment (start 129.46 79.856) (end 128.48 79.856) (width 0.25) (layer "B.Cu") (net 1))
  (segment (start 102.390003 87.94) (end 102.39 87.940001) (width 0.1) (layer "B.Cu") (net 1))
  (segment (start 107.67 91.28) (end 107.34 91.61) (width 0.4) (layer "B.Cu") (net 1))
  (segment (start 143.15 73.998) (end 144.15 73.998) (width 0.25) (layer "B.Cu") (net 1))
  (segment (start 128.48 79.856) (end 127.505 79.856) (width 0.25) (layer "B.Cu") (net 1))
  (segment (start 143.15 76.916) (end 144.15 76.916) (width 0.25) (layer "B.Cu") (net 1))
  (segment (start 143.966349 91.227769) (end 143.673607 91.520511) (width 0.1) (layer "B.Cu") (net 1))
  (segment (start 132.525 81.966) (end 132.366 82.125) (width 0.25) (layer "B.Cu") (net 1))
  (segment (start 116.19 93.11) (end 115.95 93.35) (width 0.4) (layer "B.Cu") (net 1))
  (segment (start 130.361 78.93) (end 130.416 78.875) (width 0.25) (layer "B.Cu") (net 1))
  (segment (start 139.198 77.886) (end 139.184 77.9) (width 0.25) (layer "B.Cu") (net 1))
  (segment (start 130.5 97.08) (end 130.5 94.05) (width 0.4) (layer "B.Cu") (net 1))
  (segment (start 140.374501 80.6055) (end 140.16 80.820001) (width 0.1) (layer "B.Cu") (net 1))
  (segment (start 157.14 63.1) (end 156.64 63.1) (width 0.25) (layer "B.Cu") (net 1))
  (segment (start 131.075 68.285) (end 132.1 68.285) (width 0.25) (layer "B.Cu") (net 1))
  (segment (start 116.19 92.115) (end 116.19 93.11) (width 0.4) (layer "B.Cu") (net 1))
  (segment (start 154.91 58.986) (end 154.884 58.986) (width 0.1) (layer "B.Cu") (net 1))
  (segment (start 132.525 77.084) (end 132.366 76.925) (width 0.25) (layer "B.Cu") (net 1))
  (segment (start 130.416 79.85) (end 130.416 78.875) (width 0.25) (layer "B.Cu") (net 1))
  (segment (start 163.73 72.438971) (end 163.73 72.063922) (width 0.25) (layer "B.Cu") (net 1))
  (segment (start 117.5 97.08) (end 117.5 93.960003) (width 0.6) (layer "B.Cu") (net 1))
  (segment (start 107.01 91.28) (end 107.34 91.61) (width 0.4) (layer "B.Cu") (net 1))
  (segment (start 145.097 73.998) (end 145.135 73.96) (width 0.25) (layer "B.Cu") (net 1))
  (segment (start 114.5 94.75) (end 115.35 93.9) (width 0.6) (layer "B.Cu") (net 1))
  (segment (start 156.64 62.6) (end 156.525 62.6) (width 0.25) (layer "B.Cu") (net 1))
  (segment (start 132.525 78.716) (end 132.366 78.875) (width 0.25) (layer "B.Cu") (net 1))
  (segment (start 135.45 81.8) (end 135.775 82.125) (width 0.25) (layer "B.Cu") (net 1))
  (segment (start 133.5 97.08) (end 133.5 94.55) (width 0.4) (layer "B.Cu") (net 1))
  (segment (start 115.23 92.115) (end 115.35 92.235) (width 0.4) (layer "B.Cu") (net 1))
  (segment (start 129.99 82.61) (end 130.215 82.835) (width 0.25) (layer "B.Cu") (net 1))
  (segment (start 138.5 94.545046) (end 139 94.045046) (width 0.4) (layer "B.Cu") (net 1))
  (segment (start 115.471002 64.16) (end 116.426001 63.205001) (width 0.25) (layer "B.Cu") (net 1))
  (segment (start 130.416 78.875) (end 130.416 77.9) (width 0.25) (layer "B.Cu") (net 1))
  (segment (start 151.895 63.97) (end 151.895 62.97) (width 0.25) (layer "B.Cu") (net 1))
  (segment (start 135.409 81.8) (end 135.45 81.8) (width 0.25) (layer "B.Cu") (net 1))
  (segment (start 158.91 64.986) (end 158.91 64.87) (width 0.25) (layer "B.Cu") (net 1))
  (segment (start 161.04 66.77) (end 161.04 66.86) (width 0.25) (layer "B.Cu") (net 1))
  (segment (start 154.164 63.85) (end 154.39 63.85) (width 0.1) (layer "F.Cu") (net 2))
  (segment (start 141.125 75.48) (end 141.15 75.455) (width 0.1) (layer "F.Cu") (net 2))
  (segment (start 136.75 78.55) (end 137.075 78.225) (width 0.1) (layer "F.Cu") (net 2))
  (segment (start 120.5 97.45) (end 120.5 94.51) (width 0.6) (layer "F.Cu") (net 2))
  (segment (start 154.39 60.85) (end 154.014 60.85) (width 0.1) (layer "F.Cu") (net 2))
  (segment (start 119.5 97.45) (end 119.5 94.707046) (width 0.6) (layer "F.Cu") (net 2))
  (segment (start 154.077 63.937) (end 154.164 63.85) (width 0.1) (layer "F.Cu") (net 2))
  (segment (start 120.5 94.51) (end 120.34 94.35) (width 0.6) (layer "F.Cu") (net 2))
  (segment (start 119.5 94.707046) (end 119.844245 94.362801) (width 0.6) (layer "F.Cu") (net 2))
  (segment (start 137.4 77.9) (end 137.075 78.225) (width 0.1) (layer "F.Cu") (net 2))
  (segment (start 139.86 75.71) (end 140.895 75.71) (width 0.1) (layer "F.Cu") (net 2))
  (segment (start 139.4 75.71) (end 139.63 75.48) (width 0.1) (layer "F.Cu") (net 2))
  (segment (start 139.86 75.25) (end 139.86 75.71) (width 0.1) (layer "F.Cu") (net 2))
  (segment (start 154.014 60.85) (end 153.91 60.954) (width 0.1) (layer "F.Cu") (net 2))
  (segment (start 139.63 75.48) (end 141.125 75.48) (width 0.1) (layer "F.Cu") (net 2))
  (segment (start 139.86 75.25) (end 140.945 75.25) (width 0.1) (layer "F.Cu") (net 2))
  (segment (start 137.4 77.9) (end 137.725 78.225) (width 0.1) (layer "F.Cu") (net 2))
  (segment (start 140.945 75.25) (end 141.15 75.455) (width 0.1) (layer "F.Cu") (net 2))
  (segment (start 140.895 75.71) (end 141.15 75.455) (width 0.1) (layer "F.Cu") (net 2))
  (via (at 141.15 75.455) (size 0.45) (drill 0.1) (layers "F.Cu" "B.Cu") (net 2))
  (via (at 122.830001 57.39) (size 0.45) (drill 0.1) (layers "F.Cu" "B.Cu") (net 2))
  (via (at 123.975 79.2) (size 0.45) (drill 0.1) (layers "F.Cu" "B.Cu") (net 2))
  (via (at 122.330001 60.79) (size 0.45) (drill 0.1) (layers "F.Cu" "B.Cu") (net 2))
  (via (at 135.6 62.93) (size 0.45) (drill 0.1) (layers "F.Cu" "B.Cu") (net 2))
  (via (at 119.41 87.46) (size 0.45) (drill 0.1) (layers "F.Cu" "B.Cu") (net 2))
  (via (at 119.91 87.46) (size 0.45) (drill 0.1) (layers "F.Cu" "B.Cu") (net 2))
  (via (at 132.1 66.335) (size 0.45) (drill 0.1) (layers "F.Cu" "B.Cu") (net 2))
  (via (at 135.6 60.395) (size 0.45) (drill 0.1) (layers "F.Cu" "B.Cu") (net 2))
  (via (at 135.6 61.665) (size 0.45) (drill 0.1) (layers "F.Cu" "B.Cu") (net 2))
  (via (at 127.705 77.84) (size 0.45) (drill 0.1) (layers "F.Cu" "B.Cu") (net 2))
  (via (at 123.325756 57.377199) (size 0.45) (drill 0.1) (layers "F.Cu" "B.Cu") (net 2))
  (via (at 154.077 63.937) (size 0.45) (drill 0.1) (layers "F.Cu" "B.Cu") (net 2))
  (via (at 120.414245 87.972801) (size 0.45) (drill 0.1) (layers "F.Cu" "B.Cu") (net 2))
  (via (at 122.330001 57.89) (size 0.45) (drill 0.1) (layers "F.Cu" "B.Cu") (net 2))
  (via (at 122.830001 60.29) (size 0.45) (drill 0.1) (layers "F.Cu" "B.Cu") (net 2))
  (via (at 120.91 87.96) (size 0.45) (drill 0.1) (layers "F.Cu" "B.Cu") (net 2))
  (via (at 151.955 59.97) (size 0.45) (drill 0.1) (layers "F.Cu" "B.Cu") (net 2))
  (via (at 137.725 78.225) (size 0.45) (drill 0.1) (layers "F.Cu" "B.Cu") (net 2))
  (via (at 120.62 94.86) (size 0.45) (drill 0.1) (layers "F.Cu" "B.Cu") (net 2))
  (via (at 120.91 87.460001) (size 0.45) (drill 0.1) (layers "F.Cu" "B.Cu") (net 2))
  (via (at 122.325756 60.277199) (size 0.45) (drill 0.1) (layers "F.Cu" "B.Cu") (net 2))
  (via (at 129.07 82.27) (size 0.45) (drill 0.1) (layers "F.Cu" "B.Cu") (net 2))
  (via (at 146.75 68.74) (size 0.45) (drill 0.1) (layers "F.Cu" "B.Cu") (net 2))
  (via (at 120.12 94.859999) (size 0.45) (drill 0.1) (layers "F.Cu" "B.Cu") (net 2))
  (via (at 121.830001 57.89) (size 0.45) (drill 0.1) (layers "F.Cu" "B.Cu") (net 2))
  (via (at 119.414245 87.972801) (size 0.45) (drill 0.1) (layers "F.Cu" "B.Cu") (net 2))
  (via (at 139.38 60.546) (size 0.45) (drill 0.1) (layers "F.Cu" "B.Cu") (net 2))
  (via (at 123.330001 60.79) (size 0.45) (drill 0.1) (layers "F.Cu" "B.Cu") (net 2))
  (via (at 121.830001 57.39) (size 0.45) (drill 0.1) (layers "F.Cu" "B.Cu") (net 2))
  (via (at 137.2 70.235) (size 0.45) (drill 0.1) (layers "F.Cu" "B.Cu") (net 2))
  (via (at 144.15 75.455) (size 0.45) (drill 0.1) (layers "F.Cu" "B.Cu") (net 2))
  (via (at 136.2 66.335) (size 0.45) (drill 0.1) (layers "F.Cu" "B.Cu") (net 2))
  (via (at 120.607199 94.354245) (size 0.45) (drill 0.1) (layers "F.Cu" "B.Cu") (net 2))
  (via (at 142.15 75.455) (size 0.45) (drill 0.1) (layers "F.Cu" "B.Cu") (net 2))
  (via (at 135.15 66.335) (size 0.45) (drill 0.1) (layers "F.Cu" "B.Cu") (net 2))
  (via (at 153.91 60.954) (size 0.45) (drill 0.1) (layers "F.Cu" "B.Cu") (net 2))
  (via (at 122.325756 57.377199) (size 0.45) (drill 0.1) (layers "F.Cu" "B.Cu") (net 2))
  (via (at 123.325756 60.277199) (size 0.45) (drill 0.1) (layers "F.Cu" "B.Cu") (net 2))
  (via (at 119.91 87.96) (size 0.45) (drill 0.1) (layers "F.Cu" "B.Cu") (net 2))
  (via (at 121.830001 60.79) (size 0.45) (drill 0.1) (layers "F.Cu" "B.Cu") (net 2))
  (via (at 122.830001 57.89) (size 0.45) (drill 0.1) (layers "F.Cu" "B.Cu") (net 2))
  (via (at 123.330001 57.89) (size 0.45) (drill 0.1) (layers "F.Cu" "B.Cu") (net 2))
  (via (at 136.2 70.235) (size 0.45) (drill 0.1) (layers "F.Cu" "B.Cu") (net 2))
  (via (at 120.41 87.46) (size 0.45) (drill 0.1) (layers "F.Cu" "B.Cu") (net 2))
  (via (at 137.075 78.225) (size 0.45) (drill 0.1) (layers "F.Cu" "B.Cu") (net 2))
  (via (at 140.34 60.545) (size 0.45) (drill 0.1) (layers "F.Cu" "B.Cu") (net 2))
  (via (at 120.111444 94.367046) (size 0.45) (drill 0.1) (layers "F.Cu" "B.Cu") (net 2))
  (via (at 143.15 75.455) (size 0.45) (drill 0.1) (layers "F.Cu" "B.Cu") (net 2))
  (via (at 121.830001 60.29) (size 0.45) (drill 0.1) (layers "F.Cu" "B.Cu") (net 2))
  (via (at 122.830001 60.79) (size 0.45) (drill 0.1) (layers "F.Cu" "B.Cu") (net 2))
  (via (at 134.15 66.335) (size 0.45) (drill 0.1) (layers "F.Cu" "B.Cu") (net 2))
  (via (at 129.07 81.78) (size 0.45) (drill 0.1) (layers "F.Cu" "B.Cu") (net 2))
  (segment (start 129.46 80.824) (end 129.46 81.42) (width 0.25) (layer "B.Cu") (net 2))
  (segment (start 118.5 94.707046) (end 118.844245 94.362801) (width 0.6) (layer "B.Cu") (net 2))
  (segment (start 144.15 74.966) (end 144.15 75.455) (width 0.4) (layer "B.Cu") (net 2))
  (segment (start 143.15 75.948) (end 143.15 75.455) (width 0.4) (layer "B.Cu") (net 2))
  (segment (start 144.15 75.948) (end 144.15 75.455) (width 0.4) (layer "B.Cu") (net 2))
  (segment (start 118.5 97.445) (end 118.5 94.707046) (width 0.6) (layer "B.Cu") (net 2))
  (segment (start 137.075 78.059) (end 137.234 77.9) (width 0.25) (layer "B.Cu") (net 2))
  (segment (start 137.725 78.225) (end 138.05 77.9) (width 0.25) (layer "B.Cu") (net 2))
  (segment (start 137.075 78.225) (end 137.891 78.225) (width 0.25) (layer "B.Cu") (net 2))
  (segment (start 141.15 74.966) (end 141.15 75.455) (width 0.4) (layer "B.Cu") (net 2))
  (segment (start 140.661 75.455) (end 141.15 75.455) (width 0.4) (layer "B.Cu") (net 2))
  (segment (start 138.216 77.9) (end 140.661 75.455) (width 0.4) (layer "B.Cu") (net 2))
  (segment (start 142.15 75.946) (end 142.15 75.455) (width 0.4) (layer "B.Cu") (net 2))
  (segment (start 137.725 78.225) (end 137.075 78.225) (width 0.25) (layer "B.Cu") (net 2))
  (segment (start 129.46 81.39) (end 129.46 80.824) (width 0.4) (layer "B.Cu") (net 2))
  (segment (start 151.895 60.97) (end 151.895 59.97) (width 0.25) (layer "B.Cu") (net 2))
  (segment (start 129.065 81.815) (end 129.065 82.04) (width 0.25) (layer "B.Cu") (net 2))
  (segment (start 141.15 75.946) (end 141.15 75.455) (width 0.4) (layer "B.Cu") (net 2))
  (segment (start 123.484 79.2) (end 123.975 79.2) (width 0.25) (layer "B.Cu") (net 2))
  (segment (start 138.05 77.9) (end 138.216 77.9) (width 0.25) (layer "B.Cu") (net 2))
  (segment (start 137.234 77.9) (end 138.216 77.9) (width 0.25) (layer "B.Cu") (net 2))
  (segment (start 129.07 81.78) (end 129.46 81.39) (width 0.4) (layer "B.Cu") (net 2))
  (segment (start 120.5 97.445) (end 120.5 94.51) (width 0.6) (layer "B.Cu") (net 2))
  (segment (start 137.075 78.225) (end 137.075 78.059) (width 0.25) (layer "B.Cu") (net 2))
  (segment (start 137.725 78.225) (end 137.4 77.9) (width 0.25) (layer "B.Cu") (net 2))
  (segment (start 137.725 78.225) (end 137.891 78.225) (width 0.25) (layer "B.Cu") (net 2))
  (segment (start 151.895 61.97) (end 151.895 60.97) (width 0.25) (layer "B.Cu") (net 2))
  (segment (start 142.15 74.966) (end 142.15 75.455) (width 0.4) (layer "B.Cu") (net 2))
  (segment (start 137.891 78.225) (end 138.216 77.9) (width 0.25) (layer "B.Cu") (net 2))
  (segment (start 129.46 81.42) (end 129.065 81.815) (width 0.25) (layer "B.Cu") (net 2))
  (segment (start 143.15 74.966) (end 143.15 75.455) (width 0.4) (layer "B.Cu") (net 2))
  (segment (start 120.5 94.51) (end 120.34 94.35) (width 0.6) (layer "B.Cu") (net 2))
  (segment (start 137.4 77.9) (end 137.234 77.9) (width 0.25) (layer "B.Cu") (net 2))
  (segment (start 164.035 77.428922) (end 164.425 77.428922) (width 0.25) (layer "F.Cu") (net 3))
  (segment (start 162.433 77.178922) (end 163 77.178922) (width 0.25) (layer "F.Cu") (net 3))
  (segment (start 163.25 77.428922) (end 163.25 76.878922) (width 0.25) (layer "F.Cu") (net 3))
  (segment (start 164.424 74.929922) (end 164.425 74.928922) (width 0.25) (layer "F.Cu") (net 3))
  (segment (start 163.501 74.929922) (end 163.25 74.678922) (width 0.25) (layer "F.Cu") (net 3))
  (segment (start 163.25 76.328922) (end 163.25 75.778922) (width 0.25) (layer "F.Cu") (net 3))
  (segment (start 164.035 77.428922) (end 163.25 77.428922) (width 0.25) (layer "F.Cu") (net 3))
  (segment (start 163.249 74.679922) (end 163.25 74.678922) (width 0.25) (layer "F.Cu") (net 3))
  (segment (start 164.035 74.929922) (end 163.501 74.929922) (width 0.25) (layer "F.Cu") (net 3))
  (segment (start 163 77.178922) (end 163.25 77.428922) (width 0.25) (layer "F.Cu") (net 3))
  (segment (start 162.433 77.178922) (end 162.95 77.178922) (width 0.25) (layer "F.Cu") (net 3))
  (segment (start 161.734 74.678922) (end 161.484 74.928922) (width 0.25) (layer "F.Cu") (net 3))
  (segment (start 161.975 77.178922) (end 161.734 77.178922) (width 0.25) (layer "F.Cu") (net 3))
  (segment (start 163.25 75.778922) (end 163.25 75.228922) (width 0.25) (layer "F.Cu") (net 3))
  (segment (start 164.035 74.929922) (end 164.424 74.929922) (width 0.25) (layer "F.Cu") (net 3))
  (segment (start 162.433 77.178922) (end 161.975 77.178922) (width 0.25) (layer "F.Cu") (net 3))
  (segment (start 164.035 74.929922) (end 163.549 74.929922) (width 0.25) (layer "F.Cu") (net 3))
  (segment (start 162.95 77.178922) (end 163.25 76.878922) (width 0.25) (layer "F.Cu") (net 3))
  (segment (start 161.976 74.679922) (end 161.975 74.678922) (width 0.25) (layer "F.Cu") (net 3))
  (segment (start 163.25 75.228922) (end 163.25 74.678922) (width 0.25) (layer "F.Cu") (net 3))
  (segment (start 162.433 74.679922) (end 163.249 74.679922) (width 0.25) (layer "F.Cu") (net 3))
  (segment (start 161.975 74.678922) (end 161.734 74.678922) (width 0.25) (layer "F.Cu") (net 3))
  (segment (start 163.549 74.929922) (end 163.25 75.228922) (width 0.25) (layer "F.Cu") (net 3))
  (segment (start 161.734 77.178922) (end 161.484 76.928922) (width 0.25) (layer "F.Cu") (net 3))
  (segment (start 163.25 76.878922) (end 163.25 76.328922) (width 0.25) (layer "F.Cu") (net 3))
  (segment (start 162.433 74.679922) (end 161.976 74.679922) (width 0.25) (layer "F.Cu") (net 3))
  (via (at 104.930001 60.69) (size 0.45) (drill 0.1) (layers "F.Cu" "B.Cu") (net 3))
  (via (at 163.25 75.778922) (size 0.45) (drill 0.1) (layers "F.Cu" "B.Cu") (net 3))
  (via (at 104.149999 71.45) (size 0.45) (drill 0.1) (layers "F.Cu" "B.Cu") (net 3))
  (via (at 102.649999 71.95) (size 0.45) (drill 0.1) (layers "F.Cu" "B.Cu") (net 3))
  (via (at 104.930001 63.19) (size 0.45) (drill 0.1) (layers "F.Cu" "B.Cu") (net 3))
  (via (at 163.25 77.428922) (size 0.45) (drill 0.1) (layers "F.Cu" "B.Cu") (net 3))
  (via (at 104.430001 63.19) (size 0.45) (drill 0.1) (layers "F.Cu" "B.Cu") (net 3))
  (via (at 104.649999 71.450001) (size 0.45) (drill 0.1) (layers "F.Cu" "B.Cu") (net 3))
  (via (at 104.430001 61.69) (size 0.45) (drill 0.1) (layers "F.Cu" "B.Cu") (net 3))
  (via (at 104.930001 62.69) (size 0.45) (drill 0.1) (layers "F.Cu" "B.Cu") (net 3))
  (via (at 104.930001 64.19) (size 0.45) (drill 0.1) (layers "F.Cu" "B.Cu") (net 3))
  (via (at 104.930001 61.19) (size 0.45) (drill 0.1) (layers "F.Cu" "B.Cu") (net 3))
  (via (at 104.930001 61.69) (size 0.45) (drill 0.1) (layers "F.Cu" "B.Cu") (net 3))
  (via (at 103.649999 71.45) (size 0.45) (drill 0.1) (layers "F.Cu" "B.Cu") (net 3))
  (via (at 103.149999 71.45) (size 0.45) (drill 0.1) (layers "F.Cu" "B.Cu") (net 3))
  (via (at 103.649999 71.95) (size 0.45) (drill 0.1) (layers "F.Cu" "B.Cu") (net 3))
  (via (at 161.484 74.928922) (size 0.45) (drill 0.1) (layers "F.Cu" "B.Cu") (net 3))
  (via (at 163 61.27) (size 0.45) (drill 0.1) (layers "F.Cu" "B.Cu") (net 3))
  (via (at 164.425 77.428922) (size 0.45) (drill 0.1) (layers "F.Cu" "B.Cu") (net 3))
  (via (at 102.649999 71.450001) (size 0.45) (drill 0.1) (layers "F.Cu" "B.Cu") (net 3))
  (via (at 104.430001 63.69) (size 0.45) (drill 0.1) (layers "F.Cu" "B.Cu") (net 3))
  (via (at 163.25 74.678922) (size 0.45) (drill 0.1) (layers "F.Cu" "B.Cu") (net 3))
  (via (at 161.975 74.678922) (size 0.45) (drill 0.1) (layers "F.Cu" "B.Cu") (net 3))
  (via (at 104.430001 61.19) (size 0.45) (drill 0.1) (layers "F.Cu" "B.Cu") (net 3))
  (via (at 104.430001 64.19) (size 0.45) (drill 0.1) (layers "F.Cu" "B.Cu") (net 3))
  (via (at 161.484 76.928922) (size 0.45) (drill 0.1) (layers "F.Cu" "B.Cu") (net 3))
  (via (at 103.149998 71.95) (size 0.45) (drill 0.1) (layers "F.Cu" "B.Cu") (net 3))
  (via (at 163.25 75.228922) (size 0.45) (drill 0.1) (layers "F.Cu" "B.Cu") (net 3))
  (via (at 163.25 76.328922) (size 0.45) (drill 0.1) (layers "F.Cu" "B.Cu") (net 3))
  (via (at 104.15 71.95) (size 0.45) (drill 0.1) (layers "F.Cu" "B.Cu") (net 3))
  (via (at 104.430001 60.69) (size 0.45) (drill 0.1) (layers "F.Cu" "B.Cu") (net 3))
  (via (at 163.25 76.878922) (size 0.45) (drill 0.1) (layers "F.Cu" "B.Cu") (net 3))
  (via (at 104.430001 60.19) (size 0.45) (drill 0.1) (layers "F.Cu" "B.Cu") (net 3))
  (via (at 163.7 61.28) (size 0.45) (drill 0.1) (layers "F.Cu" "B.Cu") (net 3))
  (via (at 161.975 77.178922) (size 0.45) (drill 0.1) (layers "F.Cu" "B.Cu") (net 3))
  (via (at 104.430001 62.69) (size 0.45) (drill 0.1) (layers "F.Cu" "B.Cu") (net 3))
  (via (at 104.649999 71.95) (size 0.45) (drill 0.1) (layers "F.Cu" "B.Cu") (net 3))
  (via (at 105.149998 71.95) (size 0.45) (drill 0.1) (layers "F.Cu" "B.Cu") (net 3))
  (via (at 105.149999 71.45) (size 0.45) (drill 0.1) (layers "F.Cu" "B.Cu") (net 3))
  (via (at 104.930001 60.19) (size 0.45) (drill 0.1) (layers "F.Cu" "B.Cu") (net 3))
  (via (at 104.930001 63.69) (size 0.45) (drill 0.1) (layers "F.Cu" "B.Cu") (net 3))
  (via (at 164.425 74.928922) (size 0.45) (drill 0.1) (layers "F.Cu" "B.Cu") (net 3))
  (segment (start 164.425 74.928922) (end 165.2 74.928922) (width 0.25) (layer "B.Cu") (net 3))
  (segment (start 164.425 77.428922) (end 165.2 77.428922) (width 0.25) (layer "B.Cu") (net 3))
  (segment (start 109.575 78.6) (end 109.575 78.45) (width 0.25) (layer "F.Cu") (net 4))
  (segment (start 109.075 79.25) (end 109.075 78.6) (width 0.25) (layer "F.Cu") (net 4))
  (segment (start 109.575 79.25) (end 109.575 78.6) (width 0.25) (layer "F.Cu") (net 4))
  (via (at 109.1 78.2) (size 0.45) (drill 0.1) (layers "F.Cu" "B.Cu") (net 4))
  (segment (start 108.431 78.869) (end 108.431 79.65) (width 0.25) (layer "B.Cu") (net 4))
  (segment (start 109.1 78.2) (end 108.431 78.869) (width 0.25) (layer "B.Cu") (net 4))
  (via (at 108.425 83.9) (size 0.45) (drill 0.1) (layers "F.Cu" "B.Cu") (net 5))
  (segment (start 108.43 85.165001) (end 108.43 84.68) (width 0.1) (layer "B.Cu") (net 5))
  (segment (start 108.43 84.68) (end 108.43 83.905) (width 0.1) (layer "B.Cu") (net 5))
  (segment (start 108.431 83.894) (end 108.425 83.9) (width 0.1) (layer "B.Cu") (net 5))
  (segment (start 107.425 84.655) (end 108.405 84.655) (width 0.1) (layer "B.Cu") (net 5))
  (segment (start 108.431 83.67) (end 108.431 83.894) (width 0.1) (layer "B.Cu") (net 5))
  (segment (start 108.405 84.655) (end 108.43 84.68) (width 0.1) (layer "B.Cu") (net 5))
  (segment (start 108.43 83.905) (end 108.425 83.9) (width 0.1) (layer "B.Cu") (net 5))
  (segment (start 110.065 85.685001) (end 108.95 85.685001) (width 0.1) (layer "B.Cu") (net 5))
  (segment (start 108.95 85.685001) (end 108.43 85.165001) (width 0.1) (layer "B.Cu") (net 5))
  (segment (start 117.159001 63.440001) (end 117.394001 63.205001) (width 0.25) (layer "F.Cu") (net 6))
  (segment (start 117.159001 63.686) (end 117.159001 63.440001) (width 0.25) (layer "F.Cu") (net 6))
  (via (at 117.394001 63.205001) (size 0.45) (drill 0.1) (layers "F.Cu" "B.Cu") (net 6))
  (segment (start 116.45 64.149002) (end 117.394001 63.205001) (width 0.25) (layer "B.Cu") (net 6))
  (segment (start 116.45 64.19) (end 116.45 64.149002) (width 0.25) (layer "B.Cu") (net 6))
  (segment (start 112.064 85.686) (end 111.095 86.655) (width 0.1) (layer "B.Cu") (net 7))
  (segment (start 112.115 85.686) (end 112.064 85.686) (width 0.1) (layer "B.Cu") (net 7))
  (segment (start 113.5 94.2) (end 112.95 93.65) (width 0.6) (layer "F.Cu") (net 8))
  (segment (start 112.5 97.075046) (end 112.5 94.1) (width 0.6) (layer "F.Cu") (net 8))
  (segment (start 112.5 94.1) (end 112.95 93.65) (width 0.6) (layer "F.Cu") (net 8))
  (segment (start 113.5 97.075046) (end 113.5 94.2) (width 0.6) (layer "F.Cu") (net 8))
  (via (at 113.85 93.9) (size 0.45) (drill 0.1) (layers "F.Cu" "B.Cu") (net 8))
  (via (at 112.65 93.9) (size 0.45) (drill 0.1) (layers "F.Cu" "B.Cu") (net 8))
  (via (at 112.05 93.9) (size 0.45) (drill 0.1) (layers "F.Cu" "B.Cu") (net 8))
  (via (at 113.85 92.8) (size 0.45) (drill 0.1) (layers "F.Cu" "B.Cu") (net 8))
  (via (at 113.25 93.9) (size 0.45) (drill 0.1) (layers "F.Cu" "B.Cu") (net 8))
  (via (at 112.65 93.35) (size 0.45) (drill 0.1) (layers "F.Cu" "B.Cu") (net 8))
  (via (at 113.85 93.35) (size 0.45) (drill 0.1) (layers "F.Cu" "B.Cu") (net 8))
  (via (at 113.25 93.35) (size 0.45) (drill 0.1) (layers "F.Cu" "B.Cu") (net 8))
  (via (at 112.65 92.8) (size 0.45) (drill 0.1) (layers "F.Cu" "B.Cu") (net 8))
  (via (at 113.25 92.8) (size 0.45) (drill 0.1) (layers "F.Cu" "B.Cu") (net 8))
  (via (at 112.05 93.35) (size 0.45) (drill 0.1) (layers "F.Cu" "B.Cu") (net 8))
  (via (at 112.05 92.8) (size 0.45) (drill 0.1) (layers "F.Cu" "B.Cu") (net 8))
  (segment (start 111.5 97.08) (end 111.5 94.2) (width 0.6) (layer "B.Cu") (net 8))
  (segment (start 111.5 94.2) (end 112.05 93.65) (width 0.6) (layer "B.Cu") (net 8))
  (segment (start 113.5 94.2) (end 112.95 93.65) (width 0.6) (layer "B.Cu") (net 8))
  (segment (start 112.05 93.65) (end 112.95 93.65) (width 0.6) (layer "B.Cu") (net 8))
  (segment (start 113.5 97.08) (end 113.5 94.2) (width 0.6) (layer "B.Cu") (net 8))
  (segment (start 112.5 94.1) (end 112.95 93.65) (width 0.6) (layer "B.Cu") (net 8))
  (segment (start 112.5 97.08) (end 112.5 94.1) (width 0.6) (layer "B.Cu") (net 8))
  (segment (start 153.66 63.35) (end 153.6 63.29) (width 0.1) (layer "F.Cu") (net 9))
  (segment (start 154.39 63.35) (end 153.66 63.35) (width 0.1) (layer "F.Cu") (net 9))
  (via (at 153.6 63.29) (size 0.45) (drill 0.1) (layers "F.Cu" "B.Cu") (net 9))
  (via (at 153.32 59.22) (size 0.45) (drill 0.1) (layers "F.Cu" "B.Cu") (net 9))
  (segment (start 153.32 59.22) (end 153.32 62.55) (width 0.25) (layer "In3.Cu") (net 9))
  (segment (start 153.32 62.55) (end 153.6 62.83) (width 0.25) (layer "In3.Cu") (net 9))
  (segment (start 153.6 62.83) (end 153.6 63.29) (width 0.25) (layer "In3.Cu") (net 9))
  (segment (start 157.89 56.905) (end 158.345 56.905) (width 0.25) (layer "B.Cu") (net 9))
  (segment (start 153.79 63.1) (end 153.914 63.1) (width 0.1) (layer "B.Cu") (net 9))
  (segment (start 152.925 60.955) (end 153.42 61.45) (width 0.1) (layer "B.Cu") (net 9))
  (segment (start 153.32 57.98) (end 154.395 56.905) (width 0.25) (layer "B.Cu") (net 9))
  (segment (start 155.89 56.905) (end 156.89 56.905) (width 0.25) (layer "B.Cu") (net 9))
  (segment (start 155.91 58.985) (end 156.38 58.515) (width 0.1) (layer "B.Cu") (net 9))
  (segment (start 158.91 57.47) (end 158.91 58.985) (width 0.25) (layer "B.Cu") (net 9))
  (segment (start 161.895 58.775) (end 161.895 60.97) (width 0.25) (layer "B.Cu") (net 9))
  (segment (start 161.895 61.97) (end 161.895 60.97) (width 0.25) (layer "B.Cu") (net 9))
  (segment (start 154.395 56.905) (end 155.89 56.905) (width 0.25) (layer "B.Cu") (net 9))
  (segment (start 153.41 63.48) (end 153.6 63.29) (width 0.1) (layer "B.Cu") (net 9))
  (segment (start 153.41 64.33) (end 153.41 63.48) (width 0.1) (layer "B.Cu") (net 9))
  (segment (start 151.955 64.97) (end 152.455 64.47) (width 0.1) (layer "B.Cu") (net 9))
  (segment (start 152.91 60.955) (end 152.925 60.955) (width 0.1) (layer "B.Cu") (net 9))
  (segment (start 156.38 58.515) (end 156.38 57.395) (width 0.1) (layer "B.Cu") (net 9))
  (segment (start 158.345 56.905) (end 158.91 57.47) (width 0.25) (layer "B.Cu") (net 9))
  (segment (start 153.32 59.22) (end 153.32 57.98) (width 0.25) (layer "B.Cu") (net 9))
  (segment (start 153.42 62.496) (end 153.894 62.97) (width 0.1) (layer "B.Cu") (net 9))
  (segment (start 161.35 58.23) (end 161.895 58.775) (width 0.25) (layer "B.Cu") (net 9))
  (segment (start 153.42 61.45) (end 153.42 62.496) (width 0.1) (layer "B.Cu") (net 9))
  (segment (start 152.455 64.47) (end 153.27 64.47) (width 0.1) (layer "B.Cu") (net 9))
  (segment (start 156.89 56.905) (end 157.89 56.905) (width 0.25) (layer "B.Cu") (net 9))
  (segment (start 159.665 58.23) (end 158.91 58.985) (width 0.25) (layer "B.Cu") (net 9))
  (segment (start 159.665 58.23) (end 161.35 58.23) (width 0.25) (layer "B.Cu") (net 9))
  (segment (start 153.6 63.29) (end 153.79 63.1) (width 0.1) (layer "B.Cu") (net 9))
  (segment (start 161.895 62.97) (end 161.895 61.97) (width 0.25) (layer "B.Cu") (net 9))
  (segment (start 153.27 64.47) (end 153.41 64.33) (width 0.1) (layer "B.Cu") (net 9))
  (segment (start 156.38 57.395) (end 155.89 56.905) (width 0.1) (layer "B.Cu") (net 9))
  (segment (start 158.89 65.53) (end 158.89 65.35) (width 0.1) (layer "F.Cu") (net 10))
  (segment (start 159.91 66.46) (end 159.82 66.46) (width 0.1) (layer "F.Cu") (net 10))
  (segment (start 159.82 66.46) (end 158.89 65.53) (width 0.1) (layer "F.Cu") (net 10))
  (via (at 159.91 66.46) (size 0.45) (drill 0.1) (layers "F.Cu" "B.Cu") (net 10))
  (via (at 164.035 75.429922) (size 0.45) (drill 0.1) (layers "F.Cu" "B.Cu") (net 10))
  (segment (start 159.91 68.4) (end 159.91 66.46) (width 0.1) (layer "In3.Cu") (net 10))
  (segment (start 163.9 70.22) (end 161.73 70.22) (width 0.1) (layer "In3.Cu") (net 10))
  (segment (start 165.2 75.978922) (end 165.625 75.978922) (width 0.1) (layer "In3.Cu") (net 10))
  (segment (start 161.73 70.22) (end 159.91 68.4) (width 0.1) (layer "In3.Cu") (net 10))
  (segment (start 164.035 75.429922) (end 164.651 75.429922) (width 0.1) (layer "In3.Cu") (net 10))
  (segment (start 166 72.32) (end 163.9 70.22) (width 0.1) (layer "In3.Cu") (net 10))
  (segment (start 164.651 75.429922) (end 165.2 75.978922) (width 0.1) (layer "In3.Cu") (net 10))
  (segment (start 166 75.603922) (end 166 72.32) (width 0.1) (layer "In3.Cu") (net 10))
  (segment (start 165.625 75.978922) (end 166 75.603922) (width 0.1) (layer "In3.Cu") (net 10))
  (segment (start 159.91 65.954) (end 159.91 66.46) (width 0.25) (layer "B.Cu") (net 10))
  (segment (start 159.91 66.985) (end 159.91 66.46) (width 0.25) (layer "B.Cu") (net 10))
  (segment (start 158.39 65.61) (end 158.39 65.35) (width 0.1) (layer "F.Cu") (net 11))
  (segment (start 158.91 66.45) (end 158.91 66.13) (width 0.1) (layer "F.Cu") (net 11))
  (segment (start 158.91 66.13) (end 158.39 65.61) (width 0.1) (layer "F.Cu") (net 11))
  (via (at 162.433 76.678922) (size 0.45) (drill 0.1) (layers "F.Cu" "B.Cu") (net 11))
  (via (at 158.91 66.45) (size 0.45) (drill 0.1) (layers "F.Cu" "B.Cu") (net 11))
  (segment (start 161.817 76.678922) (end 161.268 76.129922) (width 0.1) (layer "In3.Cu") (net 11))
  (segment (start 158.91 69.01) (end 158.91 66.45) (width 0.1) (layer "In3.Cu") (net 11))
  (segment (start 159.59 75.41) (end 159.59 69.69) (width 0.1) (layer "In3.Cu") (net 11))
  (segment (start 160.309922 76.129922) (end 159.59 75.41) (width 0.1) (layer "In3.Cu") (net 11))
  (segment (start 159.59 69.69) (end 158.91 69.01) (width 0.1) (layer "In3.Cu") (net 11))
  (segment (start 161.268 76.129922) (end 160.309922 76.129922) (width 0.1) (layer "In3.Cu") (net 11))
  (segment (start 162.433 76.678922) (end 161.817 76.678922) (width 0.1) (layer "In3.Cu") (net 11))
  (segment (start 158.91 65.954) (end 158.91 66.45) (width 0.25) (layer "B.Cu") (net 11))
  (segment (start 158.91 66.985) (end 158.91 66.45) (width 0.25) (layer "B.Cu") (net 11))
  (segment (start 161.071065 78.128765) (end 161.004078 78.128765) (width 0.2) (layer "F.Cu") (net 12))
  (segment (start 161.518258 78.128765) (end 161.585245 78.128765) (width 0.2) (layer "F.Cu") (net 12))
  (segment (start 161.654849 78.128765) (end 161.585245 78.128765) (width 0.2) (layer "F.Cu") (net 12))
  (segment (start 158.049619 80.764455) (end 158.049619 80.852843) (width 0.2) (layer "F.Cu") (net 12))
  (segment (start 161.518258 78.128765) (end 161.44342 78.128765) (width 0.2) (layer "F.Cu") (net 12))
  (segment (start 158.112118 80.613567) (end 160.309017 78.416668) (width 0.2) (layer "F.Cu") (net 12))
  (segment (start 161.793354 78.178922) (end 162.433 78.178922) (width 0.2) (layer "F.Cu") (net 12))
  (segment (start 161.689651 78.128765) (end 161.654849 78.128765) (width 0.2) (layer "F.Cu") (net 12))
  (segment (start 161.205039 78.128765) (end 161.071065 78.128765) (width 0.2) (layer "F.Cu") (net 12))
  (segment (start 161.44342 78.128765) (end 161.368582 78.128765) (width 0.2) (layer "F.Cu") (net 12))
  (segment (start 161.368582 78.128765) (end 161.205039 78.128765) (width 0.2) (layer "F.Cu") (net 12))
  (via (at 158.049619 80.852843) (size 0.45) (drill 0.1) (layers "F.Cu" "B.Cu") (net 12))
  (arc (start 161.689651 78.128765) (mid 161.712881 78.138994) (end 161.732999 78.153922) (width 0.2) (layer "F.Cu") (net 12))
  (arc (start 158.112118 80.613567) (mid 158.065861 80.682795) (end 158.049619 80.764455) (width 0.2) (layer "F.Cu") (net 12))
  (arc (start 161.004078 78.128765) (mid 160.627913 78.203588) (end 160.309017 78.416668) (width 0.2) (layer "F.Cu") (net 12))
  (arc (start 161.732999 78.153922) (mid 161.76069 78.172424) (end 161.793354 78.178922) (width 0.2) (layer "F.Cu") (net 12))
  (segment (start 155.714 81.59) (end 155.564 81.74) (width 0.2) (layer "B.Cu") (net 12))
  (segment (start 157.810343 80.915342) (end 157.579264 81.146421) (width 0.2) (layer "B.Cu") (net 12))
  (segment (start 156.870503 81.44) (end 156.076132 81.44) (width 0.2) (layer "B.Cu") (net 12))
  (segment (start 157.961231 80.852843) (end 158.049619 80.852843) (width 0.2) (layer "B.Cu") (net 12))
  (arc (start 157.810343 80.915342) (mid 157.879571 80.869085) (end 157.961231 80.852843) (width 0.2) (layer "B.Cu") (net 12))
  (arc (start 155.714 81.59) (mid 155.880147 81.478983) (end 156.076132 81.44) (width 0.2) (layer "B.Cu") (net 12))
  (arc (start 157.579264 81.146421) (mid 157.254081 81.363701) (end 156.870503 81.44) (width 0.2) (layer "B.Cu") (net 12))
  (segment (start 151.825319 83.352476) (end 152.300343 82.877452) (width 0.2) (layer "F.Cu") (net 13))
  (segment (start 139.777426 83.3) (end 140.088786 83.3) (width 0.1) (layer "F.Cu") (net 13))
  (segment (start 139.675 83.197574) (end 139.675 83.172427) (width 0.1) (layer "F.Cu") (net 13))
  (segment (start 139.777425 83.07) (end 139.86 83.07) (width 0.1) (layer "F.Cu") (net 13))
  (segment (start 141.908749 83.27) (end 140.161213 83.27) (width 0.2) (layer "F.Cu") (net 13))
  (segment (start 150.527622 83.89) (end 143.405562 83.89) (width 0.2) (layer "F.Cu") (net 13))
  (segment (start 152.451231 82.814953) (end 152.539619 82.814953) (width 0.2) (layer "F.Cu") (net 13))
  (via (at 152.539619 82.814953) (size 0.45) (drill 0.1) (layers "F.Cu" "B.Cu") (net 13))
  (arc (start 140.088786 83.3) (mid 140.108385 83.296101) (end 140.125 83.285) (width 0.1) (layer "F.Cu") (net 13))
  (arc (start 152.451231 82.814953) (mid 152.369571 82.831195) (end 152.300343 82.877452) (width 0.2) (layer "F.Cu") (net 13))
  (arc (start 139.777426 83.3) (mid 139.738229 83.292204) (end 139.705 83.27) (width 0.1) (layer "F.Cu") (net 13))
  (arc (start 139.675 83.197574) (mid 139.682796 83.236771) (end 139.705 83.27) (width 0.1) (layer "F.Cu") (net 13))
  (arc (start 151.825319 83.352476) (mid 151.22993 83.750302) (end 150.527622 83.89) (width 0.2) (layer "F.Cu") (net 13))
  (arc (start 142.657156 83.58) (mid 143.000527 83.809433) (end 143.405562 83.89) (width 0.2) (layer "F.Cu") (net 13))
  (arc (start 141.908749 83.27) (mid 142.313784 83.350566) (end 142.657156 83.58) (width 0.2) (layer "F.Cu") (net 13))
  (arc (start 139.705 83.1) (mid 139.738229 83.077797) (end 139.777425 83.07) (width 0.1) (layer "F.Cu") (net 13))
  (arc (start 140.161213 83.27) (mid 140.141614 83.273898) (end 140.125 83.285) (width 0.2) (layer "F.Cu") (net 13))
  (arc (start 139.705 83.1) (mid 139.682796 83.133229) (end 139.675 83.172427) (width 0.1) (layer "F.Cu") (net 13))
  (segment (start 152.539619 82.814953) (end 152.539619 82.726565) (width 0.2) (layer "B.Cu") (net 13))
  (segment (start 152.602118 82.575677) (end 153.540441 81.637354) (width 0.2) (layer "B.Cu") (net 13))
  (segment (start 154.446 81.59) (end 154.596 81.74) (width 0.2) (layer "B.Cu") (net 13))
  (segment (start 154.083867 81.44) (end 154.016898 81.44) (width 0.2) (layer "B.Cu") (net 13))
  (arc (start 154.083867 81.44) (mid 154.279852 81.478983) (end 154.446 81.59) (width 0.2) (layer "B.Cu") (net 13))
  (arc (start 152.602118 82.575677) (mid 152.555861 82.644905) (end 152.539619 82.726565) (width 0.2) (layer "B.Cu") (net 13))
  (arc (start 154.016898 81.44) (mid 153.759041 81.49129) (end 153.540441 81.637354) (width 0.2) (layer "B.Cu") (net 13))
  (via (at 164.3 73.929923) (size 0.45) (drill 0.1) (layers "F.Cu" "B.Cu") (net 14))
  (segment (start 155.719 77.57) (end 155.569 77.42) (width 0.2) (layer "B.Cu") (net 14))
  (segment (start 157.818577 77.208577) (end 157.81562 77.211535) (width 0.2) (layer "B.Cu") (net 14))
  (segment (start 156.588078 77.72) (end 156.081132 77.72) (width 0.2) (layer "B.Cu") (net 14))
  (segment (start 161.29551 73.41) (end 163.195279 73.41) (width 0.2) (layer "B.Cu") (net 14))
  (segment (start 158.33 75.973896) (end 158.33 75.922156) (width 0.2) (layer "B.Cu") (net 14))
  (segment (start 164.191422 73.929923) (end 164.3 73.929923) (width 0.2) (layer "B.Cu") (net 14))
  (segment (start 163.822882 73.669961) (end 164.006067 73.853146) (width 0.2) (layer "B.Cu") (net 14))
  (segment (start 159.198577 74.278577) (end 158.878007 74.599148) (width 0.2) (layer "B.Cu") (net 14))
  (arc (start 158.33 75.922156) (mid 158.472422 75.206149) (end 158.878007 74.599148) (width 0.2) (layer "B.Cu") (net 14))
  (arc (start 163.822882 73.669961) (mid 163.534935 73.477561) (end 163.195279 73.41) (width 0.2) (layer "B.Cu") (net 14))
  (arc (start 159.198577 74.278577) (mid 160.160658 73.635735) (end 161.29551 73.41) (width 0.2) (layer "B.Cu") (net 14))
  (arc (start 155.719 77.57) (mid 155.885147 77.681016) (end 156.081132 77.72) (width 0.2) (layer "B.Cu") (net 14))
  (arc (start 158.33 75.973896) (mid 158.197085 76.6421) (end 157.818577 77.208577) (width 0.2) (layer "B.Cu") (net 14))
  (arc (start 164.191422 73.929923) (mid 164.091108 73.909969) (end 164.006067 73.853146) (width 0.2) (layer "B.Cu") (net 14))
  (arc (start 156.588078 77.72) (mid 157.252419 77.587854) (end 157.81562 77.211535) (width 0.2) (layer "B.Cu") (net 14))
  (segment (start 139.675 82.022426) (end 139.675 82.047573) (width 0.1) (layer "F.Cu") (net 15))
  (segment (start 139.777425 82.15) (end 139.86 82.15) (width 0.1) (layer "F.Cu") (net 15))
  (segment (start 149.9975 80.599275) (end 149.353387 81.243387) (width 0.2) (layer "F.Cu") (net 15))
  (segment (start 140.161213 81.95) (end 147.647475 81.95) (width 0.2) (layer "F.Cu") (net 15))
  (segment (start 150.06 80.36) (end 150.06 80.448388) (width 0.2) (layer "F.Cu") (net 15))
  (segment (start 139.777426 81.92) (end 140.088786 81.92) (width 0.1) (layer "F.Cu") (net 15))
  (via (at 150.06 80.36) (size 0.45) (drill 0.1) (layers "F.Cu" "B.Cu") (net 15))
  (arc (start 139.705 82.12) (mid 139.738229 82.142203) (end 139.777425 82.15) (width 0.1) (layer "F.Cu") (net 15))
  (arc (start 140.125 81.935) (mid 140.108385 81.923898) (end 140.088786 81.92) (width 0.1) (layer "F.Cu") (net 15))
  (arc (start 139.705 81.95) (mid 139.738229 81.927796) (end 139.777426 81.92) (width 0.1) (layer "F.Cu") (net 15))
  (arc (start 140.125 81.935) (mid 140.141614 81.946101) (end 140.161213 81.95) (width 0.1) (layer "F.Cu") (net 15))
  (arc (start 139.705 82.12) (mid 139.682796 82.086771) (end 139.675 82.047573) (width 0.1) (layer "F.Cu") (net 15))
  (arc (start 149.9975 80.599275) (mid 150.043756 80.530047) (end 150.06 80.448388) (width 0.2) (layer "F.Cu") (net 15))
  (arc (start 147.647475 81.95) (mid 148.570708 81.766357) (end 149.353387 81.243387) (width 0.2) (layer "F.Cu") (net 15))
  (arc (start 139.705 81.95) (mid 139.682796 81.983229) (end 139.675 82.022426) (width 0.1) (layer "F.Cu") (net 15))
  (segment (start 153.588888 77.72) (end 154.088867 77.72) (width 0.2) (layer "B.Cu") (net 15))
  (segment (start 154.451 77.57) (end 154.601 77.42) (width 0.2) (layer "B.Cu") (net 15))
  (segment (start 150.06 80.36) (end 150.148388 80.36) (width 0.2) (layer "B.Cu") (net 15))
  (segment (start 152.373236 78.223539) (end 150.299275 80.2975) (width 0.2) (layer "B.Cu") (net 15))
  (arc (start 152.373236 78.223539) (mid 152.930982 77.850865) (end 153.588888 77.72) (width 0.2) (layer "B.Cu") (net 15))
  (arc (start 150.299275 80.2975) (mid 150.230047 80.343756) (end 150.148388 80.36) (width 0.2) (layer "B.Cu") (net 15))
  (arc (start 154.451 77.57) (mid 154.284852 77.681016) (end 154.088867 77.72) (width 0.2) (layer "B.Cu") (net 15))
  (segment (start 150.985 63.97) (end 151.11 64.095) (width 0.2) (layer "F.Cu") (net 16))
  (segment (start 153.445576 64.22) (end 151.411776 64.22) (width 0.2) (layer "F.Cu") (net 16))
  (segment (start 153.759423 64.35) (end 154.39 64.35) (width 0.1) (layer "F.Cu") (net 16))
  (via (at 150.985 63.97) (size 0.45) (drill 0.1) (layers "F.Cu" "B.Cu") (net 16))
  (arc (start 153.759423 64.35) (mid 153.674497 64.333107) (end 153.6025 64.285) (width 0.1) (layer "F.Cu") (net 16))
  (arc (start 151.11 64.095) (mid 151.248456 64.187513) (end 151.411776 64.22) (width 0.2) (layer "F.Cu") (net 16))
  (arc (start 153.445576 64.22) (mid 153.530502 64.236892) (end 153.6025 64.285) (width 0.1) (layer "F.Cu") (net 16))
  (segment (start 149.578922 64.27) (end 150.412867 64.27) (width 0.2) (layer "B.Cu") (net 16))
  (segment (start 147.793155 63.530311) (end 144.256636 59.993792) (width 0.2) (layer "B.Cu") (net 16))
  (segment (start 135.749 58.25) (end 135.599 58.1) (width 0.2) (layer "B.Cu") (net 16))
  (segment (start 150.775 64.12) (end 150.925 63.97) (width 0.2) (layer "B.Cu") (net 16))
  (segment (start 140.40888 58.4) (end 136.111132 58.4) (width 0.2) (layer "B.Cu") (net 16))
  (arc (start 140.40888 58.4) (mid 142.49127 58.814213) (end 144.256636 59.993792) (width 0.2) (layer "B.Cu") (net 16))
  (arc (start 135.749 58.25) (mid 135.915147 58.361016) (end 136.111132 58.4) (width 0.2) (layer "B.Cu") (net 16))
  (arc (start 147.793155 63.530311) (mid 148.612471 64.077761) (end 149.578922 64.27) (width 0.2) (layer "B.Cu") (net 16))
  (arc (start 150.412867 64.27) (mid 150.608852 64.231016) (end 150.775 64.12) (width 0.2) (layer "B.Cu") (net 16))
  (segment (start 161.433638 77.725337) (end 161.357035 77.725337) (width 0.2) (layer "F.Cu") (net 17))
  (segment (start 161.663449 77.725337) (end 161.586845 77.725337) (width 0.2) (layer "F.Cu") (net 17))
  (segment (start 161.793354 77.678922) (end 162.433 77.678922) (width 0.2) (layer "F.Cu") (net 17))
  (segment (start 161.586845 77.725337) (end 161.510241 77.725337) (width 0.2) (layer "F.Cu") (net 17))
  (segment (start 161.510241 77.725337) (end 161.433638 77.725337) (width 0.2) (layer "F.Cu") (net 17))
  (segment (start 157.678388 80.393224) (end 157.59 80.393224) (width 0.2) (layer "F.Cu") (net 17))
  (segment (start 161.001961 77.725337) (end 160.915 77.725337) (width 0.2) (layer "F.Cu") (net 17))
  (segment (start 161.663449 77.725337) (end 161.701751 77.725337) (width 0.2) (layer "F.Cu") (net 17))
  (segment (start 160.095013 78.064986) (end 157.829275 80.330724) (width 0.2) (layer "F.Cu") (net 17))
  (segment (start 161.175884 77.725337) (end 161.001961 77.725337) (width 0.2) (layer "F.Cu") (net 17))
  (segment (start 161.175884 77.725337) (end 161.357035 77.725337) (width 0.2) (layer "F.Cu") (net 17))
  (via (at 157.59 80.393224) (size 0.45) (drill 0.1) (layers "F.Cu" "B.Cu") (net 17))
  (arc (start 161.793354 77.678922) (mid 161.76069 77.685419) (end 161.732999 77.703922) (width 0.2) (layer "F.Cu") (net 17))
  (arc (start 160.095013 78.064986) (mid 160.471226 77.813608) (end 160.915 77.725337) (width 0.2) (layer "F.Cu") (net 17))
  (arc (start 157.678388 80.393224) (mid 157.760047 80.37698) (end 157.829275 80.330724) (width 0.2) (layer "F.Cu") (net 17))
  (arc (start 161.732999 77.703922) (mid 161.718085 77.715609) (end 161.701751 77.725337) (width 0.2) (layer "F.Cu") (net 17))
  (segment (start 156.076132 81.04) (end 156.787659 81.04) (width 0.2) (layer "B.Cu") (net 17))
  (segment (start 155.714 80.89) (end 155.564 80.74) (width 0.2) (layer "B.Cu") (net 17))
  (segment (start 157.355 80.805) (end 157.5275 80.632499) (width 0.2) (layer "B.Cu") (net 17))
  (segment (start 157.59 80.481612) (end 157.59 80.393224) (width 0.2) (layer "B.Cu") (net 17))
  (arc (start 157.355 80.805) (mid 157.094701 80.978925) (end 156.787659 81.04) (width 0.2) (layer "B.Cu") (net 17))
  (arc (start 157.59 80.481612) (mid 157.573756 80.563271) (end 157.5275 80.632499) (width 0.2) (layer "B.Cu") (net 17))
  (arc (start 156.076132 81.04) (mid 155.880147 81.001016) (end 155.714 80.89) (width 0.2) (layer "B.Cu") (net 17))
  (segment (start 140.140234 82.86961) (end 140.140156 82.869532) (width 0.1) (layer "F.Cu") (net 18))
  (segment (start 150.444779 83.49) (end 143.57125 83.49) (width 0.2) (layer "F.Cu") (net 18))
  (segment (start 152.08 82.443722) (end 152.08 82.355334) (width 0.2) (layer "F.Cu") (net 18))
  (segment (start 139.515 82.955) (end 139.4 83.07) (width 0.1) (layer "F.Cu") (net 18))
  (segment (start 140.139844 82.86922) (end 140.125468 82.854844) (width 0.1) (layer "F.Cu") (net 18))
  (segment (start 152.0175 82.594609) (end 151.601054 83.011054) (width 0.2) (layer "F.Cu") (net 18))
  (segment (start 140.089631 82.84) (end 139.792634 82.84) (width 0.1) (layer "F.Cu") (net 18))
  (segment (start 140.14039 82.869766) (end 140.140468 82.869844) (width 0.1) (layer "F.Cu") (net 18))
  (segment (start 140.139844 82.86922) (end 140.140156 82.869532) (width 0.1) (layer "F.Cu") (net 18))
  (segment (start 140.140234 82.86961) (end 140.14039 82.869766) (width 0.1) (layer "F.Cu") (net 18))
  (segment (start 142.074437 82.87) (end 140.140844 82.87) (width 0.2) (layer "F.Cu") (net 18))
  (via (at 152.08 82.355334) (size 0.45) (drill 0.1) (layers "F.Cu" "B.Cu") (net 18))
  (arc (start 152.0175 82.594609) (mid 152.063756 82.525381) (end 152.08 82.443722) (width 0.2) (layer "F.Cu") (net 18))
  (arc (start 150.444779 83.49) (mid 151.07055 83.365525) (end 151.601054 83.011054) (width 0.2) (layer "F.Cu") (net 18))
  (arc (start 142.074437 82.87) (mid 142.479472 82.950566) (end 142.822844 83.18) (width 0.2) (layer "F.Cu") (net 18))
  (arc (start 142.822844 83.18) (mid 143.166215 83.409433) (end 143.57125 83.49) (width 0.2) (layer "F.Cu") (net 18))
  (arc (start 139.792634 82.84) (mid 139.642379 82.869888) (end 139.515 82.955) (width 0.1) (layer "F.Cu") (net 18))
  (arc (start 140.089631 82.84) (mid 140.109025 82.843857) (end 140.125468 82.854844) (width 0.1) (layer "F.Cu") (net 18))
  (arc (start 140.140844 82.87) (mid 140.14064 82.869959) (end 140.140468 82.869844) (width 0.2) (layer "F.Cu") (net 18))
  (segment (start 154.446 80.89) (end 154.596 80.74) (width 0.2) (layer "B.Cu") (net 18))
  (segment (start 153.934055 81.04) (end 154.083867 81.04) (width 0.2) (layer "B.Cu") (net 18))
  (segment (start 152.168388 82.355334) (end 152.08 82.355334) (width 0.2) (layer "B.Cu") (net 18))
  (segment (start 152.319275 82.292834) (end 153.316176 81.295933) (width 0.2) (layer "B.Cu") (net 18))
  (arc (start 154.083867 81.04) (mid 154.279852 81.001016) (end 154.446 80.89) (width 0.2) (layer "B.Cu") (net 18))
  (arc (start 153.934055 81.04) (mid 153.599661 81.106514) (end 153.316176 81.295933) (width 0.2) (layer "B.Cu") (net 18))
  (arc (start 152.168388 82.355334) (mid 152.250047 82.33909) (end 152.319275 82.292834) (width 0.2) (layer "B.Cu") (net 18))
  (segment (start 157.39 60.85) (end 157.39 60.35) (width 0.1) (layer "F.Cu") (net 19))
  (segment (start 156.89 60.35) (end 157.39 60.35) (width 0.1) (layer "F.Cu") (net 19))
  (segment (start 157.39 60.35) (end 157.89 60.35) (width 0.1) (layer "F.Cu") (net 19))
  (segment (start 157.414 60.35) (end 157.89 59.874) (width 0.1) (layer "F.Cu") (net 19))
  (segment (start 157.39 60.35) (end 157.414 60.35) (width 0.1) (layer "F.Cu") (net 19))
  (segment (start 157.89 60.35) (end 157.89 59.874) (width 0.1) (layer "F.Cu") (net 19))
  (via (at 157.89 59.874) (size 0.45) (drill 0.1) (layers "F.Cu" "B.Cu") (net 19))
  (segment (start 159.39 60.85) (end 159.39 61.35) (width 0.1) (layer "F.Cu") (net 20))
  (segment (start 159.39 60.35) (end 159.39 60.85) (width 0.1) (layer "F.Cu") (net 20))
  (segment (start 159.39 61.35) (end 159.39 61.85) (width 0.1) (layer "F.Cu") (net 20))
  (segment (start 158.89 63.85) (end 158.76 63.85) (width 0.1) (layer "F.Cu") (net 20))
  (segment (start 159.866 59.874) (end 159.89 59.874) (width 0.1) (layer "F.Cu") (net 20))
  (segment (start 159.39 60.35) (end 159.866 59.874) (width 0.1) (layer "F.Cu") (net 20))
  (via (at 158.76 63.85) (size 0.45) (drill 0.1) (layers "F.Cu" "B.Cu") (net 20))
  (via (at 159.89 59.874) (size 0.45) (drill 0.1) (layers "F.Cu" "B.Cu") (net 20))
  (segment (start 158.76 63.85) (end 159.39 63.22) (width 0.1) (layer "B.Cu") (net 20))
  (segment (start 159.39 63.22) (end 159.39 60.374) (width 0.1) (layer "B.Cu") (net 20))
  (segment (start 159.39 60.374) (end 159.89 59.874) (width 0.1) (layer "B.Cu") (net 20))
  (via (at 163.800001 74.425923) (size 0.45) (drill 0.1) (layers "F.Cu" "B.Cu") (net 21))
  (segment (start 163.800001 74.425923) (end 163.800001 74.319344) (width 0.2) (layer "B.Cu") (net 21))
  (segment (start 155.719 78.27) (end 155.569 78.42) (width 0.2) (layer "B.Cu") (net 21))
  (segment (start 162.25 73.81) (end 161.295515 73.81) (width 0.2) (layer "B.Cu") (net 21))
  (segment (start 159.481422 74.561422) (end 159.278007 74.764836) (width 0.2) (layer "B.Cu") (net 21))
  (segment (start 162.316654 73.81) (end 162.25 73.81) (width 0.2) (layer "B.Cu") (net 21))
  (segment (start 158.181991 77.410851) (end 158.039888 77.552955) (width 0.2) (layer "B.Cu") (net 21))
  (segment (start 162.716654 74.143346) (end 162.65 74.143346) (width 0.2) (layer "B.Cu") (net 21))
  (segment (start 163.724638 74.137403) (end 163.598618 74.011383) (width 0.2) (layer "B.Cu") (net 21))
  (segment (start 163.112436 73.81) (end 163.05 73.81) (width 0.2) (layer "B.Cu") (net 21))
  (segment (start 156.670922 78.12) (end 156.081132 78.12) (width 0.2) (layer "B.Cu") (net 21))
  (arc (start 159.278007 74.764836) (mid 158.872422 75.371837) (end 158.73 76.087844) (width 0.2) (layer "B.Cu") (net 21))
  (arc (start 156.081132 78.12) (mid 155.885147 78.158983) (end 155.719 78.27) (width 0.2) (layer "B.Cu") (net 21))
  (arc (start 162.65 74.143346) (mid 162.532144 74.094529) (end 162.483327 73.976673) (width 0.2) (layer "B.Cu") (net 21))
  (arc (start 162.883327 73.976673) (mid 162.83451 74.094529) (end 162.716654 74.143346) (width 0.2) (layer "B.Cu") (net 21))
  (arc (start 163.800001 74.319344) (mid 163.780414 74.220878) (end 163.724638 74.137403) (width 0.2) (layer "B.Cu") (net 21))
  (arc (start 163.598618 74.011383) (mid 163.375555 73.862337) (end 163.112436 73.81) (width 0.2) (layer "B.Cu") (net 21))
  (arc (start 161.295515 73.81) (mid 160.313734 74.005288) (end 159.481422 74.561422) (width 0.2) (layer "B.Cu") (net 21))
  (arc (start 158.73 76.087844) (mid 158.587577 76.80385) (end 158.181991 77.410851) (width 0.2) (layer "B.Cu") (net 21))
  (arc (start 163.05 73.81) (mid 162.932144 73.858817) (end 162.883327 73.976673) (width 0.2) (layer "B.Cu") (net 21))
  (arc (start 162.483327 73.976673) (mid 162.43451 73.858817) (end 162.316654 73.81) (width 0.2) (layer "B.Cu") (net 21))
  (arc (start 158.039888 77.552955) (mid 157.411801 77.972629) (end 156.670922 78.12) (width 0.2) (layer "B.Cu") (net 21))
  (segment (start 150.519619 80.819619) (end 150.431231 80.819619) (width 0.2) (layer "F.Cu") (net 22))
  (segment (start 147.730319 82.35) (end 140.161213 82.35) (width 0.2) (layer "F.Cu") (net 22))
  (segment (start 139.515 82.265) (end 139.4 82.15) (width 0.1) (layer "F.Cu") (net 22))
  (segment (start 150.280343 80.882118) (end 149.577652 81.584809) (width 0.2) (layer "F.Cu") (net 22))
  (segment (start 139.792634 82.38) (end 140.088786 82.38) (width 0.1) (layer "F.Cu") (net 22))
  (via (at 150.519619 80.819619) (size 0.45) (drill 0.1) (layers "F.Cu" "B.Cu") (net 22))
  (arc (start 139.515 82.265) (mid 139.642379 82.350112) (end 139.792634 82.38) (width 0.1) (layer "F.Cu") (net 22))
  (arc (start 147.730319 82.35) (mid 148.730088 82.151133) (end 149.577652 81.584809) (width 0.2) (layer "F.Cu") (net 22))
  (arc (start 140.125 82.365) (mid 140.108385 82.376101) (end 140.088786 82.38) (width 0.1) (layer "F.Cu") (net 22))
  (arc (start 150.280343 80.882118) (mid 150.349571 80.835861) (end 150.431231 80.819619) (width 0.2) (layer "F.Cu") (net 22))
  (arc (start 140.125 82.365) (mid 140.141614 82.353898) (end 140.161213 82.35) (width 0.2) (layer "F.Cu") (net 22))
  (segment (start 150.519619 80.819619) (end 150.519619 80.731231) (width 0.2) (layer "B.Cu") (net 22))
  (segment (start 153.671731 78.12) (end 154.088867 78.12) (width 0.2) (layer "B.Cu") (net 22))
  (segment (start 150.582118 80.580343) (end 152.597501 78.56496) (width 0.2) (layer "B.Cu") (net 22))
  (segment (start 154.451 78.27) (end 154.601 78.42) (width 0.2) (layer "B.Cu") (net 22))
  (arc (start 154.451 78.27) (mid 154.284852 78.158983) (end 154.088867 78.12) (width 0.2) (layer "B.Cu") (net 22))
  (arc (start 150.519619 80.731231) (mid 150.535861 80.649571) (end 150.582118 80.580343) (width 0.2) (layer "B.Cu") (net 22))
  (arc (start 152.597501 78.56496) (mid 153.090362 78.235641) (end 153.671731 78.12) (width 0.2) (layer "B.Cu") (net 22))
  (segment (start 154.463223 64.6) (end 153.742352 64.6) (width 0.1) (layer "F.Cu") (net 23))
  (segment (start 154.765 64.475) (end 154.89 64.35) (width 0.1) (layer "F.Cu") (net 23))
  (segment (start 151.11 64.845) (end 150.985 64.97) (width 0.2) (layer "F.Cu") (net 23))
  (segment (start 151.411776 64.72) (end 153.452647 64.72) (width 0.2) (layer "F.Cu") (net 23))
  (via (at 150.985 64.97) (size 0.45) (drill 0.1) (layers "F.Cu" "B.Cu") (net 23))
  (arc (start 151.11 64.845) (mid 151.248456 64.752486) (end 151.411776 64.72) (width 0.2) (layer "F.Cu") (net 23))
  (arc (start 153.742352 64.6) (mid 153.663958 64.615593) (end 153.5975 64.66) (width 0.1) (layer "F.Cu") (net 23))
  (arc (start 153.452647 64.72) (mid 153.53104 64.704406) (end 153.5975 64.66) (width 0.1) (layer "F.Cu") (net 23))
  (arc (start 154.463223 64.6) (mid 154.626543 64.567513) (end 154.765 64.475) (width 0.1) (layer "F.Cu") (net 23))
  (segment (start 144.090948 60.393792) (end 147.568887 63.871731) (width 0.2) (layer "B.Cu") (net 23))
  (segment (start 140.243192 58.8) (end 136.111132 58.8) (width 0.2) (layer "B.Cu") (net 23))
  (segment (start 150.775 64.82) (end 150.925 64.97) (width 0.2) (layer "B.Cu") (net 23))
  (segment (start 149.496078 64.67) (end 150.412867 64.67) (width 0.2) (layer "B.Cu") (net 23))
  (segment (start 135.749 58.95) (end 135.599 59.1) (width 0.2) (layer "B.Cu") (net 23))
  (arc (start 135.749 58.95) (mid 135.915147 58.838983) (end 136.111132 58.8) (width 0.2) (layer "B.Cu") (net 23))
  (arc (start 150.412867 64.67) (mid 150.608852 64.708983) (end 150.775 64.82) (width 0.2) (layer "B.Cu") (net 23))
  (arc (start 149.496078 64.67) (mid 148.453089 64.462536) (end 147.568887 63.871731) (width 0.2) (layer "B.Cu") (net 23))
  (arc (start 144.090948 60.393792) (mid 142.325582 59.214213) (end 140.243192 58.8) (width 0.2) (layer "B.Cu") (net 23))
  (segment (start 127.5 95.542132) (end 127.5 97.08) (width 0.2) (layer "B.Cu") (net 24))
  (segment (start 127.2 93.646132) (end 127.2 94.817867) (width 0.2) (layer "B.Cu") (net 24))
  (segment (start 127.35 93.284) (end 127.5 93.134) (width 0.2) (layer "B.Cu") (net 24))
  (arc (start 127.2 94.817867) (mid 127.238983 95.013852) (end 127.35 95.18) (width 0.2) (layer "B.Cu") (net 24))
  (arc (start 127.2 93.646132) (mid 127.238983 93.450147) (end 127.35 93.284) (width 0.2) (layer "B.Cu") (net 24))
  (arc (start 127.5 95.542132) (mid 127.461016 95.346147) (end 127.35 95.18) (width 0.2) (layer "B.Cu") (net 24))
  (segment (start 132.5 95.542132) (end 132.5 97.08) (width 0.2) (layer "B.Cu") (net 25))
  (segment (start 132.2 93.646132) (end 132.2 94.817867) (width 0.2) (layer "B.Cu") (net 25))
  (segment (start 132.35 93.284) (end 132.5 93.134) (width 0.2) (layer "B.Cu") (net 25))
  (arc (start 132.35 95.18) (mid 132.238983 95.013852) (end 132.2 94.817867) (width 0.2) (layer "B.Cu") (net 25))
  (arc (start 132.35 93.284) (mid 132.238983 93.450147) (end 132.2 93.646132) (width 0.2) (layer "B.Cu") (net 25))
  (arc (start 132.35 95.18) (mid 132.461016 95.346147) (end 132.5 95.542132) (width 0.2) (layer "B.Cu") (net 25))
  (segment (start 136.5 95.542132) (end 136.5 97.08) (width 0.2) (layer "B.Cu") (net 26))
  (segment (start 136.2 93.646132) (end 136.2 94.817867) (width 0.2) (layer "B.Cu") (net 26))
  (segment (start 136.35 93.284) (end 136.5 93.134) (width 0.2) (layer "B.Cu") (net 26))
  (arc (start 136.2 94.817867) (mid 136.238983 95.013852) (end 136.35 95.18) (width 0.2) (layer "B.Cu") (net 26))
  (arc (start 136.5 95.542132) (mid 136.461016 95.346147) (end 136.35 95.18) (width 0.2) (layer "B.Cu") (net 26))
  (arc (start 136.2 93.646132) (mid 136.238983 93.450147) (end 136.35 93.284) (width 0.2) (layer "B.Cu") (net 26))
  (segment (start 140.2 93.646132) (end 140.2 94.817867) (width 0.2) (layer "B.Cu") (net 27))
  (segment (start 140.5 95.542132) (end 140.5 97.08) (width 0.2) (layer "B.Cu") (net 27))
  (segment (start 140.35 93.284) (end 140.5 93.134) (width 0.2) (layer "B.Cu") (net 27))
  (arc (start 140.35 95.18) (mid 140.461016 95.346147) (end 140.5 95.542132) (width 0.2) (layer "B.Cu") (net 27))
  (arc (start 140.35 95.18) (mid 140.238983 95.013852) (end 140.2 94.817867) (width 0.2) (layer "B.Cu") (net 27))
  (arc (start 140.35 93.284) (mid 140.238983 93.450147) (end 140.2 93.646132) (width 0.2) (layer "B.Cu") (net 27))
  (segment (start 126.5 95.542132) (end 126.5 97.08) (width 0.2) (layer "B.Cu") (net 28))
  (segment (start 126.65 93.284) (end 126.5 93.134) (width 0.2) (layer "B.Cu") (net 28))
  (segment (start 126.8 94.817867) (end 126.8 93.646132) (width 0.2) (layer "B.Cu") (net 28))
  (arc (start 126.65 93.284) (mid 126.761016 93.450147) (end 126.8 93.646132) (width 0.2) (layer "B.Cu") (net 28))
  (arc (start 126.5 95.542132) (mid 126.538983 95.346147) (end 126.65 95.18) (width 0.2) (layer "B.Cu") (net 28))
  (arc (start 126.65 95.18) (mid 126.761016 95.013852) (end 126.8 94.817867) (width 0.2) (layer "B.Cu") (net 28))
  (segment (start 131.5 95.542132) (end 131.5 97.08) (width 0.2) (layer "B.Cu") (net 29))
  (segment (start 131.8 93.646132) (end 131.8 94.817867) (width 0.2) (layer "B.Cu") (net 29))
  (segment (start 131.65 93.284) (end 131.5 93.134) (width 0.2) (layer "B.Cu") (net 29))
  (arc (start 131.65 95.18) (mid 131.538983 95.346147) (end 131.5 95.542132) (width 0.2) (layer "B.Cu") (net 29))
  (arc (start 131.65 93.284) (mid 131.761016 93.450147) (end 131.8 93.646132) (width 0.2) (layer "B.Cu") (net 29))
  (arc (start 131.65 95.18) (mid 131.761016 95.013852) (end 131.8 94.817867) (width 0.2) (layer "B.Cu") (net 29))
  (segment (start 135.8 93.646132) (end 135.8 94.817867) (width 0.2) (layer "B.Cu") (net 30))
  (segment (start 135.65 93.284) (end 135.5 93.134) (width 0.2) (layer "B.Cu") (net 30))
  (segment (start 135.5 95.542132) (end 135.5 97.08) (width 0.2) (layer "B.Cu") (net 30))
  (arc (start 135.8 94.817867) (mid 135.761016 95.013852) (end 135.65 95.18) (width 0.2) (layer "B.Cu") (net 30))
  (arc (start 135.5 95.542132) (mid 135.538983 95.346147) (end 135.65 95.18) (width 0.2) (layer "B.Cu") (net 30))
  (arc (start 135.65 93.284) (mid 135.761016 93.450147) (end 135.8 93.646132) (width 0.2) (layer "B.Cu") (net 30))
  (segment (start 139.5 95.542132) (end 139.5 97.08) (width 0.2) (layer "B.Cu") (net 31))
  (segment (start 139.8 93.646132) (end 139.8 94.817867) (width 0.2) (layer "B.Cu") (net 31))
  (segment (start 139.65 93.284) (end 139.5 93.134) (width 0.2) (layer "B.Cu") (net 31))
  (arc (start 139.65 95.18) (mid 139.761016 95.013852) (end 139.8 94.817867) (width 0.2) (layer "B.Cu") (net 31))
  (arc (start 139.65 93.284) (mid 139.761016 93.450147) (end 139.8 93.646132) (width 0.2) (layer "B.Cu") (net 31))
  (arc (start 139.5 95.542132) (mid 139.538983 95.346147) (end 139.65 95.18) (width 0.2) (layer "B.Cu") (net 31))
  (segment (start 159.39 63.85) (end 160.21 63.85) (width 0.25) (layer "F.Cu") (net 32))
  (segment (start 158.89 64.35) (end 160.28 64.35) (width 0.25) (layer "F.Cu") (net 32))
  (segment (start 159.39 64.85) (end 160.31 64.85) (width 0.25) (layer "F.Cu") (net 32))
  (segment (start 156.555 67.11821) (end 156.555 70.510716) (width 0.2) (layer "F.Cu") (net 33))
  (segment (start 158.312392 76.129422) (end 161.673497 76.129422) (width 0.2) (layer "F.Cu") (net 33))
  (segment (start 161.793 76.178922) (end 162.433 76.178922) (width 0.2) (layer "F.Cu") (net 33))
  (segment (start 155.86 72.188595) (end 155.86 73.677029) (width 0.2) (layer "F.Cu") (net 33))
  (segment (start 156.655 65.25117) (end 156.655 66.876789) (width 0.1) (layer "F.Cu") (net 33))
  (segment (start 156.7725 64.9675) (end 156.89 64.85) (width 0.1) (layer "F.Cu") (net 33))
  (arc (start 156.2075 71.349656) (mid 156.464687 70.964747) (end 156.555 70.510716) (width 0.2) (layer "F.Cu") (net 33))
  (arc (start 156.555 67.11821) (mid 156.567994 67.052882) (end 156.605 66.9975) (width 0.1) (layer "F.Cu") (net 33))
  (arc (start 155.86 73.677029) (mid 156.046677 74.615519) (end 156.578289 75.411133) (width 0.2) (layer "F.Cu") (net 33))
  (arc (start 156.655 65.25117) (mid 156.685537 65.097648) (end 156.7725 64.9675) (width 0.1) (layer "F.Cu") (net 33))
  (arc (start 156.605 66.9975) (mid 156.642005 66.942117) (end 156.655 66.876789) (width 0.1) (layer "F.Cu") (net 33))
  (arc (start 161.733249 76.154172) (mid 161.705834 76.135854) (end 161.673497 76.129422) (width 0.2) (layer "F.Cu") (net 33))
  (arc (start 158.312392 76.129422) (mid 157.373902 75.942744) (end 156.578289 75.411133) (width 0.2) (layer "F.Cu") (net 33))
  (arc (start 161.733249 76.154172) (mid 161.760663 76.172489) (end 161.793 76.178922) (width 0.2) (layer "F.Cu") (net 33))
  (arc (start 156.2075 71.349656) (mid 155.950312 71.734564) (end 155.86 72.188595) (width 0.2) (layer "F.Cu") (net 33))
  (segment (start 161.673497 75.729422) (end 161.222348 75.729422) (width 0.2) (layer "F.Cu") (net 34))
  (segment (start 158.725578 75.147162) (end 158.725578 75.504422) (width 0.2) (layer "F.Cu") (net 34))
  (segment (start 161.793 75.679922) (end 162.433 75.679922) (width 0.2) (layer "F.Cu") (net 34))
  (segment (start 161.222348 75.729422) (end 160.320051 75.729422) (width 0.2) (layer "F.Cu") (net 34))
  (segment (start 156.26 72.354283) (end 156.26 73.677025) (width 0.2) (layer "F.Cu") (net 34))
  (segment (start 156.855 66.876789) (end 156.855 65.409748) (width 0.1) (layer "F.Cu") (net 34))
  (segment (start 159.175578 75.147162) (end 159.175578 75.504422) (width 0.2) (layer "F.Cu") (net 34))
  (segment (start 159.400578 75.729422) (end 160.320051 75.729422) (width 0.2) (layer "F.Cu") (net 34))
  (segment (start 158.312396 75.729422) (end 158.500578 75.729422) (width 0.2) (layer "F.Cu") (net 34))
  (segment (start 156.8725 65.3675) (end 156.89 65.35) (width 0.1) (layer "F.Cu") (net 34))
  (segment (start 156.955 70.676404) (end 156.955 67.11821) (width 0.2) (layer "F.Cu") (net 34))
  (arc (start 158.500578 75.729422) (mid 158.659677 75.663521) (end 158.725578 75.504422) (width 0.2) (layer "F.Cu") (net 34))
  (arc (start 156.905 66.9975) (mid 156.942005 67.052882) (end 156.955 67.11821) (width 0.1) (layer "F.Cu") (net 34))
  (arc (start 156.955 70.676404) (mid 156.864687 71.130435) (end 156.6075 71.515344) (width 0.2) (layer "F.Cu") (net 34))
  (arc (start 156.855 66.876789) (mid 156.867994 66.942117) (end 156.905 66.9975) (width 0.1) (layer "F.Cu") (net 34))
  (arc (start 161.793 75.679922) (mid 161.760663 75.686354) (end 161.733249 75.704672) (width 0.2) (layer "F.Cu") (net 34))
  (arc (start 156.26 73.677025) (mid 156.416229 74.462443) (end 156.861133 75.128289) (width 0.2) (layer "F.Cu") (net 34))
  (arc (start 158.312396 75.729422) (mid 157.526978 75.573192) (end 156.861133 75.128289) (width 0.2) (layer "F.Cu") (net 34))
  (arc (start 158.725578 75.147162) (mid 158.791479 74.988063) (end 158.950578 74.922162) (width 0.2) (layer "F.Cu") (net 34))
  (arc (start 156.855 65.409748) (mid 156.859548 65.386883) (end 156.8725 65.3675) (width 0.1) (layer "F.Cu") (net 34))
  (arc (start 158.950578 74.922162) (mid 159.109677 74.988063) (end 159.175578 75.147162) (width 0.2) (layer "F.Cu") (net 34))
  (arc (start 161.673497 75.729422) (mid 161.705834 75.722989) (end 161.733249 75.704672) (width 0.2) (layer "F.Cu") (net 34))
  (arc (start 156.6075 71.515344) (mid 156.350312 71.900252) (end 156.26 72.354283) (width 0.2) (layer "F.Cu") (net 34))
  (arc (start 159.400578 75.729422) (mid 159.241479 75.663521) (end 159.175578 75.504422) (width 0.2) (layer "F.Cu") (net 34))
  (segment (start 157.655 65.085) (end 157.89 64.85) (width 0.1) (layer "F.Cu") (net 35))
  (segment (start 158.05938 66.369711) (end 157.655 65.965331) (width 0.1) (layer "F.Cu") (net 35))
  (segment (start 157.655 65.965331) (end 157.655 65.085) (width 0.1) (layer "F.Cu") (net 35))
  (segment (start 158.349109 66.369711) (end 158.05938 66.369711) (width 0.1) (layer "F.Cu") (net 35))
  (via (at 162.433 75.179922) (size 0.45) (drill 0.1) (layers "F.Cu" "B.Cu") (net 35))
  (via (at 158.349109 66.369711) (size 0.45) (drill 0.1) (layers "F.Cu" "B.Cu") (net 35))
  (segment (start 160.419922 75.729922) (end 161.268 75.729922) (width 0.1) (layer "In3.Cu") (net 35))
  (segment (start 158.74382 65.975) (end 159.2 65.975) (width 0.1) (layer "In3.Cu") (net 35))
  (segment (start 161.818 75.179922) (end 162.433 75.179922) (width 0.1) (layer "In3.Cu") (net 35))
  (segment (start 161.268 75.729922) (end 161.818 75.179922) (width 0.1) (layer "In3.Cu") (net 35))
  (segment (start 159.4 66.175) (end 159.4 68.83) (width 0.1) (layer "In3.Cu") (net 35))
  (segment (start 158.349109 66.369711) (end 158.74382 65.975) (width 0.1) (layer "In3.Cu") (net 35))
  (segment (start 160.01 69.44) (end 160.01 75.32) (width 0.1) (layer "In3.Cu") (net 35))
  (segment (start 159.4 68.83) (end 160.01 69.44) (width 0.1) (layer "In3.Cu") (net 35))
  (segment (start 159.2 65.975) (end 159.4 66.175) (width 0.1) (layer "In3.Cu") (net 35))
  (segment (start 160.01 75.32) (end 160.419922 75.729922) (width 0.1) (layer "In3.Cu") (net 35))
  (segment (start 160.736745 74.129922) (end 161.672643 74.129922) (width 0.2) (layer "F.Cu") (net 36))
  (segment (start 158.023386 73.395001) (end 158.962489 73.395001) (width 0.2) (layer "F.Cu") (net 36))
  (segment (start 139.515 81.345) (end 139.4 81.23) (width 0.1) (layer "F.Cu") (net 36))
  (segment (start 157.81 73.52) (end 157.872499 73.4575) (width 0.2) (layer "F.Cu") (net 36))
  (segment (start 148.651583 79.490878) (end 153.400343 74.742118) (width 0.2) (layer "F.Cu") (net 36))
  (segment (start 153.639619 74.679619) (end 153.551231 74.679619) (width 0.2) (layer "F.Cu") (net 36))
  (segment (start 161.793354 74.179922) (end 162.433 74.179922) (width 0.2) (layer "F.Cu") (net 36))
  (segment (start 142.649082 81.43) (end 140.161213 81.43) (width 0.2) (layer "F.Cu") (net 36))
  (segment (start 139.792634 81.46) (end 140.088786 81.46) (width 0.1) (layer "F.Cu") (net 36))
  (segment (start 144.266605 80.76) (end 145.587653 80.76) (width 0.2) (layer "F.Cu") (net 36))
  (via (at 153.639619 74.679619) (size 0.45) (drill 0.1) (layers "F.Cu" "B.Cu") (net 36))
  (via (at 157.81 73.52) (size 0.45) (drill 0.1) (layers "F.Cu" "B.Cu") (net 36))
  (arc (start 148.651583 79.490878) (mid 147.24584 80.430165) (end 145.587653 80.76) (width 0.2) (layer "F.Cu") (net 36))
  (arc (start 160.736745 74.129922) (mid 160.256635 74.034421) (end 159.849617 73.762461) (width 0.2) (layer "F.Cu") (net 36))
  (arc (start 140.088786 81.46) (mid 140.108385 81.456101) (end 140.125 81.445) (width 0.1) (layer "F.Cu") (net 36))
  (arc (start 139.515 81.345) (mid 139.642379 81.430112) (end 139.792634 81.46) (width 0.1) (layer "F.Cu") (net 36))
  (arc (start 161.732999 74.154922) (mid 161.705307 74.136419) (end 161.672643 74.129922) (width 0.2) (layer "F.Cu") (net 36))
  (arc (start 159.849617 73.762461) (mid 159.442599 73.4905) (end 158.962489 73.395001) (width 0.2) (layer "F.Cu") (net 36))
  (arc (start 158.023386 73.395001) (mid 157.941726 73.411243) (end 157.872499 73.4575) (width 0.2) (layer "F.Cu") (net 36))
  (arc (start 142.649082 81.43) (mid 143.08678 81.342936) (end 143.457844 81.095) (width 0.2) (layer "F.Cu") (net 36))
  (arc (start 140.161213 81.43) (mid 140.141614 81.433898) (end 140.125 81.445) (width 0.2) (layer "F.Cu") (net 36))
  (arc (start 144.266605 80.76) (mid 143.828906 80.847063) (end 143.457844 81.095) (width 0.2) (layer "F.Cu") (net 36))
  (arc (start 161.732999 74.154922) (mid 161.76069 74.173424) (end 161.793354 74.179922) (width 0.2) (layer "F.Cu") (net 36))
  (arc (start 153.551231 74.679619) (mid 153.469571 74.695861) (end 153.400343 74.742118) (width 0.2) (layer "F.Cu") (net 36))
  (segment (start 157.7475 73.4575) (end 157.81 73.52) (width 0.2) (layer "B.Cu") (net 36))
  (segment (start 153.639619 74.679619) (end 153.639619 74.591231) (width 0.2) (layer "B.Cu") (net 36))
  (segment (start 153.702118 74.440343) (end 154.19354 73.948922) (width 0.2) (layer "B.Cu") (net 36))
  (segment (start 157.596613 73.395001) (end 155.530823 73.395001) (width 0.2) (layer "B.Cu") (net 36))
  (arc (start 155.530823 73.395001) (mid 154.80709 73.53896) (end 154.19354 73.948922) (width 0.2) (layer "B.Cu") (net 36))
  (arc (start 157.596613 73.395001) (mid 157.678272 73.411243) (end 157.7475 73.4575) (width 0.2) (layer "B.Cu") (net 36))
  (arc (start 153.702118 74.440343) (mid 153.655861 74.509571) (end 153.639619 74.591231) (width 0.2) (layer "B.Cu") (net 36))
  (segment (start 161.793354 73.679922) (end 162.433 73.679922) (width 0.2) (layer "F.Cu") (net 37))
  (segment (start 140.088786 81) (end 139.777426 81) (width 0.1) (layer "F.Cu") (net 37))
  (segment (start 159.128177 72.995001) (end 158.023388 72.995001) (width 0.2) (layer "F.Cu") (net 37))
  (segment (start 140.161213 81.03) (end 142.483394 81.03) (width 0.2) (layer "F.Cu") (net 37))
  (segment (start 157.81 72.870001) (end 157.8725 72.932501) (width 0.2) (layer "F.Cu") (net 37))
  (segment (start 160.902433 73.729922) (end 161.672643 73.729922) (width 0.2) (layer "F.Cu") (net 37))
  (segment (start 153.18 74.308388) (end 153.18 74.22) (width 0.2) (layer "F.Cu") (net 37))
  (segment (start 145.421966 80.36) (end 144.100917 80.36) (width 0.2) (layer "F.Cu") (net 37))
  (segment (start 139.777425 81.23) (end 139.86 81.23) (width 0.1) (layer "F.Cu") (net 37))
  (segment (start 153.1175 74.459275) (end 148.485898 79.090877) (width 0.2) (layer "F.Cu") (net 37))
  (segment (start 139.675 81.127573) (end 139.675 81.102426) (width 0.1) (layer "F.Cu") (net 37))
  (via (at 157.81 72.870001) (size 0.45) (drill 0.1) (layers "F.Cu" "B.Cu") (net 37))
  (via (at 153.18 74.22) (size 0.45) (drill 0.1) (layers "F.Cu" "B.Cu") (net 37))
  (arc (start 161.732999 73.704922) (mid 161.76069 73.686419) (end 161.793354 73.679922) (width 0.2) (layer "F.Cu") (net 37))
  (arc (start 160.902433 73.729922) (mid 160.422323 73.634421) (end 160.015305 73.362461) (width 0.2) (layer "F.Cu") (net 37))
  (arc (start 139.675 81.127573) (mid 139.682796 81.166771) (end 139.705 81.2) (width 0.1) (layer "F.Cu") (net 37))
  (arc (start 139.777425 81.23) (mid 139.738229 81.222203) (end 139.705 81.2) (width 0.1) (layer "F.Cu") (net 37))
  (arc (start 143.292156 80.695) (mid 143.663218 80.447063) (end 144.100917 80.36) (width 0.2) (layer "F.Cu") (net 37))
  (arc (start 140.161213 81.03) (mid 140.141614 81.026101) (end 140.125 81.015) (width 0.1) (layer "F.Cu") (net 37))
  (arc (start 153.18 74.308388) (mid 153.163756 74.390047) (end 153.1175 74.459275) (width 0.2) (layer "F.Cu") (net 37))
  (arc (start 145.421966 80.36) (mid 147.080154 80.030165) (end 148.485898 79.090877) (width 0.2) (layer "F.Cu") (net 37))
  (arc (start 158.023388 72.995001) (mid 157.941728 72.978757) (end 157.8725 72.932501) (width 0.2) (layer "F.Cu") (net 37))
  (arc (start 159.128177 72.995001) (mid 159.608287 73.0905) (end 160.015305 73.362461) (width 0.2) (layer "F.Cu") (net 37))
  (arc (start 139.705 81.03) (mid 139.682796 81.063229) (end 139.675 81.102426) (width 0.1) (layer "F.Cu") (net 37))
  (arc (start 142.483394 81.03) (mid 142.921092 80.942936) (end 143.292156 80.695) (width 0.2) (layer "F.Cu") (net 37))
  (arc (start 161.732999 73.704922) (mid 161.705307 73.723424) (end 161.672643 73.729922) (width 0.2) (layer "F.Cu") (net 37))
  (arc (start 140.088786 81) (mid 140.108385 81.003898) (end 140.125 81.015) (width 0.1) (layer "F.Cu") (net 37))
  (arc (start 139.777426 81) (mid 139.738229 81.007796) (end 139.705 81.03) (width 0.1) (layer "F.Cu") (net 37))
  (segment (start 157.81 72.870001) (end 157.7475 72.932501) (width 0.2) (layer "B.Cu") (net 37))
  (segment (start 155.44798 72.995001) (end 157.596611 72.995001) (width 0.2) (layer "B.Cu") (net 37))
  (segment (start 153.268388 74.22) (end 153.18 74.22) (width 0.2) (layer "B.Cu") (net 37))
  (segment (start 153.969275 73.6075) (end 153.419275 74.1575) (width 0.2) (layer "B.Cu") (net 37))
  (arc (start 153.969275 73.6075) (mid 154.64771 73.154184) (end 155.44798 72.995001) (width 0.2) (layer "B.Cu") (net 37))
  (arc (start 157.596611 72.995001) (mid 157.678271 72.978757) (end 157.7475 72.932501) (width 0.2) (layer "B.Cu") (net 37))
  (arc (start 153.268388 74.22) (mid 153.350047 74.203756) (end 153.419275 74.1575) (width 0.2) (layer "B.Cu") (net 37))
  (segment (start 157.394777 66.935465) (end 157.395143 66.935465) (width 0.2) (layer "F.Cu") (net 38))
  (segment (start 157.1525 65.255437) (end 157.1525 66.415547) (width 0.1) (layer "F.Cu") (net 38))
  (segment (start 157.27125 64.96875) (end 157.39 64.85) (width 0.1) (layer "F.Cu") (net 38))
  (segment (start 157.395769 66.935724) (end 158.250277 67.790232) (width 0.2) (layer "F.Cu") (net 38))
  (segment (start 162.43 68.770001) (end 162.367499 68.7075) (width 0.2) (layer "F.Cu") (net 38))
  (segment (start 157.248578 66.6475) (end 157.294534 66.693456) (width 0.1) (layer "F.Cu") (net 38))
  (segment (start 162.216609 68.645) (end 160.313868 68.645) (width 0.2) (layer "F.Cu") (net 38))
  (via (at 164.375 75.903922) (size 0.45) (drill 0.1) (layers "F.Cu" "B.Cu") (net 38))
  (via (at 162.43 68.770001) (size 0.45) (drill 0.1) (layers "F.Cu" "B.Cu") (net 38))
  (arc (start 160.313868 68.645) (mid 159.19706 68.422853) (end 158.250277 67.790232) (width 0.2) (layer "F.Cu") (net 38))
  (arc (start 157.344656 66.814461) (mid 157.331629 66.748973) (end 157.294534 66.693456) (width 0.1) (layer "F.Cu") (net 38))
  (arc (start 162.216609 68.645) (mid 162.29827 68.661243) (end 162.367499 68.7075) (width 0.2) (layer "F.Cu") (net 38))
  (arc (start 157.344656 66.814461) (mid 157.357682 66.879948) (end 157.394777 66.935465) (width 0.1) (layer "F.Cu") (net 38))
  (arc (start 157.395769 66.935724) (mid 157.395481 66.935532) (end 157.395143 66.935465) (width 0.2) (layer "F.Cu") (net 38))
  (arc (start 157.27125 64.96875) (mid 157.183362 65.100283) (end 157.1525 65.255437) (width 0.1) (layer "F.Cu") (net 38))
  (arc (start 157.248578 66.6475) (mid 157.177469 66.541079) (end 157.1525 66.415547) (width 0.1) (layer "F.Cu") (net 38))
  (segment (start 165.77 71.989168) (end 165.77 71.022844) (width 0.2) (layer "B.Cu") (net 38))
  (segment (start 166.356568 75.530585) (end 166.049409 75.837744) (width 0.2) (layer "B.Cu") (net 38))
  (segment (start 164.441945 69.114789) (end 165.359878 70.032722) (width 0.2) (layer "B.Cu") (net 38))
  (segment (start 162.4925 68.7075) (end 162.43 68.770001) (width 0.2) (layer "B.Cu") (net 38))
  (segment (start 166.31 73.292844) (end 166.424211 73.407055) (width 0.2) (layer "B.Cu") (net 38))
  (segment (start 162.64339 68.645) (end 163.307773 68.645) (width 0.2) (layer "B.Cu") (net 38))
  (segment (start 165.255338 75.725338) (end 165.367744 75.837744) (width 0.2) (layer "B.Cu") (net 38))
  (segment (start 166.401663 75.485491) (end 166.356568 75.530585) (width 0.2) (layer "B.Cu") (net 38))
  (segment (start 164.553583 75.725338) (end 164.375 75.903922) (width 0.2) (layer "B.Cu") (net 38))
  (segment (start 166.424211 75.462944) (end 166.401663 75.485491) (width 0.2) (layer "B.Cu") (net 38))
  (arc (start 166.049409 75.837744) (mid 165.893034 75.942231) (end 165.708577 75.978922) (width 0.2) (layer "B.Cu") (net 38))
  (arc (start 164.441945 69.114789) (mid 163.921582 68.767094) (end 163.307773 68.645) (width 0.2) (layer "B.Cu") (net 38))
  (arc (start 166.85 74.435) (mid 166.739341 74.991319) (end 166.424211 75.462944) (width 0.2) (layer "B.Cu") (net 38))
  (arc (start 165.367744 75.837744) (mid 165.524119 75.942231) (end 165.708577 75.978922) (width 0.2) (layer "B.Cu") (net 38))
  (arc (start 162.64339 68.645) (mid 162.561729 68.661243) (end 162.4925 68.7075) (width 0.2) (layer "B.Cu") (net 38))
  (arc (start 165.255338 75.725338) (mid 165.094354 75.617772) (end 164.904461 75.58) (width 0.2) (layer "B.Cu") (net 38))
  (arc (start 164.904461 75.58) (mid 164.714567 75.617772) (end 164.553583 75.725338) (width 0.2) (layer "B.Cu") (net 38))
  (arc (start 166.85 74.435) (mid 166.739341 73.87868) (end 166.424211 73.407055) (width 0.2) (layer "B.Cu") (net 38))
  (arc (start 165.77 71.989168) (mid 165.910341 72.694712) (end 166.31 73.292844) (width 0.2) (layer "B.Cu") (net 38))
  (arc (start 165.359878 70.032722) (mid 165.663412 70.486993) (end 165.77 71.022844) (width 0.2) (layer "B.Cu") (net 38))
  (segment (start 160.396886 68.245) (end 162.216611 68.245) (width 0.2) (layer "F.Cu") (net 39))
  (segment (start 157.419461 66.535539) (end 157.436543 66.552621) (width 0.1) (layer "F.Cu") (net 39))
  (segment (start 157.3525 66.37388) (end 157.3525 65.414016) (width 0.1) (layer "F.Cu") (net 39))
  (segment (start 157.37125 65.36875) (end 157.39 65.35) (width 0.1) (layer "F.Cu") (net 39))
  (segment (start 157.677378 66.652378) (end 157.677744 66.652378) (width 0.2) (layer "F.Cu") (net 39))
  (segment (start 158.474422 67.448689) (end 157.67837 66.652637) (width 0.2) (layer "F.Cu") (net 39))
  (segment (start 162.43 68.12) (end 162.3675 68.1825) (width 0.2) (layer "F.Cu") (net 39))
  (via (at 162.43 68.12) (size 0.45) (drill 0.1) (layers "F.Cu" "B.Cu") (net 39))
  (via (at 164.375 76.453922) (size 0.45) (drill 0.1) (layers "F.Cu" "B.Cu") (net 39))
  (arc (start 157.556961 66.6025) (mid 157.491791 66.589536) (end 157.436543 66.552621) (width 0.1) (layer "F.Cu") (net 39))
  (arc (start 162.216611 68.245) (mid 162.298271 68.228756) (end 162.3675 68.1825) (width 0.2) (layer "F.Cu") (net 39))
  (arc (start 157.677744 66.652378) (mid 157.678082 66.652445) (end 157.67837 66.652637) (width 0.2) (layer "F.Cu") (net 39))
  (arc (start 160.396886 68.245) (mid 159.356456 68.038045) (end 158.474422 67.448689) (width 0.2) (layer "F.Cu") (net 39))
  (arc (start 157.419461 66.535539) (mid 157.369902 66.461369) (end 157.3525 66.37388) (width 0.1) (layer "F.Cu") (net 39))
  (arc (start 157.556961 66.6025) (mid 157.622139 66.61545) (end 157.677378 66.652378) (width 0.1) (layer "F.Cu") (net 39))
  (arc (start 157.3525 65.414016) (mid 157.357372 65.389518) (end 157.37125 65.36875) (width 0.1) (layer "F.Cu") (net 39))
  (segment (start 164.503033 76.378922) (end 165.667939 76.378922) (width 0.2) (layer "B.Cu") (net 39))
  (segment (start 164.4125 76.416422) (end 164.375 76.453922) (width 0.2) (layer "B.Cu") (net 39))
  (segment (start 163.390616 68.245) (end 162.643388 68.245) (width 0.2) (layer "B.Cu") (net 39))
  (segment (start 164.4125 76.416422) (end 164.375 76.453922) (width 0.2) (layer "B.Cu") (net 39))
  (segment (start 167.25 74.435) (end 167.25 74.430831) (width 0.2) (layer "B.Cu") (net 39))
  (segment (start 166.677558 75.775284) (end 166.618571 75.834271) (width 0.2) (layer "B.Cu") (net 39))
  (segment (start 166.17 71.050575) (end 166.17 71.437413) (width 0.2) (layer "B.Cu") (net 39))
  (segment (start 166.17 70.857156) (end 166.17 71.050575) (width 0.2) (layer "B.Cu") (net 39))
  (segment (start 166.618571 75.834271) (end 166.360993 76.09185) (width 0.2) (layer "B.Cu") (net 39))
  (segment (start 166.17 71.82348) (end 166.17 71.437413) (width 0.2) (layer "B.Cu") (net 39))
  (segment (start 166.677558 75.775284) (end 166.707051 75.745791) (width 0.2) (layer "B.Cu") (net 39))
  (segment (start 164.666213 68.773369) (end 165.759878 69.867034) (width 0.2) (layer "B.Cu") (net 39))
  (segment (start 162.4925 68.1825) (end 162.43 68.12) (width 0.2) (layer "B.Cu") (net 39))
  (arc (start 166.707051 75.745791) (mid 167.108892 75.144395) (end 167.25 74.435) (width 0.2) (layer "B.Cu") (net 39))
  (arc (start 166.17 71.82348) (mid 166.310341 72.529024) (end 166.71 73.127156) (width 0.2) (layer "B.Cu") (net 39))
  (arc (start 164.4125 76.416422) (mid 164.454036 76.388667) (end 164.503033 76.378922) (width 0.2) (layer "B.Cu") (net 39))
  (arc (start 162.4925 68.1825) (mid 162.561728 68.228756) (end 162.643388 68.245) (width 0.2) (layer "B.Cu") (net 39))
  (arc (start 166.71 73.127156) (mid 167.109658 73.725287) (end 167.25 74.430831) (width 0.2) (layer "B.Cu") (net 39))
  (arc (start 166.17 70.857156) (mid 166.063412 70.321305) (end 165.759878 69.867034) (width 0.2) (layer "B.Cu") (net 39))
  (arc (start 166.360993 76.09185) (mid 166.043017 76.304314) (end 165.667939 76.378922) (width 0.2) (layer "B.Cu") (net 39))
  (arc (start 164.666213 68.773369) (mid 164.080964 68.382318) (end 163.390616 68.245) (width 0.2) (layer "B.Cu") (net 39))
  (arc (start 164.503033 76.378922) (mid 164.454036 76.388667) (end 164.4125 76.416422) (width 0.2) (layer "B.Cu") (net 39))
  (segment (start 158.07 65.85) (end 157.89 65.67) (width 0.1) (layer "F.Cu") (net 40))
  (segment (start 157.89 65.67) (end 157.89 65.35) (width 0.1) (layer "F.Cu") (net 40))
  (via (at 164.035 76.928922) (size 0.45) (drill 0.1) (layers "F.Cu" "B.Cu") (net 40))
  (via (at 158.07 65.85) (size 0.45) (drill 0.1) (layers "F.Cu" "B.Cu") (net 40))
  (segment (start 165.2 76.378922) (end 165.775 76.378922) (width 0.1) (layer "In3.Cu") (net 40))
  (segment (start 166.325 72.215) (end 164.004461 69.894461) (width 0.1) (layer "In3.Cu") (net 40))
  (segment (start 164.65 76.928922) (end 165.2 76.378922) (width 0.1) (layer "In3.Cu") (net 40))
  (segment (start 164.004461 69.894461) (end 161.924461 69.894461) (width 0.1) (layer "In3.Cu") (net 40))
  (segment (start 165.775 76.378922) (end 166.325 75.828922) (width 0.1) (layer "In3.Cu") (net 40))
  (segment (start 159.965 65.675) (end 158.245 65.675) (width 0.1) (layer "In3.Cu") (net 40))
  (segment (start 158.245 65.675) (end 158.07 65.85) (width 0.1) (layer "In3.Cu") (net 40))
  (segment (start 164.035 76.928922) (end 164.65 76.928922) (width 0.1) (layer "In3.Cu") (net 40))
  (segment (start 160.45 66.16) (end 159.965 65.675) (width 0.1) (layer "In3.Cu") (net 40))
  (segment (start 161.924461 69.894461) (end 160.45 68.42) (width 0.1) (layer "In3.Cu") (net 40))
  (segment (start 166.325 75.828922) (end 166.325 72.215) (width 0.1) (layer "In3.Cu") (net 40))
  (segment (start 160.45 68.42) (end 160.45 66.16) (width 0.1) (layer "In3.Cu") (net 40))
  (segment (start 152.06 84.753991) (end 152.06 84.77) (width 0.2) (layer "F.Cu") (net 41))
  (segment (start 139.777426 83.76) (end 140.088786 83.76) (width 0.1) (layer "F.Cu") (net 41))
  (segment (start 151.81 85.02) (end 150.172646 85.02) (width 0.2) (layer "F.Cu") (net 41))
  (segment (start 140.691422 83.79) (end 140.161213 83.79) (width 0.2) (layer "F.Cu") (net 41))
  (segment (start 150.172646 85.02) (end 143.342585 85.02) (width 0.2) (layer "F.Cu") (net 41))
  (segment (start 141.857844 84.405) (end 141.632758 84.179914) (width 0.2) (layer "F.Cu") (net 41))
  (segment (start 154.140381 84.330381) (end 154.140381 84.418769) (width 0.2) (layer "F.Cu") (net 41))
  (segment (start 154.077881 84.569656) (end 153.883959 84.763578) (width 0.2) (layer "F.Cu") (net 41))
  (segment (start 153.264903 85.02) (end 152.81 85.02) (width 0.2) (layer "F.Cu") (net 41))
  (segment (start 139.675 83.862426) (end 139.675 83.887573) (width 0.1) (layer "F.Cu") (net 41))
  (segment (start 152.56 84.77) (end 152.56 84.753991) (width 0.2) (layer "F.Cu") (net 41))
  (segment (start 139.777425 83.99) (end 139.86 83.99) (width 0.1) (layer "F.Cu") (net 41))
  (via (at 154.140381 84.330381) (size 0.45) (drill 0.1) (layers "F.Cu" "B.Cu") (net 41))
  (via (at 163.79 77.923922) (size 0.45) (drill 0.1) (layers "F.Cu" "B.Cu") (net 41))
  (arc (start 140.125 83.775) (mid 140.141614 83.786101) (end 140.161213 83.79) (width 0.1) (layer "F.Cu") (net 41))
  (arc (start 139.705 83.79) (mid 139.682796 83.823229) (end 139.675 83.862426) (width 0.1) (layer "F.Cu") (net 41))
  (arc (start 152.81 85.02) (mid 152.633223 84.946777) (end 152.56 84.77) (width 0.2) (layer "F.Cu") (net 41))
  (arc (start 143.342585 85.02) (mid 142.539049 84.860166) (end 141.857844 84.405) (width 0.2) (layer "F.Cu") (net 41))
  (arc (start 139.705 83.79) (mid 139.738229 83.767796) (end 139.777426 83.76) (width 0.1) (layer "F.Cu") (net 41))
  (arc (start 152.31 84.503991) (mid 152.133223 84.577214) (end 152.06 84.753991) (width 0.2) (layer "F.Cu") (net 41))
  (arc (start 154.140381 84.418769) (mid 154.124137 84.500428) (end 154.077881 84.569656) (width 0.2) (layer "F.Cu") (net 41))
  (arc (start 152.06 84.77) (mid 151.986777 84.946777) (end 151.81 85.02) (width 0.2) (layer "F.Cu") (net 41))
  (arc (start 139.705 83.96) (mid 139.682796 83.926771) (end 139.675 83.887573) (width 0.1) (layer "F.Cu") (net 41))
  (arc (start 139.705 83.96) (mid 139.738229 83.982203) (end 139.777425 83.99) (width 0.1) (layer "F.Cu") (net 41))
  (arc (start 141.632758 84.179914) (mid 141.200869 83.891335) (end 140.691422 83.79) (width 0.2) (layer "F.Cu") (net 41))
  (arc (start 153.883959 84.763578) (mid 153.599933 84.953358) (end 153.264903 85.02) (width 0.2) (layer "F.Cu") (net 41))
  (arc (start 140.125 83.775) (mid 140.108385 83.763898) (end 140.088786 83.76) (width 0.1) (layer "F.Cu") (net 41))
  (arc (start 152.56 84.753991) (mid 152.486777 84.577214) (end 152.31 84.503991) (width 0.2) (layer "F.Cu") (net 41))
  (segment (start 154.379656 84.267881) (end 154.812347 83.83519) (width 0.2) (layer "B.Cu") (net 41))
  (segment (start 163.79 77.923922) (end 163.79 78.0325) (width 0.2) (layer "B.Cu") (net 41))
  (segment (start 154.140381 84.330381) (end 154.228769 84.330381) (width 0.2) (layer "B.Cu") (net 41))
  (segment (start 156.007843 83.34) (end 157.310342 83.34) (width 0.2) (layer "B.Cu") (net 41))
  (segment (start 161.407398 78.49) (end 163.194354 78.49) (width 0.2) (layer "B.Cu") (net 41))
  (segment (start 159.91 79.987398) (end 159.91 80.740342) (width 0.2) (layer "B.Cu") (net 41))
  (segment (start 163.615539 78.315539) (end 163.713223 78.217855) (width 0.2) (layer "B.Cu") (net 41))
  (arc (start 159.148578 82.578578) (mid 159.712112 81.735188) (end 159.91 80.740342) (width 0.2) (layer "B.Cu") (net 41))
  (arc (start 159.148578 82.578578) (mid 158.305188 83.142112) (end 157.310342 83.34) (width 0.2) (layer "B.Cu") (net 41))
  (arc (start 163.615539 78.315539) (mid 163.422297 78.444659) (end 163.194354 78.49) (width 0.2) (layer "B.Cu") (net 41))
  (arc (start 163.713223 78.217855) (mid 163.770046 78.132813) (end 163.79 78.0325) (width 0.2) (layer "B.Cu") (net 41))
  (arc (start 154.379656 84.267881) (mid 154.310428 84.314137) (end 154.228769 84.330381) (width 0.2) (layer "B.Cu") (net 41))
  (arc (start 160.348578 78.928578) (mid 160.834368 78.603982) (end 161.407398 78.49) (width 0.2) (layer "B.Cu") (net 41))
  (arc (start 159.91 79.987398) (mid 160.023982 79.414368) (end 160.348578 78.928578) (width 0.2) (layer "B.Cu") (net 41))
  (arc (start 156.007843 83.34) (mid 155.360845 83.468695) (end 154.812347 83.83519) (width 0.2) (layer "B.Cu") (net 41))
  (segment (start 164.0375 78.426422) (end 164.035 78.428922) (width 0.2) (layer "F.Cu") (net 42))
  (segment (start 154.108224 85.105) (end 154.360724 84.852499) (width 0.2) (layer "F.Cu") (net 42))
  (segment (start 139.515 84.105) (end 139.4 83.99) (width 0.1) (layer "F.Cu") (net 42))
  (segment (start 139.792634 84.22) (end 140.08941 84.22) (width 0.1) (layer "F.Cu") (net 42))
  (segment (start 140.60889 84.19) (end 140.161837 84.19) (width 0.2) (layer "F.Cu") (net 42))
  (segment (start 141.40827 84.521114) (end 141.692156 84.805) (width 0.2) (layer "F.Cu") (net 42))
  (segment (start 153.347746 85.42) (end 143.176897 85.42) (width 0.2) (layer "F.Cu") (net 42))
  (segment (start 164.043535 78.423922) (end 164.27 78.423922) (width 0.2) (layer "F.Cu") (net 42))
  (segment (start 154.511612 84.79) (end 154.6 84.79) (width 0.2) (layer "F.Cu") (net 42))
  (via (at 154.6 84.79) (size 0.45) (drill 0.1) (layers "F.Cu" "B.Cu") (net 42))
  (via (at 164.29 78.423922) (size 0.45) (drill 0.1) (layers "F.Cu" "B.Cu") (net 42))
  (arc (start 153.347746 85.42) (mid 153.759313 85.338134) (end 154.108224 85.105) (width 0.2) (layer "F.Cu") (net 42))
  (arc (start 164.0375 78.426422) (mid 164.040268 78.424571) (end 164.043535 78.423922) (width 0.2) (layer "F.Cu") (net 42))
  (arc (start 154.511612 84.79) (mid 154.429952 84.806242) (end 154.360724 84.852499) (width 0.2) (layer "F.Cu") (net 42))
  (arc (start 140.60889 84.19) (mid 141.041511 84.276053) (end 141.40827 84.521114) (width 0.2) (layer "F.Cu") (net 42))
  (arc (start 140.161837 84.19) (mid 140.142238 84.193898) (end 140.125624 84.205) (width 0.2) (layer "F.Cu") (net 42))
  (arc (start 143.176897 85.42) (mid 142.373361 85.260166) (end 141.692156 84.805) (width 0.2) (layer "F.Cu") (net 42))
  (arc (start 139.515 84.105) (mid 139.642379 84.190112) (end 139.792634 84.22) (width 0.1) (layer "F.Cu") (net 42))
  (arc (start 140.125624 84.205) (mid 140.109009 84.216101) (end 140.08941 84.22) (width 0.1) (layer "F.Cu") (net 42))
  (segment (start 163.839803 78.65696) (end 163.996066 78.500698) (width 0.2) (layer "B.Cu") (net 42))
  (segment (start 154.662499 84.550724) (end 155.036611 84.176611) (width 0.2) (layer "B.Cu") (net 42))
  (segment (start 159.443794 82.849049) (end 159.431421 82.861421) (width 0.2) (layer "B.Cu") (net 42))
  (segment (start 157.310347 83.74) (end 156.090686 83.74) (width 0.2) (layer "B.Cu") (net 42))
  (segment (start 154.6 84.701612) (end 154.6 84.79) (width 0.2) (layer "B.Cu") (net 42))
  (segment (start 164.29 78.423922) (end 164.181421 78.423922) (width 0.2) (layer "B.Cu") (net 42))
  (segment (start 160.31 79.987403) (end 160.31 80.757844) (width 0.2) (layer "B.Cu") (net 42))
  (segment (start 161.407403 78.89) (end 163.277198 78.89) (width 0.2) (layer "B.Cu") (net 42))
  (arc (start 159.431421 82.861421) (mid 158.458264 83.511664) (end 157.310347 83.74) (width 0.2) (layer "B.Cu") (net 42))
  (arc (start 164.181421 78.423922) (mid 164.081107 78.443875) (end 163.996066 78.500698) (width 0.2) (layer "B.Cu") (net 42))
  (arc (start 160.31 79.987403) (mid 160.393534 79.567445) (end 160.631422 79.211422) (width 0.2) (layer "B.Cu") (net 42))
  (arc (start 155.036611 84.176611) (mid 155.520225 83.853471) (end 156.090686 83.74) (width 0.2) (layer "B.Cu") (net 42))
  (arc (start 154.662499 84.550724) (mid 154.616242 84.619952) (end 154.6 84.701612) (width 0.2) (layer "B.Cu") (net 42))
  (arc (start 163.277198 78.89) (mid 163.581677 78.829434) (end 163.839803 78.65696) (width 0.2) (layer "B.Cu") (net 42))
  (arc (start 161.407403 78.89) (mid 160.987445 78.973534) (end 160.631422 79.211422) (width 0.2) (layer "B.Cu") (net 42))
  (arc (start 159.443794 82.849049) (mid 160.08488 81.889596) (end 160.31 80.757844) (width 0.2) (layer "B.Cu") (net 42))
  (segment (start 121.5 93.83) (end 121.5 97.075046) (width 0.1) (layer "F.Cu") (net 43))
  (via (at 140.3 67.305) (size 0.45) (drill 0.1) (layers "F.Cu" "B.Cu") (net 43))
  (via (at 122.37 82.48) (size 0.45) (drill 0.1) (layers "F.Cu" "B.Cu") (net 43))
  (via (at 135.45 75.725) (size 0.45) (drill 0.1) (layers "F.Cu" "B.Cu") (net 43))
  (via (at 121.5 93.83) (size 0.45) (drill 0.1) (layers "F.Cu" "B.Cu") (net 43))
  (via (at 129.96 73.38) (size 0.45) (drill 0.1) (layers "F.Cu" "B.Cu") (net 43))
  (segment (start 137.19 72.63) (end 138.21 72.63) (width 0.1) (layer "In3.Cu") (net 43))
  (segment (start 125.29 78.05) (end 125.29 80.35) (width 0.1) (layer "In3.Cu") (net 43))
  (segment (start 140.3 67.3125) (end 140.3 67.305) (width 0.1) (layer "In3.Cu") (net 43))
  (segment (start 138.21 72.63) (end 139.18 71.66) (width 0.1) (layer "In3.Cu") (net 43))
  (segment (start 125.29 80.35) (end 123.16 82.48) (width 0.1) (layer "In3.Cu") (net 43))
  (segment (start 129.96 73.38) (end 125.29 78.05) (width 0.1) (layer "In3.Cu") (net 43))
  (segment (start 123.16 82.48) (end 122.37 82.48) (width 0.1) (layer "In3.Cu") (net 43))
  (segment (start 135.45 75.725) (end 135.45 74.37) (width 0.1) (layer "In3.Cu") (net 43))
  (segment (start 139.18 71.66) (end 139.18 68.4325) (width 0.1) (layer "In3.Cu") (net 43))
  (segment (start 139.18 68.4325) (end 140.3 67.3125) (width 0.1) (layer "In3.Cu") (net 43))
  (segment (start 135.45 74.37) (end 137.19 72.63) (width 0.1) (layer "In3.Cu") (net 43))
  (segment (start 121.5 93.83) (end 122.61 92.72) (width 0.1) (layer "B.Cu") (net 43))
  (segment (start 134.68 73.38) (end 135.45 74.15) (width 0.1) (layer "B.Cu") (net 43))
  (segment (start 122.61 92.72) (end 122.61 82.72) (width 0.1) (layer "B.Cu") (net 43))
  (segment (start 122.61 82.72) (end 122.37 82.48) (width 0.1) (layer "B.Cu") (net 43))
  (segment (start 129.96 73.38) (end 134.68 73.38) (width 0.1) (layer "B.Cu") (net 43))
  (segment (start 135.45 74.15) (end 135.45 75.725) (width 0.1) (layer "B.Cu") (net 43))
  (segment (start 123.319499 90.102343) (end 124.936551 91.719395) (width 0.2) (layer "F.Cu") (net 44))
  (segment (start 122.025 85.411612) (end 122.025 84.6) (width 0.2) (layer "F.Cu") (net 44))
  (segment (start 125.5 95.537178) (end 125.5 97.075046) (width 0.2) (layer "F.Cu") (net 44))
  (segment (start 125.8 93.803945) (end 125.8 94.812913) (width 0.2) (layer "F.Cu") (net 44))
  (segment (start 122.15 85.713389) (end 122.15 87.278922) (width 0.2) (layer "F.Cu") (net 44))
  (arc (start 122.0875 85.562501) (mid 122.041243 85.493272) (end 122.025 85.411612) (width 0.2) (layer "F.Cu") (net 44))
  (arc (start 122.0875 85.562501) (mid 122.133756 85.631729) (end 122.15 85.713389) (width 0.2) (layer "F.Cu") (net 44))
  (arc (start 125.65 95.175046) (mid 125.761016 95.008898) (end 125.8 94.812913) (width 0.2) (layer "F.Cu") (net 44))
  (arc (start 124.936551 91.719395) (mid 125.575596 92.675794) (end 125.8 93.803945) (width 0.2) (layer "F.Cu") (net 44))
  (arc (start 125.5 95.537178) (mid 125.538983 95.341193) (end 125.65 95.175046) (width 0.2) (layer "F.Cu") (net 44))
  (arc (start 123.319499 90.102343) (mid 122.453942 88.806946) (end 122.15 87.278922) (width 0.2) (layer "F.Cu") (net 44))
  (segment (start 122.55 87.196078) (end 122.55 85.713389) (width 0.2) (layer "F.Cu") (net 45))
  (segment (start 122.675 85.411612) (end 122.675 84.6) (width 0.2) (layer "F.Cu") (net 45))
  (segment (start 126.5 95.537178) (end 126.5 97.075046) (width 0.2) (layer "F.Cu") (net 45))
  (segment (start 125.277971 91.495127) (end 123.660919 89.878075) (width 0.2) (layer "F.Cu") (net 45))
  (segment (start 126.2 94.812913) (end 126.2 93.721101) (width 0.2) (layer "F.Cu") (net 45))
  (arc (start 122.675 85.411612) (mid 122.658756 85.493272) (end 122.6125 85.562501) (width 0.2) (layer "F.Cu") (net 45))
  (arc (start 122.6125 85.562501) (mid 122.566243 85.631729) (end 122.55 85.713389) (width 0.2) (layer "F.Cu") (net 45))
  (arc (start 125.277971 91.495127) (mid 125.960372 92.516412) (end 126.2 93.721101) (width 0.2) (layer "F.Cu") (net 45))
  (arc (start 126.5 95.537178) (mid 126.461016 95.341193) (end 126.35 95.175046) (width 0.2) (layer "F.Cu") (net 45))
  (arc (start 126.2 94.812913) (mid 126.238983 95.008898) (end 126.35 95.175046) (width 0.2) (layer "F.Cu") (net 45))
  (arc (start 122.55 87.196078) (mid 122.838718 88.647564) (end 123.660919 89.878075) (width 0.2) (layer "F.Cu") (net 45))
  (segment (start 131.12 84.827426) (end 131.12 84.91) (width 0.1) (layer "F.Cu") (net 46))
  (segment (start 130.92 85.331317) (end 130.92 85.232426) (width 0.2) (layer "F.Cu") (net 46))
  (segment (start 130.992426 84.725) (end 131.017573 84.725) (width 0.1) (layer "F.Cu") (net 46))
  (segment (start 130.89 84.827426) (end 130.89 85.159999) (width 0.1) (layer "F.Cu") (net 46))
  (segment (start 129.86 86.957156) (end 130.814939 86.002216) (width 0.2) (layer "F.Cu") (net 46))
  (segment (start 130.92 85.331317) (end 130.92 85.571526) (width 0.2) (layer "F.Cu") (net 46))
  (segment (start 128.8 89.516222) (end 128.8 94.812913) (width 0.2) (layer "F.Cu") (net 46))
  (segment (start 130.92 85.748578) (end 130.92 85.571526) (width 0.2) (layer "F.Cu") (net 46))
  (segment (start 128.5 95.537178) (end 128.5 97.075046) (width 0.2) (layer "F.Cu") (net 46))
  (arc (start 129.86 86.957156) (mid 129.075485 88.131265) (end 128.8 89.516222) (width 0.2) (layer "F.Cu") (net 46))
  (arc (start 130.905 85.196213) (mid 130.916101 85.212827) (end 130.92 85.232426) (width 0.1) (layer "F.Cu") (net 46))
  (arc (start 131.09 84.755) (mid 131.112203 84.788229) (end 131.12 84.827426) (width 0.1) (layer "F.Cu") (net 46))
  (arc (start 130.92 84.755) (mid 130.897796 84.788229) (end 130.89 84.827426) (width 0.1) (layer "F.Cu") (net 46))
  (arc (start 130.992426 84.725) (mid 130.953229 84.732796) (end 130.92 84.755) (width 0.1) (layer "F.Cu") (net 46))
  (arc (start 130.92 85.748578) (mid 130.892695 85.885846) (end 130.814939 86.002216) (width 0.2) (layer "F.Cu") (net 46))
  (arc (start 130.89 85.159999) (mid 130.893898 85.179598) (end 130.905 85.196213) (width 0.1) (layer "F.Cu") (net 46))
  (arc (start 128.5 95.537178) (mid 128.538983 95.341193) (end 128.65 95.175046) (width 0.2) (layer "F.Cu") (net 46))
  (arc (start 128.65 95.175046) (mid 128.761016 95.008898) (end 128.8 94.812913) (width 0.2) (layer "F.Cu") (net 46))
  (arc (start 131.09 84.755) (mid 131.05677 84.732796) (end 131.017573 84.725) (width 0.1) (layer "F.Cu") (net 46))
  (segment (start 131.32 85.791789) (end 131.32 85.486893) (width 0.2) (layer "F.Cu") (net 47))
  (segment (start 131.32 85.303106) (end 131.32 85.486893) (width 0.2) (layer "F.Cu") (net 47))
  (segment (start 131.35 85.159999) (end 131.35 84.842634) (width 0.1) (layer "F.Cu") (net 47))
  (segment (start 131.32 85.818211) (end 131.32 85.831422) (width 0.2) (layer "F.Cu") (net 47))
  (segment (start 129.2 94.812913) (end 129.2 89.68191) (width 0.2) (layer "F.Cu") (net 47))
  (segment (start 131.235 84.565) (end 131.12 84.45) (width 0.1) (layer "F.Cu") (net 47))
  (segment (start 129.5 95.537178) (end 129.5 97.075046) (width 0.2) (layer "F.Cu") (net 47))
  (segment (start 131.32 85.791789) (end 131.32 85.818211) (width 0.2) (layer "F.Cu") (net 47))
  (segment (start 131.32 85.232426) (end 131.32 85.303106) (width 0.2) (layer "F.Cu") (net 47))
  (segment (start 130.26 87.122844) (end 131.156359 86.226484) (width 0.2) (layer "F.Cu") (net 47))
  (arc (start 129.2 94.812913) (mid 129.238983 95.008898) (end 129.35 95.175046) (width 0.2) (layer "F.Cu") (net 47))
  (arc (start 131.235 84.565) (mid 131.320112 84.692379) (end 131.35 84.842634) (width 0.1) (layer "F.Cu") (net 47))
  (arc (start 131.156359 86.226484) (mid 131.277471 86.045228) (end 131.32 85.831422) (width 0.2) (layer "F.Cu") (net 47))
  (arc (start 131.335 85.196213) (mid 131.323898 85.212827) (end 131.32 85.232426) (width 0.1) (layer "F.Cu") (net 47))
  (arc (start 130.26 87.122844) (mid 129.475485 88.296953) (end 129.2 89.68191) (width 0.2) (layer "F.Cu") (net 47))
  (arc (start 129.35 95.175046) (mid 129.461016 95.341193) (end 129.5 95.537178) (width 0.2) (layer "F.Cu") (net 47))
  (arc (start 131.35 85.159999) (mid 131.346101 85.179598) (end 131.335 85.196213) (width 0.1) (layer "F.Cu") (net 47))
  (segment (start 131.640165 91.573009) (end 133.343137 93.275981) (width 0.2) (layer "F.Cu") (net 48))
  (segment (start 132.73 84.827426) (end 132.73 85.138786) (width 0.1) (layer "F.Cu") (net 48))
  (segment (start 132.832426 84.725) (end 132.857573 84.725) (width 0.1) (layer "F.Cu") (net 48))
  (segment (start 133.8 94.812913) (end 133.8 94.378945) (width 0.2) (layer "F.Cu") (net 48))
  (segment (start 133.5 95.537178) (end 133.5 97.075046) (width 0.2) (layer "F.Cu") (net 48))
  (segment (start 132.76 85.211213) (end 132.76 87.086391) (width 0.2) (layer "F.Cu") (net 48))
  (segment (start 131.640165 89.32699) (end 131.9675 88.999656) (width 0.2) (layer "F.Cu") (net 48))
  (segment (start 132.96 84.827426) (end 132.96 84.91) (width 0.1) (layer "F.Cu") (net 48))
  (arc (start 132.76 84.755) (mid 132.737796 84.788229) (end 132.73 84.827426) (width 0.1) (layer "F.Cu") (net 48))
  (arc (start 132.832426 84.725) (mid 132.793229 84.732796) (end 132.76 84.755) (width 0.1) (layer "F.Cu") (net 48))
  (arc (start 133.5 95.537178) (mid 133.538983 95.341193) (end 133.65 95.175046) (width 0.2) (layer "F.Cu") (net 48))
  (arc (start 131.175 90.45) (mid 131.295892 89.842231) (end 131.640165 89.32699) (width 0.2) (layer "F.Cu") (net 48))
  (arc (start 133.8 94.812913) (mid 133.761016 95.008898) (end 133.65 95.175046) (width 0.2) (layer "F.Cu") (net 48))
  (arc (start 132.745 85.175) (mid 132.756101 85.191614) (end 132.76 85.211213) (width 0.1) (layer "F.Cu") (net 48))
  (arc (start 132.93 84.755) (mid 132.952203 84.788229) (end 132.96 84.827426) (width 0.1) (layer "F.Cu") (net 48))
  (arc (start 132.93 84.755) (mid 132.89677 84.732796) (end 132.857573 84.725) (width 0.1) (layer "F.Cu") (net 48))
  (arc (start 133.8 94.378945) (mid 133.681265 93.782025) (end 133.343137 93.275981) (width 0.2) (layer "F.Cu") (net 48))
  (arc (start 132.745 85.175) (mid 132.733898 85.158385) (end 132.73 85.138786) (width 0.1) (layer "F.Cu") (net 48))
  (arc (start 131.640165 91.573009) (mid 131.295892 91.057768) (end 131.175 90.45) (width 0.2) (layer "F.Cu") (net 48))
  (arc (start 131.9675 88.999656) (mid 132.554035 88.121842) (end 132.76 87.086391) (width 0.2) (layer "F.Cu") (net 48))
  (segment (start 134.2 94.812913) (end 134.2 94.296101) (width 0.2) (layer "F.Cu") (net 49))
  (segment (start 133.075 84.565) (end 132.96 84.45) (width 0.1) (layer "F.Cu") (net 49))
  (segment (start 133.16 87.252079) (end 133.16 85.211213) (width 0.2) (layer "F.Cu") (net 49))
  (segment (start 132.367499 89.165343) (end 131.923006 89.609837) (width 0.2) (layer "F.Cu") (net 49))
  (segment (start 133.19 84.842634) (end 133.19 85.138786) (width 0.1) (layer "F.Cu") (net 49))
  (segment (start 134.5 95.537178) (end 134.5 97.075046) (width 0.2) (layer "F.Cu") (net 49))
  (segment (start 131.923006 91.290162) (end 133.684558 93.051714) (width 0.2) (layer "F.Cu") (net 49))
  (arc (start 133.19 85.138786) (mid 133.186101 85.158385) (end 133.175 85.175) (width 0.1) (layer "F.Cu") (net 49))
  (arc (start 134.5 95.537178) (mid 134.461016 95.341193) (end 134.35 95.175046) (width 0.2) (layer "F.Cu") (net 49))
  (arc (start 133.16 87.252079) (mid 132.954035 88.28753) (end 132.367499 89.165343) (width 0.2) (layer "F.Cu") (net 49))
  (arc (start 131.575 90.45) (mid 131.665443 89.995307) (end 131.923006 89.609837) (width 0.2) (layer "F.Cu") (net 49))
  (arc (start 134.2 94.812913) (mid 134.238983 95.008898) (end 134.35 95.175046) (width 0.2) (layer "F.Cu") (net 49))
  (arc (start 131.923006 91.290162) (mid 131.665443 90.904692) (end 131.575 90.45) (width 0.2) (layer "F.Cu") (net 49))
  (arc (start 133.16 85.211213) (mid 133.163898 85.191614) (end 133.175 85.175) (width 0.1) (layer "F.Cu") (net 49))
  (arc (start 134.2 94.296101) (mid 134.06604 93.622643) (end 133.684558 93.051714) (width 0.2) (layer "F.Cu") (net 49))
  (arc (start 133.075 84.565) (mid 133.160112 84.692379) (end 133.19 84.842634) (width 0.1) (layer "F.Cu") (net 49))
  (segment (start 134.6 89.994366) (end 134.6 85.211213) (width 0.2) (layer "F.Cu") (net 50))
  (segment (start 134.672426 84.725) (end 134.697573 84.725) (width 0.1) (layer "F.Cu") (net 50))
  (segment (start 137.8 94.812913) (end 137.8 94.378945) (width 0.2) (layer "F.Cu") (net 50))
  (segment (start 134.57 84.827426) (end 134.57 85.138786) (width 0.1) (layer "F.Cu") (net 50))
  (segment (start 137.343137 93.275981) (end 136.193792 92.126636) (width 0.2) (layer "F.Cu") (net 50))
  (segment (start 137.5 97.075046) (end 137.5 95.537178) (width 0.2) (layer "F.Cu") (net 50))
  (segment (start 136.193792 92.126636) (end 134.980761 90.913605) (width 0.2) (layer "F.Cu") (net 50))
  (segment (start 134.8 84.827426) (end 134.8 84.91) (width 0.1) (layer "F.Cu") (net 50))
  (arc (start 134.57 84.827426) (mid 134.577796 84.788229) (end 134.6 84.755) (width 0.1) (layer "F.Cu") (net 50))
  (arc (start 137.5 95.537178) (mid 137.538983 95.341193) (end 137.65 95.175046) (width 0.2) (layer "F.Cu") (net 50))
  (arc (start 137.65 95.175046) (mid 137.761016 95.008898) (end 137.8 94.812913) (width 0.2) (layer "F.Cu") (net 50))
  (arc (start 134.77 84.755) (mid 134.73677 84.732796) (end 134.697573 84.725) (width 0.1) (layer "F.Cu") (net 50))
  (arc (start 134.6 85.211213) (mid 134.596101 85.191614) (end 134.585 85.175) (width 0.1) (layer "F.Cu") (net 50))
  (arc (start 134.77 84.755) (mid 134.792203 84.788229) (end 134.8 84.827426) (width 0.1) (layer "F.Cu") (net 50))
  (arc (start 134.672426 84.725) (mid 134.633229 84.732796) (end 134.6 84.755) (width 0.1) (layer "F.Cu") (net 50))
  (arc (start 134.6 89.994366) (mid 134.698957 90.491854) (end 134.980761 90.913605) (width 0.2) (layer "F.Cu") (net 50))
  (arc (start 134.57 85.138786) (mid 134.573898 85.158385) (end 134.585 85.175) (width 0.1) (layer "F.Cu") (net 50))
  (arc (start 137.8 94.378945) (mid 137.681265 93.782025) (end 137.343137 93.275981) (width 0.2) (layer "F.Cu") (net 50))
  (segment (start 134.915 84.565) (end 134.8 84.45) (width 0.1) (layer "F.Cu") (net 51))
  (segment (start 135 89.952942) (end 135 85.211213) (width 0.2) (layer "F.Cu") (net 51))
  (segment (start 135.03 84.842634) (end 135.03 85.138786) (width 0.1) (layer "F.Cu") (net 51))
  (segment (start 136.593792 91.960948) (end 135.292893 90.660049) (width 0.2) (layer "F.Cu") (net 51))
  (segment (start 137.684558 93.051714) (end 136.593792 91.960948) (width 0.2) (layer "F.Cu") (net 51))
  (segment (start 138.2 94.812913) (end 138.2 94.296101) (width 0.2) (layer "F.Cu") (net 51))
  (segment (start 138.5 97.075046) (end 138.5 95.537178) (width 0.2) (layer "F.Cu") (net 51))
  (arc (start 135 85.211213) (mid 135.003898 85.191614) (end 135.015 85.175) (width 0.1) (layer "F.Cu") (net 51))
  (arc (start 138.5 95.537178) (mid 138.461016 95.341193) (end 138.35 95.175046) (width 0.2) (layer "F.Cu") (net 51))
  (arc (start 135.292893 90.660049) (mid 135.07612 90.335626) (end 135 89.952942) (width 0.2) (layer "F.Cu") (net 51))
  (arc (start 138.2 94.296101) (mid 138.06604 93.622643) (end 137.684558 93.051714) (width 0.2) (layer "F.Cu") (net 51))
  (arc (start 135.015 85.175) (mid 135.026101 85.158385) (end 135.03 85.138786) (width 0.1) (layer "F.Cu") (net 51))
  (arc (start 135.03 84.842634) (mid 135.000112 84.692379) (end 134.915 84.565) (width 0.1) (layer "F.Cu") (net 51))
  (arc (start 138.35 95.175046) (mid 138.238983 95.008898) (end 138.2 94.812913) (width 0.2) (layer "F.Cu") (net 51))
  (segment (start 137.105685 87.738529) (end 140.883518 91.516362) (width 0.2) (layer "F.Cu") (net 52))
  (segment (start 141.5 95.537178) (end 141.5 97.075046) (width 0.2) (layer "F.Cu") (net 52))
  (segment (start 136.64 84.827426) (end 136.64 84.91) (width 0.1) (layer "F.Cu") (net 52))
  (segment (start 136.44 85.211213) (end 136.44 86.131422) (width 0.2) (layer "F.Cu") (net 52))
  (segment (start 141.8 93.728945) (end 141.8 94.812913) (width 0.2) (layer "F.Cu") (net 52))
  (segment (start 136.537573 84.725) (end 136.512426 84.725) (width 0.1) (layer "F.Cu") (net 52))
  (segment (start 136.41 84.827426) (end 136.41 85.138786) (width 0.1) (layer "F.Cu") (net 52))
  (arc (start 136.425 85.175) (mid 136.413898 85.158385) (end 136.41 85.138786) (width 0.1) (layer "F.Cu") (net 52))
  (arc (start 141.5 95.537178) (mid 141.538983 95.341193) (end 141.65 95.175046) (width 0.2) (layer "F.Cu") (net 52))
  (arc (start 137.105685 87.738529) (mid 136.613005 87.001182) (end 136.44 86.131422) (width 0.2) (layer "F.Cu") (net 52))
  (arc (start 136.44 84.755) (mid 136.473229 84.732796) (end 136.512426 84.725) (width 0.1) (layer "F.Cu") (net 52))
  (arc (start 136.44 84.755) (mid 136.417796 84.788229) (end 136.41 84.827426) (width 0.1) (layer "F.Cu") (net 52))
  (arc (start 136.64 84.827426) (mid 136.632203 84.788229) (end 136.61 84.755) (width 0.1) (layer "F.Cu") (net 52))
  (arc (start 136.44 85.211213) (mid 136.436101 85.191614) (end 136.425 85.175) (width 0.1) (layer "F.Cu") (net 52))
  (arc (start 141.65 95.175046) (mid 141.761016 95.008898) (end 141.8 94.812913) (width 0.2) (layer "F.Cu") (net 52))
  (arc (start 141.8 93.728945) (mid 141.561814 92.531503) (end 140.883518 91.516362) (width 0.2) (layer "F.Cu") (net 52))
  (arc (start 136.537573 84.725) (mid 136.57677 84.732796) (end 136.61 84.755) (width 0.1) (layer "F.Cu") (net 52))
  (segment (start 137.447106 87.514262) (end 141.224938 91.292094) (width 0.2) (layer "F.Cu") (net 53))
  (segment (start 142.2 93.646101) (end 142.2 94.812913) (width 0.2) (layer "F.Cu") (net 53))
  (segment (start 136.87 84.842634) (end 136.87 85.138786) (width 0.1) (layer "F.Cu") (net 53))
  (segment (start 142.5 95.537178) (end 142.5 97.075046) (width 0.2) (layer "F.Cu") (net 53))
  (segment (start 136.84 85.211213) (end 136.84 86.048578) (width 0.2) (layer "F.Cu") (net 53))
  (segment (start 136.755 84.565) (end 136.64 84.45) (width 0.1) (layer "F.Cu") (net 53))
  (arc (start 136.87 84.842634) (mid 136.840112 84.692379) (end 136.755 84.565) (width 0.1) (layer "F.Cu") (net 53))
  (arc (start 142.5 95.537178) (mid 142.461016 95.341193) (end 142.35 95.175046) (width 0.2) (layer "F.Cu") (net 53))
  (arc (start 136.87 85.138786) (mid 136.866101 85.158385) (end 136.855 85.175) (width 0.1) (layer "F.Cu") (net 53))
  (arc (start 142.2 93.646101) (mid 141.946589 92.372121) (end 141.224938 91.292094) (width 0.2) (layer "F.Cu") (net 53))
  (arc (start 142.2 94.812913) (mid 142.238983 95.008898) (end 142.35 95.175046) (width 0.2) (layer "F.Cu") (net 53))
  (arc (start 136.84 85.211213) (mid 136.843898 85.191614) (end 136.855 85.175) (width 0.1) (layer "F.Cu") (net 53))
  (arc (start 137.447106 87.514262) (mid 136.997781 86.8418) (end 136.84 86.048578) (width 0.2) (layer "F.Cu") (net 53))
  (segment (start 137.56 75.25) (end 137.3311 75.0211) (width 0.1) (layer "F.Cu") (net 54))
  (segment (start 137.3311 72.3361) (end 136.2 71.205) (width 0.1) (layer "F.Cu") (net 54))
  (segment (start 137.3311 75.0211) (end 137.3311 72.3361) (width 0.1) (layer "F.Cu") (net 54))
  (via (at 129.95 72.69) (size 0.45) (drill 0.1) (layers "F.Cu" "B.Cu") (net 54))
  (via (at 123 81.925) (size 0.45) (drill 0.1) (layers "F.Cu" "B.Cu") (net 54))
  (via (at 136.2 71.205) (size 0.45) (drill 0.1) (layers "F.Cu" "B.Cu") (net 54))
  (segment (start 129.95 72.69) (end 129.94 72.69) (width 0.1) (layer "In3.Cu") (net 54))
  (segment (start 124.77 80.155) (end 123 81.925) (width 0.1) (layer "In3.Cu") (net 54))
  (segment (start 124.77 77.86) (end 124.77 80.155) (width 0.1) (layer "In3.Cu") (net 54))
  (segment (start 129.94 72.69) (end 124.77 77.86) (width 0.1) (layer "In3.Cu") (net 54))
  (segment (start 129.95 72.69) (end 134.715 72.69) (width 0.1) (layer "B.Cu") (net 54))
  (segment (start 134.715 72.69) (end 136.2 71.205) (width 0.1) (layer "B.Cu") (net 54))
  (segment (start 121.5 94.45) (end 121.5 97.08) (width 0.1) (layer "B.Cu") (net 54))
  (segment (start 123 92.95) (end 121.5 94.45) (width 0.1) (layer "B.Cu") (net 54))
  (segment (start 123 81.925) (end 123 92.95) (width 0.1) (layer "B.Cu") (net 54))
  (segment (start 138.94 74.79) (end 138.48 74.79) (width 0.1) (layer "F.Cu") (net 55))
  (segment (start 138.655 74.2975) (end 138.48 74.4725) (width 0.1) (layer "F.Cu") (net 55))
  (segment (start 138.94 74.28) (end 138.9375 74.2775) (width 0.1) (layer "F.Cu") (net 55))
  (segment (start 138.71 75.02) (end 138.94 75.25) (width 0.1) (layer "F.Cu") (net 55))
  (segment (start 138.48 74.4725) (end 138.48 74.79) (width 0.1) (layer "F.Cu") (net 55))
  (segment (start 138.71 75.02) (end 138.71 74.3525) (width 0.1) (layer "F.Cu") (net 55))
  (segment (start 138.94 74.79) (end 138.94 74.28) (width 0.1) (layer "F.Cu") (net 55))
  (segment (start 138.71 74.3525) (end 138.655 74.2975) (width 0.1) (layer "F.Cu") (net 55))
  (segment (start 144.75 64.99) (end 149.77 59.97) (width 0.1) (layer "F.Cu") (net 56))
  (segment (start 152.365 61.35) (end 150.985 59.97) (width 0.1) (layer "F.Cu") (net 56))
  (segment (start 154.39 61.35) (end 152.365 61.35) (width 0.1) (layer "F.Cu") (net 56))
  (segment (start 143.39 64.99) (end 144.75 64.99) (width 0.1) (layer "F.Cu") (net 56))
  (segment (start 149.77 59.97) (end 150.985 59.97) (width 0.1) (layer "F.Cu") (net 56))
  (via (at 136.1 75.725) (size 0.45) (drill 0.1) (layers "F.Cu" "B.Cu") (net 56))
  (via (at 150.985 59.97) (size 0.45) (drill 0.1) (layers "F.Cu" "B.Cu") (net 56))
  (via (at 143.39 64.99) (size 0.45) (drill 0.1) (layers "F.Cu" "B.Cu") (net 56))
  (segment (start 136.1 75.102842) (end 139.43 71.772842) (width 0.1) (layer "In3.Cu") (net 56))
  (segment (start 141.88 65) (end 143.38 65) (width 0.1) (layer "In3.Cu") (net 56))
  (segment (start 143.38 65) (end 143.39 64.99) (width 0.1) (layer "In3.Cu") (net 56))
  (segment (start 140.81 67.54) (end 140.81 66.07) (width 0.1) (layer "In3.Cu") (net 56))
  (segment (start 139.43 71.772842) (end 139.43 68.92) (width 0.1) (layer "In3.Cu") (net 56))
  (segment (start 136.1 75.725) (end 136.1 75.102842) (width 0.1) (layer "In3.Cu") (net 56))
  (segment (start 139.43 68.92) (end 140.81 67.54) (width 0.1) (layer "In3.Cu") (net 56))
  (segment (start 140.81 66.07) (end 141.88 65) (width 0.1) (layer "In3.Cu") (net 56))
  (segment (start 132.2711 73.0789) (end 133.88 71.47) (width 0.1) (layer "F.Cu") (net 57))
  (segment (start 154.64 61.6) (end 151.615 61.6) (width 0.1) (layer "F.Cu") (net 57))
  (segment (start 144.83 65.4) (end 149.26 60.97) (width 0.1) (layer "F.Cu") (net 57))
  (segment (start 151.615 61.6) (end 150.985 60.97) (width 0.1) (layer "F.Cu") (net 57))
  (segment (start 132.5 75.1051) (end 132.405187 75.1051) (width 0.1) (layer "F.Cu") (net 57))
  (segment (start 132.405187 75.1051) (end 132.2711 74.971013) (width 0.1) (layer "F.Cu") (net 57))
  (segment (start 132.2711 74.971013) (end 132.2711 73.0789) (width 0.1) (layer "F.Cu") (net 57))
  (segment (start 133.88 68.42) (end 133.64 68.18) (width 0.1) (layer "F.Cu") (net 57))
  (segment (start 149.26 60.97) (end 150.985 60.97) (width 0.1) (layer "F.Cu") (net 57))
  (segment (start 154.89 61.85) (end 154.64 61.6) (width 0.1) (layer "F.Cu") (net 57))
  (segment (start 133.64 65.97) (end 134.21 65.4) (width 0.1) (layer "F.Cu") (net 57))
  (segment (start 133.64 68.18) (end 133.64 65.97) (width 0.1) (layer "F.Cu") (net 57))
  (segment (start 133.88 71.47) (end 133.88 68.42) (width 0.1) (layer "F.Cu") (net 57))
  (segment (start 134.21 65.4) (end 144.83 65.4) (width 0.1) (layer "F.Cu") (net 57))
  (segment (start 132.5 75.25) (end 132.5 75.1051) (width 0.1) (layer "F.Cu") (net 57))
  (via (at 150.985 60.97) (size 0.45) (drill 0.1) (layers "F.Cu" "B.Cu") (net 57))
  (via (at 159.91 60.97) (size 0.45) (drill 0.1) (layers "F.Cu" "B.Cu") (net 58))
  (via (at 134.8 75.725) (size 0.45) (drill 0.1) (layers "F.Cu" "B.Cu") (net 58))
  (segment (start 159.99 63.9) (end 159.99 62.48) (width 0.1) (layer "In3.Cu") (net 58))
  (segment (start 159.99 62.48) (end 160.4 62.07) (width 0.1) (layer "In3.Cu") (net 58))
  (segment (start 134.8 75.725) (end 135.175 75.35) (width 0.1) (layer "In3.Cu") (net 58))
  (segment (start 135.175 74.295) (end 137.08 72.39) (width 0.1) (layer "In3.Cu") (net 58))
  (segment (start 157 64.71) (end 157.56 64.71) (width 0.1) (layer "In3.Cu") (net 58))
  (segment (start 156.71 64.42) (end 157 64.71) (width 0.1) (layer "In3.Cu") (net 58))
  (segment (start 139.81 66.02) (end 141.41 64.42) (width 0.1) (layer "In3.Cu") (net 58))
  (segment (start 138.08 72.39) (end 138.93 71.54) (width 0.1) (layer "In3.Cu") (net 58))
  (segment (start 138.93 71.54) (end 138.93 68.3) (width 0.1) (layer "In3.Cu") (net 58))
  (segment (start 141.41 64.42) (end 156.71 64.42) (width 0.1) (layer "In3.Cu") (net 58))
  (segment (start 135.175 75.35) (end 135.175 74.295) (width 0.1) (layer "In3.Cu") (net 58))
  (segment (start 159.51 64.38) (end 159.99 63.9) (width 0.1) (layer "In3.Cu") (net 58))
  (segment (start 157.89 64.38) (end 159.51 64.38) (width 0.1) (layer "In3.Cu") (net 58))
  (segment (start 160.4 62.07) (end 160.4 61.46) (width 0.1) (layer "In3.Cu") (net 58))
  (segment (start 160.4 61.46) (end 159.91 60.97) (width 0.1) (layer "In3.Cu") (net 58))
  (segment (start 137.08 72.39) (end 138.08 72.39) (width 0.1) (layer "In3.Cu") (net 58))
  (segment (start 157.56 64.71) (end 157.89 64.38) (width 0.1) (layer "In3.Cu") (net 58))
  (segment (start 139.81 67.42) (end 139.81 66.02) (width 0.1) (layer "In3.Cu") (net 58))
  (segment (start 138.93 68.3) (end 139.81 67.42) (width 0.1) (layer "In3.Cu") (net 58))
  (segment (start 160.43 60.435) (end 160.91 59.955) (width 0.1) (layer "B.Cu") (net 58))
  (segment (start 159.91 60.97) (end 160.43 60.45) (width 0.1) (layer "B.Cu") (net 58))
  (segment (start 160.43 60.45) (end 160.43 60.435) (width 0.1) (layer "B.Cu") (net 58))
  (segment (start 154.39 61.85) (end 151.105 61.85) (width 0.1) (layer "F.Cu") (net 59))
  (segment (start 134.66 67.62) (end 134.66 66.03) (width 0.1) (layer "F.Cu") (net 59))
  (segment (start 148.74 61.97) (end 150.985 61.97) (width 0.1) (layer "F.Cu") (net 59))
  (segment (start 134.11 71.57) (end 134.11 68.17) (width 0.1) (layer "F.Cu") (net 59))
  (segment (start 144.91 65.8) (end 148.74 61.97) (width 0.1) (layer "F.Cu") (net 59))
  (segment (start 132.5 73.18) (end 134.11 71.57) (width 0.1) (layer "F.Cu") (net 59))
  (segment (start 132.5 74.79) (end 132.5 73.18) (width 0.1) (layer "F.Cu") (net 59))
  (segment (start 134.11 68.17) (end 134.66 67.62) (width 0.1) (layer "F.Cu") (net 59))
  (segment (start 134.89 65.8) (end 144.91 65.8) (width 0.1) (layer "F.Cu") (net 59))
  (segment (start 151.105 61.85) (end 150.985 61.97) (width 0.1) (layer "F.Cu") (net 59))
  (segment (start 134.66 66.03) (end 134.89 65.8) (width 0.1) (layer "F.Cu") (net 59))
  (via (at 150.985 61.97) (size 0.45) (drill 0.1) (layers "F.Cu" "B.Cu") (net 59))
  (segment (start 116.16 88.149) (end 116.16 87.4) (width 0.1) (layer "F.Cu") (net 60))
  (segment (start 119.180499 92.74) (end 117.745 92.74) (width 0.1) (layer "F.Cu") (net 60))
  (segment (start 117.745 92.74) (end 115.805 90.8) (width 0.1) (layer "F.Cu") (net 60))
  (segment (start 116.16 87.4) (end 116.28 87.28) (width 0.1) (layer "F.Cu") (net 60))
  (segment (start 118.676501 88.149) (end 116.16 88.149) (width 0.1) (layer "F.Cu") (net 60))
  (segment (start 119.6975 89.169999) (end 118.676501 88.149) (width 0.1) (layer "F.Cu") (net 60))
  (segment (start 119.6995 92.220999) (end 119.180499 92.74) (width 0.1) (layer "F.Cu") (net 60))
  (segment (start 117.63 87.28) (end 118.53 86.38) (width 0.1) (layer "F.Cu") (net 60))
  (segment (start 116.28 87.28) (end 117.63 87.28) (width 0.1) (layer "F.Cu") (net 60))
  (via (at 116.16 88.149) (size 0.45) (drill 0.1) (layers "F.Cu" "B.Cu") (net 60))
  (segment (start 116.249095 87.039095) (end 116.249095 88.059905) (width 0.1) (layer "B.Cu") (net 60))
  (segment (start 116.249095 88.059905) (end 116.16 88.149) (width 0.1) (layer "B.Cu") (net 60))
  (segment (start 106.1955 90.3455) (end 105.9 90.05) (width 0.1) (layer "F.Cu") (net 61))
  (segment (start 107.1 86.4) (end 107.1 87.7) (width 0.1) (layer "F.Cu") (net 61))
  (segment (start 106.1955 90.349) (end 106.1955 90.3455) (width 0.1) (layer "F.Cu") (net 61))
  (segment (start 107.6955 89.2) (end 108.29 89.2) (width 0.1) (layer "F.Cu") (net 61))
  (segment (start 108.93 89.84) (end 109.25 89.84) (width 0.1) (layer "F.Cu") (net 61))
  (segment (start 108.29 89.2) (end 108.93 89.84) (width 0.1) (layer "F.Cu") (net 61))
  (segment (start 109.7575 91.11) (end 110.0675 90.8) (width 0.1) (layer "F.Cu") (net 61))
  (segment (start 107.6955 88.3045) (end 107.6955 89.2) (width 0.1) (layer "F.Cu") (net 61))
  (segment (start 110.0675 90.8) (end 110.0675 90.6575) (width 0.1) (layer "F.Cu") (net 61))
  (segment (start 110.0675 90.6575) (end 109.25 89.84) (width 0.1) (layer "F.Cu") (net 61))
  (segment (start 107.7 88.3) (end 107.6955 88.3045) (width 0.1) (layer "F.Cu") (net 61))
  (segment (start 106.1955 90.349) (end 106.9565 91.11) (width 0.1) (layer "F.Cu") (net 61))
  (segment (start 106.9565 91.11) (end 109.7575 91.11) (width 0.1) (layer "F.Cu") (net 61))
  (segment (start 107.1 87.7) (end 107.7 88.3) (width 0.1) (layer "F.Cu") (net 61))
  (via (at 108.8 92.8) (size 0.45) (drill 0.1) (layers "F.Cu" "B.Cu") (net 61))
  (via (at 109.4 93.35) (size 0.45) (drill 0.1) (layers "F.Cu" "B.Cu") (net 61))
  (via (at 105.9 90.05) (size 0.45) (drill 0.1) (layers "F.Cu" "B.Cu") (net 61))
  (via (at 162.8 88) (size 0.45) (drill 0.1) (layers "F.Cu" "B.Cu") (net 61))
  (via (at 161.7 88.55) (size 0.45) (drill 0.1) (layers "F.Cu" "B.Cu") (net 61))
  (via (at 162.25 88.55) (size 0.45) (drill 0.1) (layers "F.Cu" "B.Cu") (net 61))
  (via (at 110 93.35) (size 0.45) (drill 0.1) (layers "F.Cu" "B.Cu") (net 61))
  (via (at 110.6 93.35) (size 0.45) (drill 0.1) (layers "F.Cu" "B.Cu") (net 61))
  (via (at 162.25 89.099999) (size 0.45) (drill 0.1) (layers "F.Cu" "B.Cu") (net 61))
  (via (at 108.8 93.9) (size 0.45) (drill 0.1) (layers "F.Cu" "B.Cu") (net 61))
  (via (at 163.349999 88) (size 0.45) (drill 0.1) (layers "F.Cu" "B.Cu") (net 61))
  (via (at 110 92.8) (size 0.45) (drill 0.1) (layers "F.Cu" "B.Cu") (net 61))
  (via (at 110.6 93.9) (size 0.45) (drill 0.1) (layers "F.Cu" "B.Cu") (net 61))
  (via (at 162.799999 88.55) (size 0.45) (drill 0.1) (layers "F.Cu" "B.Cu") (net 61))
  (via (at 163.349999 88.55) (size 0.45) (drill 0.1) (layers "F.Cu" "B.Cu") (net 61))
  (via (at 109.4 93.9) (size 0.45) (drill 0.1) (layers "F.Cu" "B.Cu") (net 61))
  (via (at 162.799999 89.1) (size 0.45) (drill 0.1) (layers "F.Cu" "B.Cu") (net 61))
  (via (at 110.6 92.8) (size 0.45) (drill 0.1) (layers "F.Cu" "B.Cu") (net 61))
  (via (at 110 93.9) (size 0.45) (drill 0.1) (layers "F.Cu" "B.Cu") (net 61))
  (via (at 161.7 89.1) (size 0.45) (drill 0.1) (layers "F.Cu" "B.Cu") (net 61))
  (via (at 108.8 93.35) (size 0.45) (drill 0.1) (layers "F.Cu" "B.Cu") (net 61))
  (via (at 162.25 88) (size 0.45) (drill 0.1) (layers "F.Cu" "B.Cu") (net 61))
  (via (at 109.4 92.8) (size 0.45) (drill 0.1) (layers "F.Cu" "B.Cu") (net 61))
  (via (at 163.349999 89.1) (size 0.45) (drill 0.1) (layers "F.Cu" "B.Cu") (net 61))
  (via (at 161.7 88) (size 0.45) (drill 0.1) (layers "F.Cu" "B.Cu") (net 61))
  (segment (start 103.72 87.94) (end 105.83 90.05) (width 0.1) (layer "B.Cu") (net 61))
  (segment (start 105.83 90.05) (end 105.9 90.05) (width 0.1) (layer "B.Cu") (net 61))
  (segment (start 103.69 87.94) (end 103.72 87.94) (width 0.1) (layer "B.Cu") (net 61))
  (segment (start 159.39 62.85) (end 160.045 62.85) (width 0.1) (layer "F.Cu") (net 62))
  (segment (start 160.045 62.85) (end 160.925 61.97) (width 0.1) (layer "F.Cu") (net 62))
  (via (at 137.4 75.725) (size 0.45) (drill 0.1) (layers "F.Cu" "B.Cu") (net 62))
  (via (at 160.925 61.97) (size 0.45) (drill 0.1) (layers "F.Cu" "B.Cu") (net 62))
  (segment (start 139.98 71.96) (end 139.98 69.3) (width 0.1) (layer "In3.Cu") (net 62))
  (segment (start 139.98 69.3) (end 141.83 67.45) (width 0.1) (layer "In3.Cu") (net 62))
  (segment (start 160.32 62.575) (end 160.925 61.97) (width 0.1) (layer "In3.Cu") (net 62))
  (segment (start 141.83 67.45) (end 141.83 66.11) (width 0.1) (layer "In3.Cu") (net 62))
  (segment (start 157.43 65.34) (end 159.4 65.34) (width 0.1) (layer "In3.Cu") (net 62))
  (segment (start 141.83 66.11) (end 142.145 65.795) (width 0.1) (layer "In3.Cu") (net 62))
  (segment (start 137.4 74.54) (end 139.98 71.96) (width 0.1) (layer "In3.Cu") (net 62))
  (segment (start 137.4 75.725) (end 137.4 74.54) (width 0.1) (layer "In3.Cu") (net 62))
  (segment (start 142.145 65.795) (end 156.975 65.795) (width 0.1) (layer "In3.Cu") (net 62))
  (segment (start 156.975 65.795) (end 157.43 65.34) (width 0.1) (layer "In3.Cu") (net 62))
  (segment (start 160.32 64.42) (end 160.32 62.575) (width 0.1) (layer "In3.Cu") (net 62))
  (segment (start 159.4 65.34) (end 160.32 64.42) (width 0.1) (layer "In3.Cu") (net 62))
  (segment (start 155.29 57.97) (end 146.49 57.97) (width 0.1) (layer "F.Cu") (net 63))
  (segment (start 146.49 57.97) (end 143.41 61.05) (width 0.1) (layer "F.Cu") (net 63))
  (segment (start 134.433856 61.216144) (end 134.433856 61.665) (width 0.1) (layer "F.Cu") (net 63))
  (segment (start 155.89 60.35) (end 155.89 58.57) (width 0.1) (layer "F.Cu") (net 63))
  (segment (start 134.433856 61.665) (end 134.63 61.665) (width 0.25) (layer "F.Cu") (net 63))
  (segment (start 128.08 64.87) (end 131.285 61.665) (width 0.1) (layer "F.Cu") (net 63))
  (segment (start 129.74 76.17) (end 128.65 76.17) (width 0.1) (layer "F.Cu") (net 63))
  (segment (start 128.65 76.17) (end 128.08 75.6) (width 0.1) (layer "F.Cu") (net 63))
  (segment (start 155.89 58.57) (end 155.29 57.97) (width 0.1) (layer "F.Cu") (net 63))
  (segment (start 143.41 61.05) (end 134.6 61.05) (width 0.1) (layer "F.Cu") (net 63))
  (segment (start 134.6 61.05) (end 134.433856 61.216144) (width 0.1) (layer "F.Cu") (net 63))
  (segment (start 128.08 75.6) (end 128.08 64.87) (width 0.1) (layer "F.Cu") (net 63))
  (segment (start 131.285 61.665) (end 134.63 61.665) (width 0.1) (layer "F.Cu") (net 63))
  (via (at 134.63 61.665) (size 0.45) (drill 0.1) (layers "F.Cu" "B.Cu") (net 63))
  (segment (start 134.433856 62.932) (end 134.628 62.932) (width 0.25) (layer "F.Cu") (net 64))
  (segment (start 132.63 67.6) (end 133.64 68.61) (width 0.1) (layer "F.Cu") (net 64))
  (segment (start 132.04 72.96) (end 132.04 74.79) (width 0.1) (layer "F.Cu") (net 64))
  (segment (start 133.64 71.36) (end 132.04 72.96) (width 0.1) (layer "F.Cu") (net 64))
  (segment (start 132.63 65.45) (end 132.63 67.6) (width 0.1) (layer "F.Cu") (net 64))
  (segment (start 133.64 68.61) (end 133.64 71.36) (width 0.1) (layer "F.Cu") (net 64))
  (segment (start 134.628 62.932) (end 134.63 62.93) (width 0.25) (layer "F.Cu") (net 64))
  (via (at 132.63 65.45) (size 0.45) (drill 0.1) (layers "F.Cu" "B.Cu") (net 64))
  (via (at 134.63 62.93) (size 0.45) (drill 0.1) (layers "F.Cu" "B.Cu") (net 64))
  (segment (start 132.63 64.35) (end 134.05 62.93) (width 0.1) (layer "B.Cu") (net 64))
  (segment (start 134.05 62.93) (end 134.63 62.93) (width 0.1) (layer "B.Cu") (net 64))
  (segment (start 132.63 65.45) (end 132.63 64.35) (width 0.1) (layer "B.Cu") (net 64))
  (segment (start 128.87 65.35) (end 128.87 75.41) (width 0.1) (layer "F.Cu") (net 65))
  (segment (start 131.3 62.93) (end 131.29 62.93) (width 0.1) (layer "F.Cu") (net 65))
  (segment (start 131.29 62.93) (end 128.87 65.35) (width 0.1) (layer "F.Cu") (net 65))
  (segment (start 134.433856 60.395) (end 134.63 60.395) (width 0.25) (layer "F.Cu") (net 65))
  (segment (start 155.14 58.89) (end 154.91 58.66) (width 0.1) (layer "F.Cu") (net 65))
  (segment (start 155.39 60.85) (end 155.14 60.6) (width 0.1) (layer "F.Cu") (net 65))
  (segment (start 129.17 75.71) (end 129.74 75.71) (width 0.1) (layer "F.Cu") (net 65))
  (segment (start 147.84 58.66) (end 143.81 62.69) (width 0.1) (layer "F.Cu") (net 65))
  (segment (start 128.87 75.41) (end 129.17 75.71) (width 0.1) (layer "F.Cu") (net 65))
  (segment (start 154.91 58.66) (end 147.84 58.66) (width 0.1) (layer "F.Cu") (net 65))
  (segment (start 155.14 60.6) (end 155.14 58.89) (width 0.1) (layer "F.Cu") (net 65))
  (via (at 143.81 62.69) (size 0.45) (drill 0.1) (layers "F.Cu" "B.Cu") (net 65))
  (via (at 131.3 62.93) (size 0.45) (drill 0.1) (layers "F.Cu" "B.Cu") (net 65))
  (via (at 134.63 60.395) (size 0.45) (drill 0.1) (layers "F.Cu" "B.Cu") (net 65))
  (segment (start 135.245 59.78) (end 134.63 60.395) (width 0.1) (layer "B.Cu") (net 65))
  (segment (start 132.605 60.395) (end 134.63 60.395) (width 0.1) (layer "B.Cu") (net 65))
  (segment (start 131.3 61.7) (end 132.605 60.395) (width 0.1) (layer "B.Cu") (net 65))
  (segment (start 131.3 62.93) (end 131.3 61.7) (width 0.1) (layer "B.Cu") (net 65))
  (segment (start 143.81 62.69) (end 140.9 59.78) (width 0.1) (layer "B.Cu") (net 65))
  (segment (start 140.9 59.78) (end 135.245 59.78) (width 0.1) (layer "B.Cu") (net 65))
  (segment (start 144.894999 76.17) (end 146.105 74.959999) (width 0.1) (layer "F.Cu") (net 66))
  (segment (start 155.225 65.675) (end 155.5 65.675) (width 0.1) (layer "F.Cu") (net 66))
  (segment (start 146.48 74.42) (end 155.225 65.675) (width 0.1) (layer "F.Cu") (net 66))
  (segment (start 155.64 65.535) (end 155.64 65.1) (width 0.1) (layer "F.Cu") (net 66))
  (segment (start 155.5 65.675) (end 155.64 65.535) (width 0.1) (layer "F.Cu") (net 66))
  (segment (start 146.105 74.959999) (end 146.48 74.584999) (width 0.1) (layer "F.Cu") (net 66))
  (segment (start 139.86 76.17) (end 144.894999 76.17) (width 0.1) (layer "F.Cu") (net 66))
  (segment (start 146.48 74.584999) (end 146.48 74.42) (width 0.1) (layer "F.Cu") (net 66))
  (segment (start 155.64 65.1) (end 155.89 64.85) (width 0.1) (layer "F.Cu") (net 66))
  (via (at 146.105 74.959999) (size 0.45) (drill 0.1) (layers "F.Cu" "B.Cu") (net 66))
  (segment (start 155.35 65.95) (end 155.625 65.95) (width 0.1) (layer "F.Cu") (net 67))
  (segment (start 140.97 77.41) (end 145.655 77.41) (width 0.1) (layer "F.Cu") (net 67))
  (segment (start 146.105 76.96) (end 146.95 76.115) (width 0.1) (layer "F.Cu") (net 67))
  (segment (start 139.86 76.63) (end 140.19 76.63) (width 0.1) (layer "F.Cu") (net 67))
  (segment (start 155.625 65.95) (end 155.89 65.685) (width 0.1) (layer "F.Cu") (net 67))
  (segment (start 140.19 76.63) (end 140.97 77.41) (width 0.1) (layer "F.Cu") (net 67))
  (segment (start 145.655 77.41) (end 146.105 76.96) (width 0.1) (layer "F.Cu") (net 67))
  (segment (start 155.89 65.685) (end 155.89 65.35) (width 0.1) (layer "F.Cu") (net 67))
  (segment (start 146.95 76.115) (end 146.95 74.35) (width 0.1) (layer "F.Cu") (net 67))
  (segment (start 146.95 74.35) (end 155.35 65.95) (width 0.1) (layer "F.Cu") (net 67))
  (via (at 146.105 76.96) (size 0.45) (drill 0.1) (layers "F.Cu" "B.Cu") (net 67))
  (segment (start 131.27 62.3) (end 128.47 65.1) (width 0.1) (layer "F.Cu") (net 68))
  (segment (start 128.47 65.1) (end 128.47 75.47) (width 0.1) (layer "F.Cu") (net 68))
  (segment (start 128.47 75.47) (end 128.9389 75.9389) (width 0.1) (layer "F.Cu") (net 68))
  (segment (start 155.04 58.43) (end 147.37 58.43) (width 0.1) (layer "F.Cu") (net 68))
  (segment (start 155.39 58.78) (end 155.04 58.43) (width 0.1) (layer "F.Cu") (net 68))
  (segment (start 147.37 58.43) (end 142.87 62.93) (width 0.1) (layer "F.Cu") (net 68))
  (segment (start 129.9689 75.9389) (end 130.2 76.17) (width 0.1) (layer "F.Cu") (net 68))
  (segment (start 132 62.3) (end 131.27 62.3) (width 0.1) (layer "F.Cu") (net 68))
  (segment (start 155.39 60.35) (end 155.39 58.78) (width 0.1) (layer "F.Cu") (net 68))
  (segment (start 128.9389 75.9389) (end 129.9689 75.9389) (width 0.1) (layer "F.Cu") (net 68))
  (via (at 142.87 62.93) (size 0.45) (drill 0.1) (layers "F.Cu" "B.Cu") (net 68))
  (via (at 139.859856 62.932) (size 0.45) (drill 0.1) (layers "F.Cu" "B.Cu") (net 68))
  (via (at 132 62.3) (size 0.45) (drill 0.1) (layers "F.Cu" "B.Cu") (net 68))
  (segment (start 142.87 62.93) (end 142.868 62.932) (width 0.1) (layer "B.Cu") (net 68))
  (segment (start 142.868 62.932) (end 139.859856 62.932) (width 0.1) (layer "B.Cu") (net 68))
  (segment (start 139.227856 62.3) (end 139.859856 62.932) (width 0.1) (layer "B.Cu") (net 68))
  (segment (start 132 62.3) (end 139.227856 62.3) (width 0.1) (layer "B.Cu") (net 68))
  (segment (start 146.9 58.2) (end 142.3 62.8) (width 0.1) (layer "F.Cu") (net 69))
  (segment (start 129.43 75.48) (end 129.25 75.3) (width 0.1) (layer "F.Cu") (net 69))
  (segment (start 155.89 60.85) (end 155.64 60.6) (width 0.1) (layer "F.Cu") (net 69))
  (segment (start 130.2 75.71) (end 129.97 75.48) (width 0.1) (layer "F.Cu") (net 69))
  (segment (start 129.97 75.48) (end 129.43 75.48) (width 0.1) (layer "F.Cu") (net 69))
  (segment (start 129.25 66.35) (end 130.79 64.81) (width 0.1) (layer "F.Cu") (net 69))
  (segment (start 129.25 75.3) (end 129.25 66.35) (width 0.1) (layer "F.Cu") (net 69))
  (segment (start 130.79 64.81) (end 138.79 64.81) (width 0.1) (layer "F.Cu") (net 69))
  (segment (start 139.398 64.202) (end 139.859856 64.202) (width 0.1) (layer "F.Cu") (net 69))
  (segment (start 142.3 63.9) (end 141.998 64.202) (width 0.1) (layer "F.Cu") (net 69))
  (segment (start 155.19 58.2) (end 146.9 58.2) (width 0.1) (layer "F.Cu") (net 69))
  (segment (start 138.79 64.81) (end 139.398 64.202) (width 0.1) (layer "F.Cu") (net 69))
  (segment (start 141.998 64.202) (end 139.859856 64.202) (width 0.1) (layer "F.Cu") (net 69))
  (segment (start 155.64 58.65) (end 155.19 58.2) (width 0.1) (layer "F.Cu") (net 69))
  (segment (start 155.64 60.6) (end 155.64 58.65) (width 0.1) (layer "F.Cu") (net 69))
  (segment (start 142.3 62.8) (end 142.3 63.9) (width 0.1) (layer "F.Cu") (net 69))
  (segment (start 144.276326 78.513483) (end 144.08231 78.319467) (width 0.2) (layer "F.Cu") (net 70))
  (segment (start 138.94 83.51) (end 138.7 83.75) (width 0.1) (layer "F.Cu") (net 70))
  (segment (start 152.934678 71.632477) (end 146.244158 78.322997) (width 0.2) (layer "F.Cu") (net 70))
  (segment (start 154.465321 67.937178) (end 155.860152 66.542347) (width 0.2) (layer "F.Cu") (net 70))
  (segment (start 144.895612 78.77) (end 145.164999 78.77) (width 0.2) (layer "F.Cu") (net 70))
  (segment (start 156.2725 64.9675) (end 156.39 64.85) (width 0.1) (layer "F.Cu") (net 70))
  (segment (start 156.155 65.25117) (end 156.155 66.314943) (width 0.1) (layer "F.Cu") (net 70))
  (segment (start 144.01981 78.168578) (end 144.01981 78.08019) (width 0.2) (layer "F.Cu") (net 70))
  (segment (start 156.100837 66.442652) (end 156.102995 66.440495) (width 0.1) (layer "F.Cu") (net 70))
  (via (at 144.01981 78.08019) (size 0.45) (drill 0.1) (layers "F.Cu" "B.Cu") (net 70))
  (via (at 138.94 83.51) (size 0.45) (drill 0.1) (layers "F.Cu" "B.Cu") (net 70))
  (arc (start 144.01981 78.168578) (mid 144.036053 78.250238) (end 144.08231 78.319467) (width 0.2) (layer "F.Cu") (net 70))
  (arc (start 145.164999 78.77) (mid 145.749035 78.653827) (end 146.244158 78.322997) (width 0.2) (layer "F.Cu") (net 70))
  (arc (start 153.7 69.784828) (mid 153.8989 68.784887) (end 154.465321 67.937178) (width 0.2) (layer "F.Cu") (net 70))
  (arc (start 152.934678 71.632477) (mid 153.501099 70.784768) (end 153.7 69.784828) (width 0.2) (layer "F.Cu") (net 70))
  (arc (start 155.980495 66.4925) (mid 155.915365 66.505454) (end 155.860152 66.542347) (width 0.1) (layer "F.Cu") (net 70))
  (arc (start 156.100837 66.442652) (mid 156.045623 66.479544) (end 155.980495 66.4925) (width 0.1) (layer "F.Cu") (net 70))
  (arc (start 144.895612 78.77) (mid 144.560456 78.703333) (end 144.276326 78.513483) (width 0.2) (layer "F.Cu") (net 70))
  (arc (start 156.102995 66.440495) (mid 156.141484 66.382891) (end 156.155 66.314943) (width 0.1) (layer "F.Cu") (net 70))
  (arc (start 156.2725 64.9675) (mid 156.185537 65.097648) (end 156.155 65.25117) (width 0.1) (layer "F.Cu") (net 70))
  (segment (start 144.56 79.179129) (end 144.56 79.765) (width 0.13) (layer "In3.Cu") (net 70))
  (segment (start 141.031143 82.8) (end 139.347076 82.8) (width 0.13) (layer "In3.Cu") (net 70))
  (segment (start 144.01981 78.168578) (end 144.01981 78.08019) (width 0.13) (layer "In3.Cu") (net 70))
  (segment (start 144.289905 78.527062) (end 144.08231 78.319467) (width 0.13) (layer "In3.Cu") (net 70))
  (segment (start 138.911631 83.01505) (end 138.970841 82.955841) (width 0.13) (layer "In3.Cu") (net 70))
  (segment (start 143.875631 81.417212) (end 143.526421 81.766421) (width 0.13) (layer "In3.Cu") (net 70))
  (segment (start 138.815 83.248341) (end 138.815 83.296611) (width 0.13) (layer "In3.Cu") (net 70))
  (segment (start 138.8775 83.4475) (end 138.94 83.51) (width 0.13) (layer "In3.Cu") (net 70))
  (arc (start 144.56 79.765) (mid 144.382138 80.65917) (end 143.875631 81.417212) (width 0.13) (layer "In3.Cu") (net 70))
  (arc (start 138.970841 82.955841) (mid 139.143459 82.840501) (end 139.347076 82.8) (width 0.13) (layer "In3.Cu") (net 70))
  (arc (start 138.815 83.248341) (mid 138.840113 83.122085) (end 138.911631 83.01505) (width 0.13) (layer "In3.Cu") (net 70))
  (arc (start 144.01981 78.168578) (mid 144.036053 78.250238) (end 144.08231 78.319467) (width 0.13) (layer "In3.Cu") (net 70))
  (arc (start 144.289905 78.527062) (mid 144.489804 78.826232) (end 144.56 79.179129) (width 0.13) (layer "In3.Cu") (net 70))
  (arc (start 141.031143 82.8) (mid 142.381578 82.531381) (end 143.526421 81.766421) (width 0.13) (layer "In3.Cu") (net 70))
  (arc (start 138.8775 83.4475) (mid 138.831243 83.378271) (end 138.815 83.296611) (width 0.13) (layer "In3.Cu") (net 70))
  (segment (start 156.273921 66.552411) (end 156.242996 66.583337) (width 0.1) (layer "F.Cu") (net 71))
  (segment (start 156.3725 65.3675) (end 156.39 65.35) (width 0.1) (layer "F.Cu") (net 71))
  (segment (start 156.355 65.409748) (end 156.355 66.356672) (width 0.1) (layer "F.Cu") (net 71))
  (segment (start 143.56019 78.53981) (end 143.648578 78.53981) (width 0.2) (layer "F.Cu") (net 71))
  (segment (start 138.29 83.51) (end 138.05 83.75) (width 0.1) (layer "F.Cu") (net 71))
  (segment (start 156.142691 66.825496) (end 154.865321 68.102866) (width 0.2) (layer "F.Cu") (net 71))
  (segment (start 146.527004 78.605839) (end 153.334678 71.798165) (width 0.2) (layer "F.Cu") (net 71))
  (segment (start 144.812768 79.17) (end 145.165 79.17) (width 0.2) (layer "F.Cu") (net 71))
  (segment (start 144.052062 78.854905) (end 143.799467 78.60231) (width 0.2) (layer "F.Cu") (net 71))
  (via (at 138.29 83.51) (size 0.45) (drill 0.1) (layers "F.Cu" "B.Cu") (net 71))
  (via (at 143.56019 78.53981) (size 0.45) (drill 0.1) (layers "F.Cu" "B.Cu") (net 71))
  (arc (start 156.355 65.409748) (mid 156.359548 65.386883) (end 156.3725 65.3675) (width 0.1) (layer "F.Cu") (net 71))
  (arc (start 156.273921 66.552411) (mid 156.333928 66.462605) (end 156.355 66.356672) (width 0.1) (layer "F.Cu") (net 71))
  (arc (start 156.192844 66.704417) (mid 156.205878 66.638888) (end 156.242996 66.583337) (width 0.1) (layer "F.Cu") (net 71))
  (arc (start 144.052062 78.854905) (mid 144.401077 79.088109) (end 144.812768 79.17) (width 0.2) (layer "F.Cu") (net 71))
  (arc (start 156.192844 66.704417) (mid 156.179809 66.769944) (end 156.142691 66.825496) (width 0.1) (layer "F.Cu") (net 71))
  (arc (start 143.799467 78.60231) (mid 143.730238 78.556053) (end 143.648578 78.53981) (width 0.2) (layer "F.Cu") (net 71))
  (arc (start 154.1 69.950516) (mid 154.2989 68.950575) (end 154.865321 68.102866) (width 0.2) (layer "F.Cu") (net 71))
  (arc (start 146.527004 78.605839) (mid 145.902111 79.023379) (end 145.165 79.17) (width 0.2) (layer "F.Cu") (net 71))
  (arc (start 154.1 69.950516) (mid 153.901099 70.950456) (end 153.334678 71.798165) (width 0.2) (layer "F.Cu") (net 71))
  (segment (start 143.56019 78.53981) (end 143.648578 78.53981) (width 0.13) (layer "In3.Cu") (net 71))
  (segment (start 144.16 79.261972) (end 144.16 79.764999) (width 0.13) (layer "In3.Cu") (net 71))
  (segment (start 138.687997 82.672997) (end 138.570211 82.790783) (width 0.13) (layer "In3.Cu") (net 71))
  (segment (start 141.031139 82.4) (end 139.347071 82.4) (width 0.13) (layer "In3.Cu") (net 71))
  (segment (start 138.29 83.51) (end 138.3525 83.4475) (width 0.13) (layer "In3.Cu") (net 71))
  (segment (start 143.243577 81.483577) (end 143.592789 81.134366) (width 0.13) (layer "In3.Cu") (net 71))
  (segment (start 138.415 83.165497) (end 138.415 83.296611) (width 0.13) (layer "In3.Cu") (net 71))
  (segment (start 143.948483 78.751326) (end 143.799467 78.60231) (width 0.13) (layer "In3.Cu") (net 71))
  (arc (start 138.570211 82.790783) (mid 138.455338 82.962703) (end 138.415 83.165497) (width 0.13) (layer "In3.Cu") (net 71))
  (arc (start 144.16 79.261972) (mid 144.105028 78.985612) (end 143.948483 78.751326) (width 0.13) (layer "In3.Cu") (net 71))
  (arc (start 138.687997 82.672997) (mid 138.990383 82.470949) (end 139.347071 82.4) (width 0.13) (layer "In3.Cu") (net 71))
  (arc (start 144.16 79.764999) (mid 144.012586 80.506095) (end 143.592789 81.134366) (width 0.13) (layer "In3.Cu") (net 71))
  (arc (start 138.3525 83.4475) (mid 138.398756 83.378271) (end 138.415 83.296611) (width 0.13) (layer "In3.Cu") (net 71))
  (arc (start 143.243577 81.483577) (mid 142.228502 82.161829) (end 141.031139 82.4) (width 0.13) (layer "In3.Cu") (net 71))
  (arc (start 143.799467 78.60231) (mid 143.730238 78.556053) (end 143.648578 78.53981) (width 0.13) (layer "In3.Cu") (net 71))
  (segment (start 126.33981 83.259467) (end 126.692405 83.612062) (width 0.2) (layer "F.Cu") (net 72))
  (segment (start 131.875 82.775) (end 132.2 83.1) (width 0.1) (layer "F.Cu") (net 72))
  (segment (start 123.325 84.911611) (end 123.325 84.6) (width 0.2) (layer "F.Cu") (net 72))
  (segment (start 126.27731 83.02019) (end 126.27731 83.108578) (width 0.2) (layer "F.Cu") (net 72))
  (segment (start 127.1075 84.614189) (end 127.1075 85.503186) (width 0.2) (layer "F.Cu") (net 72))
  (segment (start 123.803578 86.446422) (end 123.792184 86.435028) (width 0.2) (layer "F.Cu") (net 72))
  (segment (start 123.45 85.608922) (end 123.45 85.213388) (width 0.2) (layer "F.Cu") (net 72))
  (segment (start 125.810686 86.8) (end 124.65719 86.8) (width 0.2) (layer "F.Cu") (net 72))
  (via (at 126.27731 83.02019) (size 0.45) (drill 0.1) (layers "F.Cu" "B.Cu") (net 72))
  (via (at 131.875 82.775) (size 0.45) (drill 0.1) (layers "F.Cu" "B.Cu") (net 72))
  (arc (start 127.1075 84.614189) (mid 126.99962 84.071841) (end 126.692405 83.612062) (width 0.2) (layer "F.Cu") (net 72))
  (arc (start 126.33981 83.259467) (mid 126.293553 83.190238) (end 126.27731 83.108578) (width 0.2) (layer "F.Cu") (net 72))
  (arc (start 123.3875 85.0625) (mid 123.433756 85.131728) (end 123.45 85.213388) (width 0.2) (layer "F.Cu") (net 72))
  (arc (start 123.45 85.608922) (mid 123.53893 86.056007) (end 123.792184 86.435028) (width 0.2) (layer "F.Cu") (net 72))
  (arc (start 123.803578 86.446422) (mid 124.195218 86.708108) (end 124.65719 86.8) (width 0.2) (layer "F.Cu") (net 72))
  (arc (start 123.325 84.911611) (mid 123.341243 84.993271) (end 123.3875 85.0625) (width 0.2) (layer "F.Cu") (net 72))
  (arc (start 127.1075 85.503186) (mid 127.008785 85.999455) (end 126.727672 86.420172) (width 0.2) (layer "F.Cu") (net 72))
  (arc (start 126.727672 86.420172) (mid 126.306955 86.701285) (end 125.810686 86.8) (width 0.2) (layer "F.Cu") (net 72))
  (segment (start 132.1 83.159099) (end 132.1 83.174289) (width 0.1) (layer "B.Cu") (net 72))
  (segment (start 131.875 82.775) (end 131.9875 82.8875) (width 0.1) (layer "B.Cu") (net 72))
  (segment (start 126.862903 83.54) (end 128.764289 83.54) (width 0.2) (layer "B.Cu") (net 72))
  (segment (start 129.00571 83.64) (end 131.602511 83.64) (width 0.1) (layer "B.Cu") (net 72))
  (segment (start 126.33981 83.259467) (end 126.448826 83.368483) (width 0.2) (layer "B.Cu") (net 72))
  (segment (start 126.27731 83.02019) (end 126.27731 83.108578) (width 0.2) (layer "B.Cu") (net 72))
  (segment (start 131.976759 83.471818) (end 131.954288 83.494288) (width 0.1) (layer "B.Cu") (net 72))
  (arc (start 126.33981 83.259467) (mid 126.293553 83.190238) (end 126.27731 83.108578) (width 0.2) (layer "B.Cu") (net 72))
  (arc (start 131.976759 83.471818) (mid 132.06797 83.33531) (end 132.1 83.174289) (width 0.1) (layer "B.Cu") (net 72))
  (arc (start 132.1 83.159099) (mid 132.070762 83.01211) (end 131.9875 82.8875) (width 0.1) (layer "B.Cu") (net 72))
  (arc (start 126.862903 83.54) (mid 126.638806 83.495424) (end 126.448826 83.368483) (width 0.2) (layer "B.Cu") (net 72))
  (arc (start 131.954288 83.494288) (mid 131.792891 83.60213) (end 131.602511 83.64) (width 0.1) (layer "B.Cu") (net 72))
  (arc (start 128.885 83.59) (mid 128.940382 83.627005) (end 129.00571 83.64) (width 0.1) (layer "B.Cu") (net 72))
  (arc (start 128.885 83.59) (mid 128.829617 83.552994) (end 128.764289 83.54) (width 0.1) (layer "B.Cu") (net 72))
  (segment (start 126.056967 83.54231) (end 126.350983 83.836326) (width 0.2) (layer "F.Cu") (net 73))
  (segment (start 125.732195 86.4) (end 125.810681 86.4) (width 0.2) (layer "F.Cu") (net 73))
  (segment (start 125.407195 85.95) (end 125.407195 86.15) (width 0.2) (layer "F.Cu") (net 73))
  (segment (start 132.525 82.775) (end 132.85 83.1) (width 0.1) (layer "F.Cu") (net 73))
  (segment (start 126.7075 85.503181) (end 126.7075 84.697033) (width 0.2) (layer "F.Cu") (net 73))
  (segment (start 123.85 85.592804) (end 123.85 85.213388) (width 0.2) (layer "F.Cu") (net 73))
  (segment (start 123.975 84.911611) (end 123.975 84.6) (width 0.2) (layer "F.Cu") (net 73))
  (segment (start 125.682195 86.4) (end 125.657195 86.4) (width 0.2) (layer "F.Cu") (net 73))
  (segment (start 124.907195 85.95) (end 124.907195 86.15) (width 0.2) (layer "F.Cu") (net 73))
  (segment (start 125.732195 86.4) (end 125.682195 86.4) (width 0.2) (layer "F.Cu") (net 73))
  (segment (start 125.906078 83.47981) (end 125.81769 83.47981) (width 0.2) (layer "F.Cu") (net 73))
  (via (at 125.81769 83.47981) (size 0.45) (drill 0.1) (layers "F.Cu" "B.Cu") (net 73))
  (via (at 132.525 82.775) (size 0.45) (drill 0.1) (layers "F.Cu" "B.Cu") (net 73))
  (arc (start 125.407195 85.95) (mid 125.333972 85.773223) (end 125.157195 85.7) (width 0.2) (layer "F.Cu") (net 73))
  (arc (start 126.7075 85.503181) (mid 126.639233 85.846379) (end 126.444828 86.137328) (width 0.2) (layer "F.Cu") (net 73))
  (arc (start 125.657195 86.4) (mid 125.480418 86.326777) (end 125.407195 86.15) (width 0.2) (layer "F.Cu") (net 73))
  (arc (start 124.657195 86.4) (mid 124.348294 86.338555) (end 124.086422 86.163578) (width 0.2) (layer "F.Cu") (net 73))
  (arc (start 123.9125 85.0625) (mid 123.958756 84.993271) (end 123.975 84.911611) (width 0.2) (layer "F.Cu") (net 73))
  (arc (start 123.9125 85.0625) (mid 123.866243 85.131728) (end 123.85 85.213388) (width 0.2) (layer "F.Cu") (net 73))
  (arc (start 124.907195 85.95) (mid 124.980418 85.773223) (end 125.157195 85.7) (width 0.2) (layer "F.Cu") (net 73))
  (arc (start 124.086422 86.163578) (mid 123.911444 85.901704) (end 123.85 85.592804) (width 0.2) (layer "F.Cu") (net 73))
  (arc (start 125.906078 83.47981) (mid 125.987738 83.496053) (end 126.056967 83.54231) (width 0.2) (layer "F.Cu") (net 73))
  (arc (start 126.7075 84.697033) (mid 126.614844 84.231221) (end 126.350983 83.836326) (width 0.2) (layer "F.Cu") (net 73))
  (arc (start 126.444828 86.137328) (mid 126.153879 86.331733) (end 125.810681 86.4) (width 0.2) (layer "F.Cu") (net 73))
  (arc (start 124.657195 86.4) (mid 124.833972 86.326777) (end 124.907195 86.15) (width 0.2) (layer "F.Cu") (net 73))
  (segment (start 132.4125 82.8875) (end 132.525 82.775) (width 0.1) (layer "B.Cu") (net 73))
  (segment (start 132.147469 83.583952) (end 132.095711 83.635711) (width 0.1) (layer "B.Cu") (net 73))
  (segment (start 131.602513 83.84) (end 129.00571 83.84) (width 0.1) (layer "B.Cu") (net 73))
  (segment (start 126.056967 83.54231) (end 126.224562 83.709905) (width 0.2) (layer "B.Cu") (net 73))
  (segment (start 132.3 83.159099) (end 132.3 83.215711) (width 0.1) (layer "B.Cu") (net 73))
  (segment (start 126.78006 83.94) (end 128.764289 83.94) (width 0.2) (layer "B.Cu") (net 73))
  (segment (start 125.81769 83.47981) (end 125.906078 83.47981) (width 0.2) (layer "B.Cu") (net 73))
  (arc (start 132.147469 83.583952) (mid 132.260358 83.415001) (end 132.3 83.215711) (width 0.1) (layer "B.Cu") (net 73))
  (arc (start 131.602513 83.84) (mid 131.869429 83.786907) (end 132.095711 83.635711) (width 0.1) (layer "B.Cu") (net 73))
  (arc (start 132.4125 82.8875) (mid 132.329237 83.01211) (end 132.3 83.159099) (width 0.1) (layer "B.Cu") (net 73))
  (arc (start 128.885 83.89) (mid 128.940382 83.852994) (end 129.00571 83.84) (width 0.1) (layer "B.Cu") (net 73))
  (arc (start 126.224562 83.709905) (mid 126.479426 83.8802) (end 126.78006 83.94) (width 0.2) (layer "B.Cu") (net 73))
  (arc (start 128.885 83.89) (mid 128.829617 83.927005) (end 128.764289 83.94) (width 0.1) (layer "B.Cu") (net 73))
  (arc (start 126.056967 83.54231) (mid 125.987738 83.496053) (end 125.906078 83.47981) (width 0.2) (layer "B.Cu") (net 73))
  (segment (start 108.431 80.65) (end 108.431 80.406) (width 0.1) (layer "F.Cu") (net 74))
  (segment (start 108.431 80.406) (end 108.425 80.4) (width 0.1) (layer "F.Cu") (net 74))
  (segment (start 108.431 80.894) (end 108.425 80.9) (width 0.1) (layer "F.Cu") (net 74))
  (segment (start 108.431 80.65) (end 108.431 80.894) (width 0.1) (layer "F.Cu") (net 74))
  (via (at 108.431 80.65) (size 0.45) (drill 0.1) (layers "F.Cu" "B.Cu") (net 74))
  (via (at 107.425 80.665) (size 0.45) (drill 0.1) (layers "F.Cu" "B.Cu") (net 74))
  (segment (start 108.416 80.665) (end 108.431 80.65) (width 0.1) (layer "B.Cu") (net 74))
  (segment (start 107.425 80.665) (end 108.416 80.665) (width 0.1) (layer "B.Cu") (net 74))
  (segment (start 112.225 80.634) (end 112.209 80.65) (width 0.25) (layer "F.Cu") (net 75))
  (segment (start 112.225 80.9) (end 112.225 80.666) (width 0.25) (layer "F.Cu") (net 75))
  (segment (start 112.225 80.666) (end 112.209 80.65) (width 0.25) (layer "F.Cu") (net 75))
  (segment (start 112.225 80.4) (end 112.225 80.634) (width 0.25) (layer "F.Cu") (net 75))
  (via (at 112.209 80.65) (size 0.45) (drill 0.1) (layers "F.Cu" "B.Cu") (net 75))
  (via (at 116.16 85.15) (size 0.45) (drill 0.1) (layers "F.Cu" "B.Cu") (net 75))
  (segment (start 116.249095 86.260905) (end 116.249095 85.239095) (width 0.1) (layer "B.Cu") (net 75))
  (segment (start 115.65 85.15) (end 114.145 86.655) (width 0.1) (layer "B.Cu") (net 75))
  (segment (start 112.209 81.659) (end 112.21 81.66) (width 0.25) (layer "B.Cu") (net 75))
  (segment (start 116.16 85.15) (end 115.65 85.15) (width 0.1) (layer "B.Cu") (net 75))
  (segment (start 116.249095 85.239095) (end 116.16 85.15) (width 0.1) (layer "B.Cu") (net 75))
  (segment (start 112.209 80.65) (end 112.209 81.659) (width 0.25) (layer "B.Cu") (net 75))
  (segment (start 131.742931 87.797016) (end 131.308363 88.231584) (width 0.2) (layer "F.Cu") (net 76))
  (segment (start 132.24 86.596986) (end 132.24 85.211213) (width 0.2) (layer "F.Cu") (net 76))
  (segment (start 132.155 84.565) (end 132.04 84.45) (width 0.1) (layer "F.Cu") (net 76))
  (segment (start 131.245863 88.382473) (end 131.245863 88.470862) (width 0.2) (layer "F.Cu") (net 76))
  (segment (start 132.27 85.138786) (end 132.27 84.842634) (width 0.1) (layer "F.Cu") (net 76))
  (via (at 131.245863 88.470862) (size 0.45) (drill 0.1) (layers "F.Cu" "B.Cu") (net 76))
  (arc (start 131.245863 88.382473) (mid 131.262106 88.300812) (end 131.308363 88.231584) (width 0.2) (layer "F.Cu") (net 76))
  (arc (start 131.742931 87.797016) (mid 132.110815 87.246437) (end 132.24 86.596986) (width 0.2) (layer "F.Cu") (net 76))
  (arc (start 132.27 84.842634) (mid 132.240112 84.692379) (end 132.155 84.565) (width 0.1) (layer "F.Cu") (net 76))
  (arc (start 132.255 85.175) (mid 132.266101 85.158385) (end 132.27 85.138786) (width 0.1) (layer "F.Cu") (net 76))
  (arc (start 132.255 85.175) (mid 132.243898 85.191614) (end 132.24 85.211213) (width 0.1) (layer "F.Cu") (net 76))
  (segment (start 127.2 91.449422) (end 127.2 91.653867) (width 0.2) (layer "B.Cu") (net 76))
  (segment (start 130.152079 89.387868) (end 131.006585 88.533362) (width 0.2) (layer "B.Cu") (net 76))
  (segment (start 127.35 92.016) (end 127.5 92.166) (width 0.2) (layer "B.Cu") (net 76))
  (segment (start 127.920712 90.31213) (end 127.494565 90.738278) (width 0.2) (layer "B.Cu") (net 76))
  (segment (start 131.157474 88.470862) (end 131.245863 88.470862) (width 0.2) (layer "B.Cu") (net 76))
  (arc (start 127.35 92.016) (mid 127.238983 91.849852) (end 127.2 91.653867) (width 0.2) (layer "B.Cu") (net 76))
  (arc (start 127.2 91.449422) (mid 127.276554 91.064553) (end 127.494565 90.738278) (width 0.2) (layer "B.Cu") (net 76))
  (arc (start 131.006585 88.533362) (mid 131.075813 88.487105) (end 131.157474 88.470862) (width 0.2) (layer "B.Cu") (net 76))
  (arc (start 130.152079 89.387868) (mid 129.640199 89.729895) (end 129.036396 89.85) (width 0.2) (layer "B.Cu") (net 76))
  (arc (start 127.920712 90.31213) (mid 128.432592 89.970103) (end 129.036396 89.85) (width 0.2) (layer "B.Cu") (net 76))
  (segment (start 133.47981 90.241421) (end 133.47981 90.32981) (width 0.2) (layer "F.Cu") (net 77))
  (segment (start 133.995 84.565) (end 133.88 84.45) (width 0.1) (layer "F.Cu") (net 77))
  (segment (start 134.11 85.138786) (end 134.11 84.842634) (width 0.1) (layer "F.Cu") (net 77))
  (segment (start 133.779904 89.852937) (end 133.54231 90.090532) (width 0.2) (layer "F.Cu") (net 77))
  (segment (start 134.08 85.211213) (end 134.08 89.128444) (width 0.2) (layer "F.Cu") (net 77))
  (via (at 133.47981 90.32981) (size 0.45) (drill 0.1) (layers "F.Cu" "B.Cu") (net 77))
  (arc (start 133.995 84.565) (mid 134.080112 84.692379) (end 134.11 84.842634) (width 0.1) (layer "F.Cu") (net 77))
  (arc (start 133.779904 89.852937) (mid 134.002007 89.520537) (end 134.08 89.128444) (width 0.2) (layer "F.Cu") (net 77))
  (arc (start 134.11 85.138786) (mid 134.106101 85.158385) (end 134.095 85.175) (width 0.1) (layer "F.Cu") (net 77))
  (arc (start 133.47981 90.241421) (mid 133.496053 90.15976) (end 133.54231 90.090532) (width 0.2) (layer "F.Cu") (net 77))
  (arc (start 134.08 85.211213) (mid 134.083898 85.191614) (end 134.095 85.175) (width 0.1) (layer "F.Cu") (net 77))
  (segment (start 132.2 91.649421) (end 132.2 91.653867) (width 0.2) (layer "B.Cu") (net 77))
  (segment (start 132.35 92.016) (end 132.5 92.166) (width 0.2) (layer "B.Cu") (net 77))
  (segment (start 133.240532 90.39231) (end 132.353144 91.279698) (width 0.2) (layer "B.Cu") (net 77))
  (segment (start 133.391421 90.32981) (end 133.47981 90.32981) (width 0.2) (layer "B.Cu") (net 77))
  (arc (start 132.2 91.653867) (mid 132.238983 91.849852) (end 132.35 92.016) (width 0.2) (layer "B.Cu") (net 77))
  (arc (start 132.353144 91.279698) (mid 132.2398 91.449328) (end 132.2 91.649421) (width 0.2) (layer "B.Cu") (net 77))
  (arc (start 133.240532 90.39231) (mid 133.30976 90.346053) (end 133.391421 90.32981) (width 0.2) (layer "B.Cu") (net 77))
  (segment (start 135.835 84.565) (end 135.72 84.45) (width 0.1) (layer "F.Cu") (net 78))
  (segment (start 135.92 85.211213) (end 135.92 88.045601) (width 0.2) (layer "F.Cu") (net 78))
  (segment (start 135.95 85.138786) (end 135.95 84.842634) (width 0.1) (layer "F.Cu") (net 78))
  (segment (start 136.161516 88.628673) (end 136.340532 88.807689) (width 0.2) (layer "F.Cu") (net 78))
  (segment (start 136.491421 88.87019) (end 136.57981 88.87019) (width 0.2) (layer "F.Cu") (net 78))
  (via (at 136.57981 88.87019) (size 0.45) (drill 0.1) (layers "F.Cu" "B.Cu") (net 78))
  (arc (start 136.491421 88.87019) (mid 136.40976 88.853946) (end 136.340532 88.807689) (width 0.2) (layer "F.Cu") (net 78))
  (arc (start 135.835 84.565) (mid 135.920112 84.692379) (end 135.95 84.842634) (width 0.1) (layer "F.Cu") (net 78))
  (arc (start 135.95 85.138786) (mid 135.946101 85.158385) (end 135.935 85.175) (width 0.1) (layer "F.Cu") (net 78))
  (arc (start 135.92 85.211213) (mid 135.923898 85.191614) (end 135.935 85.175) (width 0.1) (layer "F.Cu") (net 78))
  (arc (start 136.161516 88.628673) (mid 135.982767 88.361157) (end 135.92 88.045601) (width 0.2) (layer "F.Cu") (net 78))
  (segment (start 136.57981 88.958578) (end 136.57981 88.87019) (width 0.2) (layer "B.Cu") (net 78))
  (segment (start 136.326627 91.381216) (end 136.585196 91.122646) (width 0.2) (layer "B.Cu") (net 78))
  (segment (start 136.326627 91.992627) (end 136.5 92.166) (width 0.2) (layer "B.Cu") (net 78))
  (segment (start 136.64231 89.109467) (end 136.775101 89.242258) (width 0.2) (layer "B.Cu") (net 78))
  (segment (start 136.970394 89.713734) (end 136.970394 90.192699) (width 0.2) (layer "B.Cu") (net 78))
  (arc (start 136.2 91.686922) (mid 136.232909 91.521475) (end 136.326627 91.381216) (width 0.2) (layer "B.Cu") (net 78))
  (arc (start 136.2 91.686922) (mid 136.232909 91.852368) (end 136.326627 91.992627) (width 0.2) (layer "B.Cu") (net 78))
  (arc (start 136.970394 89.713734) (mid 136.919638 89.458573) (end 136.775101 89.242258) (width 0.2) (layer "B.Cu") (net 78))
  (arc (start 136.970394 90.192699) (mid 136.870284 90.695983) (end 136.585196 91.122646) (width 0.2) (layer "B.Cu") (net 78))
  (arc (start 136.64231 89.109467) (mid 136.596053 89.040238) (end 136.57981 88.958578) (width 0.2) (layer "B.Cu") (net 78))
  (segment (start 137.985269 86.052426) (end 139.290532 87.357689) (width 0.2) (layer "F.Cu") (net 79))
  (segment (start 139.441421 87.42019) (end 139.52981 87.42019) (width 0.2) (layer "F.Cu") (net 79))
  (segment (start 137.76 85.508578) (end 137.76 85.19) (width 0.2) (layer "F.Cu") (net 79))
  (segment (start 137.79 85.16) (end 137.76 85.19) (width 0.1) (layer "F.Cu") (net 79))
  (segment (start 137.675 84.565) (end 137.56 84.45) (width 0.1) (layer "F.Cu") (net 79))
  (segment (start 137.79 84.842634) (end 137.79 85.16) (width 0.1) (layer "F.Cu") (net 79))
  (via (at 139.52981 87.42019) (size 0.45) (drill 0.1) (layers "F.Cu" "B.Cu") (net 79))
  (arc (start 137.985269 86.052426) (mid 137.818545 85.802906) (end 137.76 85.508578) (width 0.2) (layer "F.Cu") (net 79))
  (arc (start 137.675 84.565) (mid 137.760112 84.692379) (end 137.79 84.842634) (width 0.1) (layer "F.Cu") (net 79))
  (arc (start 139.441421 87.42019) (mid 139.35976 87.403946) (end 139.290532 87.357689) (width 0.2) (layer "F.Cu") (net 79))
  (segment (start 140.35 92.016) (end 140.5 92.166) (width 0.2) (layer "B.Cu") (net 79))
  (segment (start 140.2 91.653867) (end 140.2 88.741052) (width 0.2) (layer "B.Cu") (net 79))
  (segment (start 139.59231 87.659467) (end 139.864905 87.932062) (width 0.2) (layer "B.Cu") (net 79))
  (segment (start 139.52981 87.42019) (end 139.52981 87.508578) (width 0.2) (layer "B.Cu") (net 79))
  (arc (start 139.59231 87.659467) (mid 139.546053 87.590238) (end 139.52981 87.508578) (width 0.2) (layer "B.Cu") (net 79))
  (arc (start 140.2 88.741052) (mid 140.112911 88.303229) (end 139.864905 87.932062) (width 0.2) (layer "B.Cu") (net 79))
  (arc (start 140.2 91.653867) (mid 140.238983 91.849852) (end 140.35 92.016) (width 0.2) (layer "B.Cu") (net 79))
  (segment (start 130.786243 88.011242) (end 130.874631 88.011242) (width 0.2) (layer "F.Cu") (net 80))
  (segment (start 131.84 86.514143) (end 131.84 85.211213) (width 0.2) (layer "F.Cu") (net 80))
  (segment (start 131.81 84.827426) (end 131.81 85.138786) (width 0.1) (layer "F.Cu") (net 80))
  (segment (start 131.02552 87.948741) (end 131.40151 87.572752) (width 0.2) (layer "F.Cu") (net 80))
  (segment (start 131.937573 84.725) (end 131.912426 84.725) (width 0.1) (layer "F.Cu") (net 80))
  (segment (start 132.04 84.827426) (end 132.04 84.91) (width 0.1) (layer "F.Cu") (net 80))
  (via (at 130.786243 88.011242) (size 0.45) (drill 0.1) (layers "F.Cu" "B.Cu") (net 80))
  (arc (start 131.81 84.827426) (mid 131.817796 84.788229) (end 131.84 84.755) (width 0.1) (layer "F.Cu") (net 80))
  (arc (start 131.937573 84.725) (mid 131.97677 84.732796) (end 132.01 84.755) (width 0.1) (layer "F.Cu") (net 80))
  (arc (start 131.912426 84.725) (mid 131.873229 84.732796) (end 131.84 84.755) (width 0.1) (layer "F.Cu") (net 80))
  (arc (start 131.84 86.514143) (mid 131.72604 87.087058) (end 131.40151 87.572752) (width 0.2) (layer "F.Cu") (net 80))
  (arc (start 132.04 84.827426) (mid 132.032203 84.788229) (end 132.01 84.755) (width 0.1) (layer "F.Cu") (net 80))
  (arc (start 131.825 85.175) (mid 131.836101 85.191614) (end 131.84 85.211213) (width 0.1) (layer "F.Cu") (net 80))
  (arc (start 131.02552 87.948741) (mid 130.956291 87.994998) (end 130.874631 88.011242) (width 0.2) (layer "F.Cu") (net 80))
  (arc (start 131.825 85.175) (mid 131.813898 85.158385) (end 131.81 85.138786) (width 0.1) (layer "F.Cu") (net 80))
  (segment (start 130.786243 88.011242) (end 130.786243 88.09963) (width 0.2) (layer "B.Cu") (net 80))
  (segment (start 130.723742 88.250519) (end 129.986393 88.987868) (width 0.2) (layer "B.Cu") (net 80))
  (segment (start 127.755024 89.912131) (end 127.153144 90.514011) (width 0.2) (layer "B.Cu") (net 80))
  (segment (start 126.65 92.016) (end 126.5 92.166) (width 0.2) (layer "B.Cu") (net 80))
  (segment (start 126.8 91.366578) (end 126.8 91.653867) (width 0.2) (layer "B.Cu") (net 80))
  (arc (start 127.755024 89.912131) (mid 128.266904 89.570103) (end 128.870709 89.45) (width 0.2) (layer "B.Cu") (net 80))
  (arc (start 126.8 91.366578) (mid 126.891779 90.905172) (end 127.153144 90.514011) (width 0.2) (layer "B.Cu") (net 80))
  (arc (start 126.65 92.016) (mid 126.761016 91.849852) (end 126.8 91.653867) (width 0.2) (layer "B.Cu") (net 80))
  (arc (start 130.786243 88.09963) (mid 130.769999 88.18129) (end 130.723742 88.250519) (width 0.2) (layer "B.Cu") (net 80))
  (arc (start 128.870709 89.45) (mid 129.474513 89.329895) (end 129.986393 88.987868) (width 0.2) (layer "B.Cu") (net 80))
  (segment (start 133.108578 89.87019) (end 133.02019 89.87019) (width 0.2) (layer "F.Cu") (net 81))
  (segment (start 133.65 84.827426) (end 133.65 85.138786) (width 0.1) (layer "F.Cu") (net 81))
  (segment (start 133.438483 89.628673) (end 133.259466 89.807689) (width 0.2) (layer "F.Cu") (net 81))
  (segment (start 133.88 84.827426) (end 133.88 84.91) (width 0.1) (layer "F.Cu") (net 81))
  (segment (start 133.752426 84.725) (end 133.777573 84.725) (width 0.1) (layer "F.Cu") (net 81))
  (segment (start 133.68 89.045601) (end 133.68 85.211213) (width 0.2) (layer "F.Cu") (net 81))
  (via (at 133.02019 89.87019) (size 0.45) (drill 0.1) (layers "F.Cu" "B.Cu") (net 81))
  (arc (start 133.85 84.755) (mid 133.81677 84.732796) (end 133.777573 84.725) (width 0.1) (layer "F.Cu") (net 81))
  (arc (start 133.752426 84.725) (mid 133.713229 84.732796) (end 133.68 84.755) (width 0.1) (layer "F.Cu") (net 81))
  (arc (start 133.665 85.175) (mid 133.653898 85.158385) (end 133.65 85.138786) (width 0.1) (layer "F.Cu") (net 81))
  (arc (start 133.665 85.175) (mid 133.676101 85.191614) (end 133.68 85.211213) (width 0.1) (layer "F.Cu") (net 81))
  (arc (start 133.68 89.045601) (mid 133.617231 89.361157) (end 133.438483 89.628673) (width 0.2) (layer "F.Cu") (net 81))
  (arc (start 133.88 84.827426) (mid 133.872203 84.788229) (end 133.85 84.755) (width 0.1) (layer "F.Cu") (net 81))
  (arc (start 133.108578 89.87019) (mid 133.190238 89.853946) (end 133.259466 89.807689) (width 0.2) (layer "F.Cu") (net 81))
  (arc (start 133.65 84.827426) (mid 133.657796 84.788229) (end 133.68 84.755) (width 0.1) (layer "F.Cu") (net 81))
  (segment (start 132.011722 91.055433) (end 132.957689 90.109467) (width 0.2) (layer "B.Cu") (net 81))
  (segment (start 131.65 92.016) (end 131.5 92.166) (width 0.2) (layer "B.Cu") (net 81))
  (segment (start 131.8 91.566578) (end 131.8 91.653867) (width 0.2) (layer "B.Cu") (net 81))
  (segment (start 133.02019 89.87019) (end 133.02019 89.958578) (width 0.2) (layer "B.Cu") (net 81))
  (arc (start 131.8 91.566578) (mid 131.855024 91.289948) (end 132.011722 91.055433) (width 0.2) (layer "B.Cu") (net 81))
  (arc (start 131.8 91.653867) (mid 131.761016 91.849852) (end 131.65 92.016) (width 0.2) (layer "B.Cu") (net 81))
  (arc (start 132.957689 90.109467) (mid 133.003946 90.040238) (end 133.02019 89.958578) (width 0.2) (layer "B.Cu") (net 81))
  (segment (start 135.72 84.827426) (end 135.72 84.91) (width 0.1) (layer "F.Cu") (net 82))
  (segment (start 135.820095 88.852938) (end 136.057689 89.090532) (width 0.2) (layer "F.Cu") (net 82))
  (segment (start 135.52 85.211213) (end 135.52 88.128444) (width 0.2) (layer "F.Cu") (net 82))
  (segment (start 135.617573 84.725) (end 135.592426 84.725) (width 0.1) (layer "F.Cu") (net 82))
  (segment (start 135.49 85.138786) (end 135.49 84.827426) (width 0.1) (layer "F.Cu") (net 82))
  (segment (start 136.12019 89.241421) (end 136.12019 89.32981) (width 0.2) (layer "F.Cu") (net 82))
  (via (at 136.12019 89.32981) (size 0.45) (drill 0.1) (layers "F.Cu" "B.Cu") (net 82))
  (arc (start 135.617573 84.725) (mid 135.65677 84.732796) (end 135.69 84.755) (width 0.1) (layer "F.Cu") (net 82))
  (arc (start 135.505 85.175) (mid 135.516101 85.191614) (end 135.52 85.211213) (width 0.1) (layer "F.Cu") (net 82))
  (arc (start 135.820095 88.852938) (mid 135.597992 88.520537) (end 135.52 88.128444) (width 0.2) (layer "F.Cu") (net 82))
  (arc (start 136.12019 89.241421) (mid 136.103946 89.15976) (end 136.057689 89.090532) (width 0.2) (layer "F.Cu") (net 82))
  (arc (start 135.505 85.175) (mid 135.493898 85.158385) (end 135.49 85.138786) (width 0.1) (layer "F.Cu") (net 82))
  (arc (start 135.52 84.755) (mid 135.553229 84.732796) (end 135.592426 84.725) (width 0.1) (layer "F.Cu") (net 82))
  (arc (start 135.52 84.755) (mid 135.497796 84.788229) (end 135.49 84.827426) (width 0.1) (layer "F.Cu") (net 82))
  (arc (start 135.72 84.827426) (mid 135.712203 84.788229) (end 135.69 84.755) (width 0.1) (layer "F.Cu") (net 82))
  (segment (start 136.570394 89.79658) (end 136.570394 90.0875) (width 0.2) (layer "B.Cu") (net 82))
  (segment (start 136.227969 90.914186) (end 135.985206 91.156948) (width 0.2) (layer "B.Cu") (net 82))
  (segment (start 136.12019 89.32981) (end 136.208578 89.32981) (width 0.2) (layer "B.Cu") (net 82))
  (segment (start 135.65 92.016) (end 135.5 92.166) (width 0.2) (layer "B.Cu") (net 82))
  (segment (start 135.8 91.604078) (end 135.8 91.653867) (width 0.2) (layer "B.Cu") (net 82))
  (segment (start 136.43368 89.466524) (end 136.359466 89.39231) (width 0.2) (layer "B.Cu") (net 82))
  (arc (start 135.8 91.604078) (mid 135.848133 91.362093) (end 135.985206 91.156948) (width 0.2) (layer "B.Cu") (net 82))
  (arc (start 136.570394 89.79658) (mid 136.534863 89.617955) (end 136.43368 89.466524) (width 0.2) (layer "B.Cu") (net 82))
  (arc (start 135.65 92.016) (mid 135.761016 91.849852) (end 135.8 91.653867) (width 0.2) (layer "B.Cu") (net 82))
  (arc (start 136.227969 90.914186) (mid 136.4814 90.534899) (end 136.570394 90.0875) (width 0.2) (layer "B.Cu") (net 82))
  (arc (start 136.208578 89.32981) (mid 136.290238 89.346053) (end 136.359466 89.39231) (width 0.2) (layer "B.Cu") (net 82))
  (segment (start 137.457573 84.725) (end 137.432426 84.725) (width 0.1) (layer "F.Cu") (net 83))
  (segment (start 139.07019 87.791421) (end 139.07019 87.87981) (width 0.2) (layer "F.Cu") (net 83))
  (segment (start 137.36 85.591421) (end 137.36 85.19) (width 0.2) (layer "F.Cu") (net 83))
  (segment (start 137.56 84.827426) (end 137.56 84.91) (width 0.1) (layer "F.Cu") (net 83))
  (segment (start 137.33 84.827426) (end 137.33 85.16) (width 0.1) (layer "F.Cu") (net 83))
  (segment (start 137.33 85.16) (end 137.36 85.19) (width 0.1) (layer "F.Cu") (net 83))
  (segment (start 137.643847 86.27669) (end 139.007689 87.640532) (width 0.2) (layer "F.Cu") (net 83))
  (via (at 139.07019 87.87981) (size 0.45) (drill 0.1) (layers "F.Cu" "B.Cu") (net 83))
  (arc (start 137.36 84.755) (mid 137.393229 84.732796) (end 137.432426 84.725) (width 0.1) (layer "F.Cu") (net 83))
  (arc (start 139.07019 87.791421) (mid 139.053946 87.70976) (end 139.007689 87.640532) (width 0.2) (layer "F.Cu") (net 83))
  (arc (start 137.56 84.827426) (mid 137.552203 84.788229) (end 137.53 84.755) (width 0.1) (layer "F.Cu") (net 83))
  (arc (start 137.643847 86.27669) (mid 137.433769 85.962286) (end 137.36 85.591421) (width 0.2) (layer "F.Cu") (net 83))
  (arc (start 137.33 84.827426) (mid 137.337796 84.788229) (end 137.36 84.755) (width 0.1) (layer "F.Cu") (net 83))
  (arc (start 137.457573 84.725) (mid 137.49677 84.732796) (end 137.53 84.755) (width 0.1) (layer "F.Cu") (net 83))
  (segment (start 139.309467 87.94231) (end 139.523483 88.156326) (width 0.2) (layer "B.Cu") (net 83))
  (segment (start 139.158578 87.87981) (end 139.07019 87.87981) (width 0.2) (layer "B.Cu") (net 83))
  (segment (start 139.8 91.653867) (end 139.8 88.823896) (width 0.2) (layer "B.Cu") (net 83))
  (segment (start 139.65 92.016) (end 139.5 92.166) (width 0.2) (layer "B.Cu") (net 83))
  (arc (start 139.158578 87.87981) (mid 139.240238 87.896053) (end 139.309467 87.94231) (width 0.2) (layer "B.Cu") (net 83))
  (arc (start 139.8 88.823896) (mid 139.728135 88.462609) (end 139.523483 88.156326) (width 0.2) (layer "B.Cu") (net 83))
  (arc (start 139.8 91.653867) (mid 139.761016 91.849852) (end 139.65 92.016) (width 0.2) (layer "B.Cu") (net 83))
  (segment (start 109.225 85.725001) (end 109.075 85.575001) (width 0.1) (layer "F.Cu") (net 84))
  (segment (start 108.720545 87.625545) (end 108.968033 87.625545) (width 0.1) (layer "F.Cu") (net 84))
  (segment (start 109.224999 87.368578) (end 109.225 85.725001) (width 0.1) (layer "F.Cu") (net 84))
  (segment (start 109.075 85.575001) (end 109.075 85.05) (width 0.1) (layer "F.Cu") (net 84))
  (segment (start 108.968033 87.625545) (end 109.224999 87.368578) (width 0.1) (layer "F.Cu") (net 84))
  (via (at 108.720545 87.625545) (size 0.45) (drill 0.1) (layers "F.Cu" "B.Cu") (net 84))
  (segment (start 108.720545 87.625545) (end 108.968033 87.625545) (width 0.1) (layer "B.Cu") (net 84))
  (segment (start 108.968033 87.625545) (end 109.303577 87.29) (width 0.1) (layer "B.Cu") (net 84))
  (segment (start 115.96 86.55) (end 116.089289 86.420711) (width 0.1) (layer "B.Cu") (net 84))
  (segment (start 114.878578 87.29) (end 115.618578 86.55) (width 0.1) (layer "B.Cu") (net 84))
  (segment (start 109.303577 87.29) (end 114.878578 87.29) (width 0.1) (layer "B.Cu") (net 84))
  (segment (start 115.618578 86.55) (end 115.96 86.55) (width 0.1) (layer "B.Cu") (net 84))
  (segment (start 109.109455 88.014455) (end 109.109455 87.766967) (width 0.1) (layer "F.Cu") (net 85))
  (segment (start 109.425 85.725001) (end 109.575 85.575001) (width 0.1) (layer "F.Cu") (net 85))
  (segment (start 109.109455 87.766967) (end 109.425 87.451422) (width 0.1) (layer "F.Cu") (net 85))
  (segment (start 109.425 87.451422) (end 109.425 85.725001) (width 0.1) (layer "F.Cu") (net 85))
  (segment (start 109.575 85.575001) (end 109.575 85.05) (width 0.1) (layer "F.Cu") (net 85))
  (via (at 109.109455 88.014455) (size 0.45) (drill 0.1) (layers "F.Cu" "B.Cu") (net 85))
  (segment (start 109.109455 87.766967) (end 109.386422 87.489999) (width 0.1) (layer "B.Cu") (net 85))
  (segment (start 109.386422 87.489999) (end 114.961423 87.489999) (width 0.1) (layer "B.Cu") (net 85))
  (segment (start 109.109455 88.014455) (end 109.109455 87.766967) (width 0.1) (layer "B.Cu") (net 85))
  (segment (start 114.961423 87.489999) (end 115.701422 86.75) (width 0.1) (layer "B.Cu") (net 85))
  (segment (start 115.701422 86.75) (end 115.96 86.75) (width 0.1) (layer "B.Cu") (net 85))
  (segment (start 115.96 86.75) (end 116.070197 86.860197) (width 0.1) (layer "B.Cu") (net 85))
  (segment (start 131.225 81.475) (end 130.9 81.15) (width 0.1) (layer "F.Cu") (net 86))
  (via (at 126.40019 78.77981) (size 0.45) (drill 0.1) (layers "F.Cu" "B.Cu") (net 86))
  (via (at 131.225 81.475) (size 0.45) (drill 0.1) (layers "F.Cu" "B.Cu") (net 86))
  (segment (start 131.35 81.246422) (end 131.35 81.261611) (width 0.13) (layer "In3.Cu") (net 86))
  (segment (start 126.40019 78.77981) (end 126.488578 78.77981) (width 0.13) (layer "In3.Cu") (net 86))
  (segment (start 127.685093 79.887936) (end 126.639467 78.84231) (width 0.13) (layer "In3.Cu") (net 86))
  (segment (start 131.225 81.475) (end 131.2875 81.4125) (width 0.13) (layer "In3.Cu") (net 86))
  (segment (start 129.742156 80.74) (end 130.662302 80.74) (width 0.13) (layer "In3.Cu") (net 86))
  (segment (start 131.148578 80.941422) (end 131.276759 81.069603) (width 0.13) (layer "In3.Cu") (net 86))
  (arc (start 131.148578 80.941422) (mid 130.925472 80.792347) (end 130.662302 80.74) (width 0.13) (layer "In3.Cu") (net 86))
  (arc (start 131.276759 81.069603) (mid 131.330965 81.150728) (end 131.35 81.246422) (width 0.13) (layer "In3.Cu") (net 86))
  (arc (start 126.488578 78.77981) (mid 126.570238 78.796053) (end 126.639467 78.84231) (width 0.13) (layer "In3.Cu") (net 86))
  (arc (start 131.2875 81.4125) (mid 131.333756 81.343271) (end 131.35 81.261611) (width 0.13) (layer "In3.Cu") (net 86))
  (arc (start 129.742156 80.74) (mid 128.628881 80.518555) (end 127.685093 79.887936) (width 0.13) (layer "In3.Cu") (net 86))
  (segment (start 134.481 58.25) (end 134.631 58.1) (width 0.2) (layer "B.Cu") (net 86))
  (segment (start 131.740509 59.076646) (end 127.203792 63.613363) (width 0.2) (layer "B.Cu") (net 86))
  (segment (start 126.337689 78.540532) (end 126.005095 78.207938) (width 0.2) (layer "B.Cu") (net 86))
  (segment (start 134.118867 58.4) (end 133.374078 58.4) (width 0.2) (layer "B.Cu") (net 86))
  (segment (start 126.40019 78.77981) (end 126.40019 78.691421) (width 0.2) (layer "B.Cu") (net 86))
  (segment (start 125.61 77.254094) (end 125.61 67.461119) (width 0.2) (layer "B.Cu") (net 86))
  (arc (start 131.740509 59.076646) (mid 132.489997 58.575854) (end 133.374078 58.4) (width 0.2) (layer "B.Cu") (net 86))
  (arc (start 125.61 67.461119) (mid 126.024213 65.378728) (end 127.203792 63.613363) (width 0.2) (layer "B.Cu") (net 86))
  (arc (start 126.337689 78.540532) (mid 126.383946 78.60976) (end 126.40019 78.691421) (width 0.2) (layer "B.Cu") (net 86))
  (arc (start 134.481 58.25) (mid 134.314852 58.361016) (end 134.118867 58.4) (width 0.2) (layer "B.Cu") (net 86))
  (arc (start 125.61 77.254094) (mid 125.712681 77.77031) (end 126.005095 78.207938) (width 0.2) (layer "B.Cu") (net 86))
  (segment (start 131.875 81.475) (end 131.55 81.15) (width 0.1) (layer "F.Cu") (net 87))
  (via (at 131.875 81.475) (size 0.45) (drill 0.1) (layers "F.Cu" "B.Cu") (net 87))
  (via (at 126.85981 78.32019) (size 0.45) (drill 0.1) (layers "F.Cu" "B.Cu") (net 87))
  (segment (start 131.431422 80.658578) (end 131.618179 80.845335) (width 0.13) (layer "In3.Cu") (net 87))
  (segment (start 131.875 81.475) (end 131.8125 81.4125) (width 0.13) (layer "In3.Cu") (net 87))
  (segment (start 129.907843 80.34) (end 130.662306 80.34) (width 0.13) (layer "In3.Cu") (net 87))
  (segment (start 126.85981 78.408578) (end 126.85981 78.32019) (width 0.13) (layer "In3.Cu") (net 87))
  (segment (start 131.75 81.163578) (end 131.75 81.261611) (width 0.13) (layer "In3.Cu") (net 87))
  (segment (start 126.92231 78.559467) (end 127.850778 79.487935) (width 0.13) (layer "In3.Cu") (net 87))
  (arc (start 131.75 81.163578) (mid 131.71574 80.991346) (end 131.618179 80.845335) (width 0.13) (layer "In3.Cu") (net 87))
  (arc (start 131.431422 80.658578) (mid 131.078548 80.422795) (end 130.662306 80.34) (width 0.13) (layer "In3.Cu") (net 87))
  (arc (start 129.907843 80.34) (mid 128.794567 80.118555) (end 127.850778 79.487935) (width 0.13) (layer "In3.Cu") (net 87))
  (arc (start 126.85981 78.408578) (mid 126.876053 78.490238) (end 126.92231 78.559467) (width 0.13) (layer "In3.Cu") (net 87))
  (arc (start 131.75 81.261611) (mid 131.766243 81.343271) (end 131.8125 81.4125) (width 0.13) (layer "In3.Cu") (net 87))
  (segment (start 126.85981 78.32019) (end 126.771421 78.32019) (width 0.2) (layer "B.Cu") (net 87))
  (segment (start 126.620532 78.257689) (end 126.346516 77.983673) (width 0.2) (layer "B.Cu") (net 87))
  (segment (start 134.118867 58.8) (end 133.456922 58.8) (width 0.2) (layer "B.Cu") (net 87))
  (segment (start 131.964777 59.418066) (end 127.603792 63.779051) (width 0.2) (layer "B.Cu") (net 87))
  (segment (start 126.01 67.626807) (end 126.01 77.17125) (width 0.2) (layer "B.Cu") (net 87))
  (segment (start 134.481 58.95) (end 134.631 59.1) (width 0.2) (layer "B.Cu") (net 87))
  (arc (start 134.118867 58.8) (mid 134.314852 58.838983) (end 134.481 58.95) (width 0.2) (layer "B.Cu") (net 87))
  (arc (start 126.620532 78.257689) (mid 126.68976 78.303946) (end 126.771421 78.32019) (width 0.2) (layer "B.Cu") (net 87))
  (arc (start 126.01 77.17125) (mid 126.097457 77.61093) (end 126.346516 77.983673) (width 0.2) (layer "B.Cu") (net 87))
  (arc (start 126.01 67.626807) (mid 126.424213 65.544416) (end 127.603792 63.779051) (width 0.2) (layer "B.Cu") (net 87))
  (arc (start 131.964777 59.418066) (mid 132.649379 58.96063) (end 133.456922 58.8) (width 0.2) (layer "B.Cu") (net 87))
  (segment (start 107.44 82.365) (end 107.905 81.9) (width 0.1) (layer "F.Cu") (net 88))
  (segment (start 107.44 82.660001) (end 107.44 82.365) (width 0.1) (layer "F.Cu") (net 88))
  (segment (start 107.905 81.9) (end 108.425 81.9) (width 0.1) (layer "F.Cu") (net 88))
  (via (at 103.035 87.05) (size 0.45) (drill 0.1) (layers "F.Cu" "B.Cu") (net 88))
  (via (at 107.44 82.660001) (size 0.45) (drill 0.1) (layers "F.Cu" "B.Cu") (net 88))
  (segment (start 107.425 81.635) (end 107.425 82.645001) (width 0.1) (layer "B.Cu") (net 88))
  (segment (start 107.425 82.645001) (end 107.44 82.660001) (width 0.1) (layer "B.Cu") (net 88))
  (segment (start 104.5 83.9) (end 104.9 83.5) (width 0.1) (layer "B.Cu") (net 88))
  (segment (start 103.035 87.05) (end 103.035 86.945001) (width 0.1) (layer "B.Cu") (net 88))
  (segment (start 106.600001 83.5) (end 107.44 82.660001) (width 0.1) (layer "B.Cu") (net 88))
  (segment (start 104.9 83.5) (end 106.600001 83.5) (width 0.1) (layer "B.Cu") (net 88))
  (segment (start 103.035 86.945001) (end 104.5 85.480001) (width 0.1) (layer "B.Cu") (net 88))
  (segment (start 104.5 85.480001) (end 104.5 83.9) (width 0.1) (layer "B.Cu") (net 88))
  (segment (start 140.19 61.665) (end 140.34 61.515) (width 0.1) (layer "F.Cu") (net 89))
  (segment (start 139.859856 61.665) (end 140.19 61.665) (width 0.1) (layer "F.Cu") (net 89))
  (via (at 140.34 61.515) (size 0.45) (drill 0.1) (layers "F.Cu" "B.Cu") (net 89))
  (segment (start 115.440001 64.516001) (end 115.434 64.51) (width 0.25) (layer "F.Cu") (net 90))
  (segment (start 114.434002 64.436) (end 114.434002 64.164) (width 0.25) (layer "F.Cu") (net 90))
  (segment (start 115.859001 64.436) (end 115.508001 64.436) (width 0.25) (layer "F.Cu") (net 90))
  (segment (start 115.859001 64.436) (end 114.434002 64.436) (width 0.25) (layer "F.Cu") (net 90))
  (segment (start 114.434002 64.164) (end 114.430001 64.16) (width 0.25) (layer "F.Cu") (net 90))
  (segment (start 115.508001 64.436) (end 115.434 64.51) (width 0.25) (layer "F.Cu") (net 90))
  (segment (start 115.440001 64.835001) (end 115.440001 64.516001) (width 0.25) (layer "F.Cu") (net 90))
  (via (at 115.440001 64.835001) (size 0.45) (drill 0.1) (layers "F.Cu" "B.Cu") (net 90))
  (via (at 114.430001 64.16) (size 0.45) (drill 0.1) (layers "F.Cu" "B.Cu") (net 90))
  (segment (start 115.440001 65.131) (end 115.440001 64.835001) (width 0.25) (layer "B.Cu") (net 90))
  (segment (start 108.431 82.67) (end 108.431 82.406) (width 0.1) (layer "F.Cu") (net 91))
  (segment (start 108.431 82.406) (end 108.425 82.4) (width 0.1) (layer "F.Cu") (net 91))
  (segment (start 108.431 82.67) (end 108.431 82.894) (width 0.1) (layer "F.Cu") (net 91))
  (segment (start 108.431 82.894) (end 108.425 82.9) (width 0.1) (layer "F.Cu") (net 91))
  (via (at 108.431 82.67) (size 0.45) (drill 0.1) (layers "F.Cu" "B.Cu") (net 91))
  (segment (start 108.43 81.66) (end 108.43 82.669) (width 0.1) (layer "B.Cu") (net 91))
  (segment (start 108.43 82.669) (end 108.431 82.67) (width 0.1) (layer "B.Cu") (net 91))
  (segment (start 112.225 84.4) (end 112.901 84.399999) (width 0.1) (layer "F.Cu") (net 92))
  (segment (start 112.901 84.399999) (end 113.191 84.689999) (width 0.1) (layer "F.Cu") (net 92))
  (via (at 113.191 84.689999) (size 0.45) (drill 0.1) (layers "F.Cu" "B.Cu") (net 92))
  (segment (start 110.075 79.25) (end 110.075 79.65) (width 0.25) (layer "F.Cu") (net 93))
  (segment (start 110.075 79.65) (end 110.025 79.7) (width 0.25) (layer "F.Cu") (net 93))
  (via (at 110.025 79.7) (size 0.45) (drill 0.1) (layers "F.Cu" "B.Cu") (net 93))
  (segment (start 109.399 79.65) (end 109.975 79.65) (width 0.25) (layer "B.Cu") (net 93))
  (segment (start 109.975 79.65) (end 110.025 79.7) (width 0.25) (layer "B.Cu") (net 93))
  (segment (start 117.360001 64.436) (end 117.379001 64.436) (width 0.25) (layer "F.Cu") (net 94))
  (segment (start 117.379001 64.436) (end 117.540001 64.275) (width 0.25) (layer "F.Cu") (net 94))
  (via (at 117.540001 64.275) (size 0.45) (drill 0.1) (layers "F.Cu" "B.Cu") (net 94))
  (segment (start 118.247001 65.022) (end 118.111001 64.886) (width 0.25) (layer "F.Cu") (net 95))
  (segment (start 118.111001 64.886) (end 116.961001 64.886001) (width 0.25) (layer "F.Cu") (net 95))
  (via (at 118.247001 65.022) (size 0.45) (drill 0.1) (layers "F.Cu" "B.Cu") (net 95))
  (segment (start 118.247001 65.022) (end 118.110001 65.159) (width 0.25) (layer "B.Cu") (net 95))
  (segment (start 118.110001 65.159) (end 117.450001 65.159) (width 0.25) (layer "B.Cu") (net 95))
  (segment (start 110.575 79.25) (end 110.575 79.65) (width 0.25) (layer "F.Cu") (net 96))
  (segment (start 110.575 79.65) (end 110.625 79.7) (width 0.25) (layer "F.Cu") (net 96))
  (via (at 110.625 79.7) (size 0.45) (drill 0.1) (layers "F.Cu" "B.Cu") (net 96))
  (segment (start 110.675 79.65) (end 110.625 79.7) (width 0.25) (layer "B.Cu") (net 96))
  (segment (start 111.241 79.65) (end 110.675 79.65) (width 0.25) (layer "B.Cu") (net 96))
  (via (at 112.225 82.4) (size 0.45) (drill 0.1) (layers "F.Cu" "B.Cu") (net 97))
  (segment (start 112.209 82.67) (end 112.209 82.416001) (width 0.1) (layer "B.Cu") (net 97))
  (segment (start 111.24 81.701) (end 112.209 82.67) (width 0.25) (layer "B.Cu") (net 97))
  (segment (start 111.24 81.66) (end 111.24 81.701) (width 0.25) (layer "B.Cu") (net 97))
  (segment (start 112.209 82.416001) (end 112.225 82.4) (width 0.1) (layer "B.Cu") (net 97))
  (segment (start 157.39 63.85) (end 157.39 64.11) (width 0.1) (layer "F.Cu") (net 98))
  (segment (start 157.39 64.11) (end 157.23 64.27) (width 0.1) (layer "F.Cu") (net 98))
  (via (at 157.23 64.27) (size 0.45) (drill 0.1) (layers "F.Cu" "B.Cu") (net 98))
  (segment (start 156.93 63.97) (end 157.23 64.27) (width 0.1) (layer "B.Cu") (net 98))
  (segment (start 156.926 63.97) (end 156.93 63.97) (width 0.1) (layer "B.Cu") (net 98))
  (segment (start 116.161001 61.921) (end 116.161001 63.686) (width 0.25) (layer "F.Cu") (net 99))
  (segment (start 115.930001 61.69) (end 116.161001 61.921) (width 0.25) (layer "F.Cu") (net 99))
  (via (at 115.930001 61.69) (size 0.45) (drill 0.1) (layers "F.Cu" "B.Cu") (net 99))
  (segment (start 116.425001 62.185) (end 115.930001 61.69) (width 0.25) (layer "B.Cu") (net 99))
  (segment (start 115.939001 61.69) (end 116.435001 61.194) (width 0.25) (layer "B.Cu") (net 99))
  (segment (start 116.425001 61.206) (end 116.436001 61.195) (width 0.25) (layer "B.Cu") (net 99))
  (segment (start 116.425001 62.205) (end 116.425001 62.185) (width 0.25) (layer "B.Cu") (net 99))
  (segment (start 116.435001 61.194) (end 116.435001 60.195) (width 0.25) (layer "B.Cu") (net 99))
  (segment (start 116.425001 62.205) (end 116.425001 61.206) (width 0.25) (layer "B.Cu") (net 99))
  (segment (start 115.930001 61.69) (end 115.939001 61.69) (width 0.25) (layer "B.Cu") (net 99))
  (segment (start 121.1 62.8) (end 121.1 62.05) (width 0.1) (layer "F.Cu") (net 100))
  (segment (start 121.4 61.75) (end 123.92 61.75) (width 0.1) (layer "F.Cu") (net 100))
  (segment (start 121.1 62.05) (end 121.4 61.75) (width 0.1) (layer "F.Cu") (net 100))
  (segment (start 125.4 60.27) (end 125.4 59.99) (width 0.1) (layer "F.Cu") (net 100))
  (segment (start 123.92 61.75) (end 125.4 60.27) (width 0.1) (layer "F.Cu") (net 100))
  (segment (start 121.15 62.75) (end 121.1 62.8) (width 0.1) (layer "F.Cu") (net 100))
  (segment (start 125.5 62.75) (end 121.15 62.75) (width 0.1) (layer "F.Cu") (net 100))
  (via (at 118.830001 59.1125) (size 0.45) (drill 0.1) (layers "F.Cu" "B.Cu") (net 100))
  (segment (start 118.487501 59.1125) (end 118.830001 59.1125) (width 0.25) (layer "B.Cu") (net 100))
  (segment (start 117.404001 60.196) (end 117.405001 60.195) (width 0.25) (layer "B.Cu") (net 100))
  (segment (start 117.404001 61.195) (end 117.404001 60.196) (width 0.25) (layer "B.Cu") (net 100))
  (segment (start 117.405001 60.195) (end 118.487501 59.1125) (width 0.25) (layer "B.Cu") (net 100))
  (segment (start 155.1 63.85) (end 154.89 63.85) (width 0.1) (layer "F.Cu") (net 101))
  (segment (start 155.22 63.97) (end 155.1 63.85) (width 0.1) (layer "F.Cu") (net 101))
  (via (at 155.22 63.97) (size 0.45) (drill 0.1) (layers "F.Cu" "B.Cu") (net 101))
  (segment (start 154.856 63.97) (end 155.22 63.97) (width 0.1) (layer "B.Cu") (net 101))
  (segment (start 154.164 64.85) (end 153.914 65.1) (width 0.1) (layer "F.Cu") (net 102))
  (segment (start 154.39 64.85) (end 154.164 64.85) (width 0.1) (layer "F.Cu") (net 102))
  (via (at 153.914 65.1) (size 0.45) (drill 0.1) (layers "F.Cu" "B.Cu") (net 102))
  (segment (start 154.89 60.35) (end 154.89 59.95) (width 0.1) (layer "F.Cu") (net 103))
  (segment (start 154.89 59.95) (end 154.68 59.74) (width 0.1) (layer "F.Cu") (net 103))
  (via (at 154.68 59.74) (size 0.45) (drill 0.1) (layers "F.Cu" "B.Cu") (net 103))
  (segment (start 154.39 62.35) (end 153.95 62.35) (width 0.1) (layer "F.Cu") (net 104))
  (segment (start 153.95 62.35) (end 153.89 62.29) (width 0.1) (layer "F.Cu") (net 104))
  (via (at 153.89 62.29) (size 0.45) (drill 0.1) (layers "F.Cu" "B.Cu") (net 104))
  (segment (start 153.894 61.97) (end 153.894 62.286) (width 0.1) (layer "B.Cu") (net 104))
  (segment (start 153.894 62.286) (end 153.89 62.29) (width 0.1) (layer "B.Cu") (net 104))
  (segment (start 133.5 81.8) (end 133.175 81.475) (width 0.1) (layer "F.Cu") (net 105))
  (segment (start 133.5 81.15) (end 133.175 81.475) (width 0.1) (layer "F.Cu") (net 105))
  (segment (start 133.5 81.8) (end 133.175 82.125) (width 0.1) (layer "F.Cu") (net 105))
  (via (at 133.175 81.475) (size 0.45) (drill 0.1) (layers "F.Cu" "B.Cu") (net 105))
  (via (at 133.175 82.125) (size 0.45) (drill 0.1) (layers "F.Cu" "B.Cu") (net 105))
  (segment (start 133.175 81.475) (end 133.175 82.125) (width 0.25) (layer "B.Cu") (net 105))
  (segment (start 133.175 82.125) (end 133.175 82.775) (width 0.25) (layer "B.Cu") (net 105))
  (segment (start 133.175 82.775) (end 133.175 83.116) (width 0.25) (layer "B.Cu") (net 105))
  (segment (start 133.175 83.116) (end 133.325 83.266) (width 0.25) (layer "B.Cu") (net 105))
  (segment (start 133.175 81.475) (end 133.334 81.634) (width 0.25) (layer "B.Cu") (net 105))
  (segment (start 133.325 83.266) (end 133.325 82.134) (width 0.25) (layer "B.Cu") (net 105))
  (segment (start 133.325 82.134) (end 133.334 82.125) (width 0.25) (layer "B.Cu") (net 105))
  (segment (start 133.334 81.634) (end 133.334 82.125) (width 0.25) (layer "B.Cu") (net 105))
  (segment (start 134.8 77.9) (end 135.125 77.575) (width 0.1) (layer "F.Cu") (net 106))
  (segment (start 132.2 79.2) (end 132.525 79.525) (width 0.1) (layer "F.Cu") (net 106))
  (segment (start 135.45 77.25) (end 135.125 76.925) (width 0.1) (layer "F.Cu") (net 106))
  (segment (start 135.45 77.9) (end 135.125 77.575) (width 0.1) (layer "F.Cu") (net 106))
  (segment (start 132.2 80.5) (end 132.525 80.175) (width 0.1) (layer "F.Cu") (net 106))
  (segment (start 135.45 79.85) (end 135.125 79.525) (width 0.1) (layer "F.Cu") (net 106))
  (segment (start 132.2 79.85) (end 131.875 80.175) (width 0.1) (layer "F.Cu") (net 106))
  (segment (start 132.2 80.5) (end 131.875 80.175) (width 0.1) (layer "F.Cu") (net 106))
  (segment (start 132.85 79.85) (end 132.525 80.175) (width 0.1) (layer "F.Cu") (net 106))
  (segment (start 132.2 79.85) (end 131.875 79.525) (width 0.1) (layer "F.Cu") (net 106))
  (segment (start 132.2 79.85) (end 132.525 80.175) (width 0.1) (layer "F.Cu") (net 106))
  (segment (start 132.2 79.2) (end 131.875 79.525) (width 0.1) (layer "F.Cu") (net 106))
  (segment (start 132.85 79.85) (end 132.525 79.525) (width 0.1) (layer "F.Cu") (net 106))
  (segment (start 134.8 77.25) (end 135.125 77.575) (width 0.1) (layer "F.Cu") (net 106))
  (segment (start 134.8 77.25) (end 135.125 76.925) (width 0.1) (layer "F.Cu") (net 106))
  (segment (start 132.2 79.85) (end 132.525 79.525) (width 0.1) (layer "F.Cu") (net 106))
  (segment (start 135.45 77.25) (end 135.125 77.575) (width 0.1) (layer "F.Cu") (net 106))
  (segment (start 135.45 79.2) (end 135.125 79.525) (width 0.1) (layer "F.Cu") (net 106))
  (segment (start 132.85 79.2) (end 132.525 79.525) (width 0.1) (layer "F.Cu") (net 106))
  (via (at 131.875 79.525) (size 0.45) (drill 0.1) (layers "F.Cu" "B.Cu") (net 106))
  (via (at 135.125 76.925) (size 0.45) (drill 0.1) (layers "F.Cu" "B.Cu") (net 106))
  (via (at 132.525 79.525) (size 0.45) (drill 0.1) (layers "F.Cu" "B.Cu") (net 106))
  (via (at 132.525 80.175) (size 0.45) (drill 0.1) (layers "F.Cu" "B.Cu") (net 106))
  (via (at 131.875 80.175) (size 0.45) (drill 0.1) (layers "F.Cu" "B.Cu") (net 106))
  (via (at 135.125 77.575) (size 0.45) (drill 0.1) (layers "F.Cu" "B.Cu") (net 106))
  (via (at 135.125 79.525) (size 0.45) (drill 0.1) (layers "F.Cu" "B.Cu") (net 106))
  (segment (start 131.875 80.175) (end 131.5765 80.4735) (width 0.25) (layer "B.Cu") (net 106))
  (segment (start 135.284 79.684) (end 135.284 79.85) (width 0.25) (layer "B.Cu") (net 106))
  (segment (start 131.384 80.666) (end 131.384 80.825) (width 0.25) (layer "B.Cu") (net 106))
  (segment (start 131.5765 79.8235) (end 131.5765 80.4735) (width 0.25) (layer "B.Cu") (net 106))
  (segment (start 131.875 79.525) (end 132.525 80.175) (width 0.25) (layer "B.Cu") (net 106))
  (segment (start 132.525 79.525) (end 131.875 79.525) (width 0.25) (layer "B.Cu") (net 106))
  (segment (start 132.525 80.175) (end 131.875 80.175) (width 0.25) (layer "B.Cu") (net 106))
  (segment (start 135.125 76.925) (end 135.125 77.575) (width 0.25) (layer "B.Cu") (net 106))
  (segment (start 131.875 79.68) (end 131.705 79.85) (width 0.25) (layer "B.Cu") (net 106))
  (segment (start 131.709 79.525) (end 131.384 79.85) (width 0.25) (layer "B.Cu") (net 106))
  (segment (start 131.875 79.525) (end 132.041 79.525) (width 0.25) (layer "B.Cu") (net 106))
  (segment (start 135.284 77.9) (end 135.284 76.925) (width 0.25) (layer "B.Cu") (net 106))
  (segment (start 131.5765 80.4735) (end 131.384 80.666) (width 0.25) (layer "B.Cu") (net 106))
  (segment (start 131.875 80.175) (end 131.875 80.02) (width 0.25) (layer "B.Cu") (net 106))
  (segment (start 131.875 79.525) (end 131.709 79.525) (width 0.25) (layer "B.Cu") (net 106))
  (segment (start 132.525 79.525) (end 131.875 80.175) (width 0.25) (layer "B.Cu") (net 106))
  (segment (start 131.875 80.175) (end 131.709 80.175) (width 0.25) (layer "B.Cu") (net 106))
  (segment (start 131.875 80.02) (end 131.705 79.85) (width 0.25) (layer "B.Cu") (net 106))
  (segment (start 131.705 79.85) (end 132.366 79.85) (width 0.25) (layer "B.Cu") (net 106))
  (segment (start 135.125 77.741) (end 135.284 77.9) (width 0.25) (layer "B.Cu") (net 106))
  (segment (start 135.125 76.925) (end 135.284 76.925) (width 0.25) (layer "B.Cu") (net 106))
  (segment (start 131.709 80.175) (end 131.384 79.85) (width 0.25) (layer "B.Cu") (net 106))
  (segment (start 132.041 79.525) (end 132.366 79.85) (width 0.25) (layer "B.Cu") (net 106))
  (segment (start 135.125 79.525) (end 135.284 79.684) (width 0.25) (layer "B.Cu") (net 106))
  (segment (start 135.125 77.575) (end 135.125 77.741) (width 0.25) (layer "B.Cu") (net 106))
  (segment (start 131.384 80.825) (end 131.384 79.85) (width 0.25) (layer "B.Cu") (net 106))
  (segment (start 131.875 79.525) (end 131.5765 79.8235) (width 0.25) (layer "B.Cu") (net 106))
  (segment (start 131.384 79.85) (end 131.705 79.85) (width 0.25) (layer "B.Cu") (net 106))
  (segment (start 131.875 79.525) (end 131.875 79.68) (width 0.25) (layer "B.Cu") (net 106))
  (segment (start 133.5 77.900001) (end 133.825 78.225) (width 0.1) (layer "F.Cu") (net 107))
  (segment (start 133.5 78.55) (end 133.175 78.875) (width 0.1) (layer "F.Cu") (net 107))
  (segment (start 133.5 79.85) (end 133.5 79.2) (width 0.1) (layer "F.Cu") (net 107))
  (segment (start 133.5 78.55) (end 133.175 78.225) (width 0.1) (layer "F.Cu") (net 107))
  (segment (start 133.5 78.550001) (end 133.825 78.875) (width 0.1) (layer "F.Cu") (net 107))
  (segment (start 133.5 78.55) (end 133.825 78.225) (width 0.1) (layer "F.Cu") (net 107))
  (segment (start 133.5 79.2) (end 133.175 78.875) (width 0.1) (layer "F.Cu") (net 107))
  (segment (start 133.5 77.9) (end 133.175 78.225) (width 0.1) (layer "F.Cu") (net 107))
  (segment (start 133.5 79.2) (end 133.825 78.875) (width 0.1) (layer "F.Cu") (net 107))
  (via (at 133.175 78.875) (size 0.45) (drill 0.1) (layers "F.Cu" "B.Cu") (net 107))
  (via (at 131.225 78.225) (size 0.45) (drill 0.1) (layers "F.Cu" "B.Cu") (net 107))
  (via (at 133.175 78.225) (size 0.45) (drill 0.1) (layers "F.Cu" "B.Cu") (net 107))
  (via (at 131.225 78.875) (size 0.45) (drill 0.1) (layers "F.Cu" "B.Cu") (net 107))
  (segment (start 133.175 78.875) (end 133.175 78.225) (width 0.25) (layer "B.Cu") (net 107))
  (segment (start 133.334 78.875) (end 133.334 77.9) (width 0.25) (layer "B.Cu") (net 107))
  (segment (start 131.384 78.875) (end 131.384 77.9) (width 0.25) (layer "B.Cu") (net 107))
  (segment (start 131.225 78.875) (end 131.225 78.225) (width 0.25) (layer "B.Cu") (net 107))
  (segment (start 135.45 83.1) (end 135.125 82.775) (width 0.1) (layer "F.Cu") (net 108))
  (segment (start 134.8 82.45) (end 135.125 82.775) (width 0.1) (layer "F.Cu") (net 108))
  (segment (start 135.45 82.45) (end 135.125 82.775) (width 0.1) (layer "F.Cu") (net 108))
  (segment (start 134.8 81.8) (end 134.15 82.45) (width 0.1) (layer "F.Cu") (net 108))
  (segment (start 134.8 81.8) (end 134.475 81.475) (width 0.1) (layer "F.Cu") (net 108))
  (segment (start 134.475 80.825) (end 134.8 80.5) (width 0.1) (layer "F.Cu") (net 108))
  (segment (start 134.8 81.15) (end 134.475 81.475) (width 0.1) (layer "F.Cu") (net 108))
  (segment (start 134.15 83.1) (end 134.8 82.45) (width 0.1) (layer "F.Cu") (net 108))
  (segment (start 135.45 82.45) (end 134.8 81.8) (width 0.1) (layer "F.Cu") (net 108))
  (segment (start 135.45 83.1) (end 135.125 83.425) (width 0.1) (layer "F.Cu") (net 108))
  (segment (start 134.8 81.15) (end 134.475 80.825) (width 0.1) (layer "F.Cu") (net 108))
  (segment (start 134.15 82.45) (end 134.475 82.775) (width 0.1) (layer "F.Cu") (net 108))
  (segment (start 134.8 82.45) (end 135.125 82.125) (width 0.1) (layer "F.Cu") (net 108))
  (segment (start 134.8 82.45) (end 134.475 82.125) (width 0.1) (layer "F.Cu") (net 108))
  (via (at 134.475 81.475) (size 0.45) (drill 0.1) (layers "F.Cu" "B.Cu") (net 108))
  (via (at 134.475 80.825) (size 0.45) (drill 0.1) (layers "F.Cu" "B.Cu") (net 108))
  (via (at 135.125 82.775) (size 0.45) (drill 0.1) (layers "F.Cu" "B.Cu") (net 108))
  (via (at 135.125 83.425) (size 0.45) (drill 0.1) (layers "F.Cu" "B.Cu") (net 108))
  (segment (start 134.445 81.94) (end 134.51266 81.94) (width 0.5) (layer "B.Cu") (net 108))
  (segment (start 134.475 81.475) (end 134.475 80.825) (width 0.25) (layer "B.Cu") (net 108))
  (segment (start 134.51266 81.94) (end 135.28 82.70734) (width 0.5) (layer "B.Cu") (net 108))
  (segment (start 135.125 84.566) (end 135.284 84.725) (width 0.25) (layer "B.Cu") (net 108))
  (segment (start 134.316 80.825) (end 134.316 81.675) (width 0.25) (layer "B.Cu") (net 108))
  (segment (start 135.125 83.425) (end 135.125 84.566) (width 0.25) (layer "B.Cu") (net 108))
  (segment (start 134.475 80.825) (end 134.475 81.766) (width 0.25) (layer "B.Cu") (net 108))
  (segment (start 135.284 82.775) (end 135.284 84.725) (width 0.25) (layer "B.Cu") (net 108))
  (segment (start 135.284 82.775) (end 135.284 83.75) (width 0.25) (layer "B.Cu") (net 108))
  (segment (start 134.475 81.475) (end 134.475 81.712795) (width 0.25) (layer "B.Cu") (net 108))
  (segment (start 135.28 82.70734) (end 135.28 82.775) (width 0.5) (layer "B.Cu") (net 108))
  (segment (start 134.441 81.8) (end 134.441 81.932) (width 0.25) (layer "B.Cu") (net 108))
  (segment (start 135.284 82.521795) (end 135.284 82.775) (width 0.25) (layer "B.Cu") (net 108))
  (segment (start 134.475 81.766) (end 134.441 81.8) (width 0.25) (layer "B.Cu") (net 108))
  (segment (start 135.125 83.425) (end 135.125 82.775) (width 0.25) (layer "B.Cu") (net 108))
  (segment (start 134.316 81.675) (end 134.441 81.8) (width 0.25) (layer "B.Cu") (net 108))
  (segment (start 135.284 84.725) (end 135.284 83.75) (width 0.25) (layer "B.Cu") (net 108))
  (segment (start 134.445 81.8) (end 134.445 81.94) (width 0.1) (layer "B.Cu") (net 108))
  (segment (start 135.76926 81.48074) (end 135.45 81.8) (width 0.1) (layer "F.Cu") (net 109))
  (segment (start 136.43074 81.48074) (end 135.76926 81.48074) (width 0.1) (layer "F.Cu") (net 109))
  (via (at 136.43074 81.48074) (size 0.45) (drill 0.1) (layers "F.Cu" "B.Cu") (net 109))
  (segment (start 136.275 80.834) (end 136.275 81.325) (width 0.25) (layer "B.Cu") (net 109))
  (segment (start 136.275 81.325) (end 136.43074 81.48074) (width 0.25) (layer "B.Cu") (net 109))
  (segment (start 136.1 81.8) (end 136.425 82.125) (width 0.1) (layer "F.Cu") (net 110))
  (via (at 136.425 82.125) (size 0.45) (drill 0.1) (layers "F.Cu" "B.Cu") (net 110))
  (segment (start 136.425 82.641) (end 136.275 82.791) (width 0.25) (layer "B.Cu") (net 110))
  (segment (start 136.425 82.125) (end 136.425 82.641) (width 0.25) (layer "B.Cu") (net 110))
  (segment (start 133.5 77.25) (end 133.175 76.925) (width 0.1) (layer "F.Cu") (net 111))
  (via (at 133.175 76.925) (size 0.45) (drill 0.1) (layers "F.Cu" "B.Cu") (net 111))
  (segment (start 137.4 79.2) (end 137.08 78.88) (width 0.1) (layer "F.Cu") (net 112))
  (segment (start 134.8 78.55) (end 135.125 78.875) (width 0.1) (layer "F.Cu") (net 112))
  (segment (start 137.4 80.5) (end 137.725 80.825) (width 0.1) (layer "F.Cu") (net 112))
  (segment (start 137.4 80.5) (end 138.05 79.85) (width 0.1) (layer "F.Cu") (net 112))
  (segment (start 136.3755 78.8255) (end 136.392296 78.8255) (width 0.1) (layer "F.Cu") (net 112))
  (segment (start 136.1 78.55) (end 136.3755 78.8255) (width 0.1) (layer "F.Cu") (net 112))
  (segment (start 145.3 69.9) (end 145.3 70.05) (width 0.1) (layer "F.Cu") (net 112))
  (segment (start 135.125 78.875) (end 135.45 78.55) (width 0.1) (layer "F.Cu") (net 112))
  (segment (start 137.725 80.825) (end 138.05 80.5) (width 0.1) (layer "F.Cu") (net 112))
  (segment (start 137.4 80.5) (end 137.075 80.825) (width 0.1) (layer "F.Cu") (net 112))
  (segment (start 136.1 78.55) (end 135.775 78.875) (width 0.1) (layer "F.Cu") (net 112))
  (segment (start 146.5 66) (end 145.7 66.8) (width 0.1) (layer "F.Cu") (net 112))
  (segment (start 145.7 66.8) (end 145.7 69.5) (width 0.1) (layer "F.Cu") (net 112))
  (segment (start 138.05 79.85) (end 137.4 79.2) (width 0.1) (layer "F.Cu") (net 112))
  (segment (start 145.7 69.5) (end 145.3 69.9) (width 0.1) (layer "F.Cu") (net 112))
  (segment (start 137.08 78.88) (end 136.446796 78.88) (width 0.1) (layer "F.Cu") (net 112))
  (segment (start 137.4 79.85) (end 137.725 79.525) (width 0.1) (layer "F.Cu") (net 112))
  (segment (start 138.05 80.5) (end 138.375 80.825) (width 0.1) (layer "F.Cu") (net 112))
  (segment (start 144.95 70.4) (end 144.8 70.4) (width 0.1) (layer "F.Cu") (net 112))
  (segment (start 137.4 81.15) (end 137.075 80.825) (width 0.1) (layer "F.Cu") (net 112))
  (segment (start 138.05 80.5) (end 137.4 79.85) (width 0.1) (layer "F.Cu") (net 112))
  (segment (start 145.3 70.05) (end 144.95 70.4) (width 0.1) (layer "F.Cu") (net 112))
  (segment (start 136.446796 78.88) (end 136.392296 78.8255) (width 0.1) (layer "F.Cu") (net 112))
  (segment (start 135.45 78.55) (end 135.775 78.875) (width 0.1) (layer "F.Cu") (net 112))
  (segment (start 137.4 81.15) (end 137.725 80.825) (width 0.1) (layer "F.Cu") (net 112))
  (via (at 143.3 71.6) (size 0.45) (drill 0.1) (layers "F.Cu" "B.Cu") (net 112))
  (via (at 144.8 71.6) (size 0.45) (drill 0.1) (layers "F.Cu" "B.Cu") (net 112))
  (via (at 142.5 70.4) (size 0.45) (drill 0.1) (layers "F.Cu" "B.Cu") (net 112))
  (via (at 144 71.6) (size 0.45) (drill 0.1) (layers "F.Cu" "B.Cu") (net 112))
  (via (at 135.125 78.875) (size 0.45) (drill 0.1) (layers "F.Cu" "B.Cu") (net 112))
  (via (at 138.375 80.825) (size 0.45) (drill 0.1) (layers "F.Cu" "B.Cu") (net 112))
  (via (at 144 70.4) (size 0.45) (drill 0.1) (layers "F.Cu" "B.Cu") (net 112))
  (via (at 137.075 80.825) (size 0.45) (drill 0.1) (layers "F.Cu" "B.Cu") (net 112))
  (via (at 136.392296 78.8255) (size 0.45) (drill 0.1) (layers "F.Cu" "B.Cu") (net 112))
  (via (at 135.775 78.875) (size 0.45) (drill 0.1) (layers "F.Cu" "B.Cu") (net 112))
  (via (at 143.3 70.4) (size 0.45) (drill 0.1) (layers "F.Cu" "B.Cu") (net 112))
  (via (at 144.8 70.4) (size 0.45) (drill 0.1) (layers "F.Cu" "B.Cu") (net 112))
  (via (at 142.5 71.6) (size 0.45) (drill 0.1) (layers "F.Cu" "B.Cu") (net 112))
  (via (at 137.725 80.825) (size 0.45) (drill 0.1) (layers "F.Cu" "B.Cu") (net 112))
  (segment (start 139.175 80.816) (end 138.2 80.816) (width 0.25) (layer "B.Cu") (net 112))
  (segment (start 138.2 80.816) (end 137.225 80.816) (width 0.25) (layer "B.Cu") (net 112))
  (segment (start 144.855 70.455) (end 144.8 70.4) (width 0.1) (layer "B.Cu") (net 112))
  (segment (start 146.5 70.455) (end 144.855 70.455) (width 0.1) (layer "B.Cu") (net 112))
  (segment (start 137.075 82.775) (end 137.4 82.45) (width 0.1) (layer "F.Cu") (net 113))
  (segment (start 136.75 79.2) (end 137.075 79.525) (width 0.1) (layer "F.Cu") (net 113))
  (segment (start 136.75 79.2) (end 136.1 79.2) (width 0.1) (layer "F.Cu") (net 113))
  (segment (start 136.75 82.45) (end 137.075 82.775) (width 0.1) (layer "F.Cu") (net 113))
  (via (at 140.4 79.35) (size 0.45) (drill 0.1) (layers "F.Cu" "B.Cu") (net 113))
  (via (at 137.075 79.525) (size 0.45) (drill 0.1) (layers "F.Cu" "B.Cu") (net 113))
  (via (at 137.075 82.775) (size 0.45) (drill 0.1) (layers "F.Cu" "B.Cu") (net 113))
  (segment (start 140.4 79.612001) (end 140.16 79.852001) (width 0.25) (layer "B.Cu") (net 113))
  (segment (start 140.4 79.094) (end 140.16 78.854) (width 0.25) (layer "B.Cu") (net 113))
  (segment (start 137.241 79.85) (end 137.241 79.691) (width 0.25) (layer "B.Cu") (net 113))
  (segment (start 140.4 79.35) (end 140.4 79.612001) (width 0.25) (layer "B.Cu") (net 113))
  (segment (start 137.241 79.691) (end 137.075 79.525) (width 0.25) (layer "B.Cu") (net 113))
  (segment (start 140.4 79.35) (end 140.4 79.094) (width 0.25) (layer "B.Cu") (net 113))
  (segment (start 137.241 82.725) (end 137.125 82.725) (width 0.25) (layer "B.Cu") (net 113))
  (segment (start 137.125 82.725) (end 137.075 82.775) (width 0.25) (layer "B.Cu") (net 113))
  (segment (start 133.5 80.5) (end 133.175 80.825) (width 0.1) (layer "F.Cu") (net 114))
  (via (at 133.175 80.825) (size 0.45) (drill 0.1) (layers "F.Cu" "B.Cu") (net 114))
  (via (at 127.505 80.824) (size 0.45) (drill 0.1) (layers "F.Cu" "B.Cu") (net 114))
  (segment (start 127.506 80.825) (end 133.175 80.825) (width 0.4) (layer "In2.Cu") (net 114))
  (segment (start 127.505 80.824) (end 127.506 80.825) (width 0.4) (layer "In2.Cu") (net 114))
  (segment (start 127.505 80.824) (end 128.48 80.824) (width 0.4) (layer "B.Cu") (net 114))
  (segment (start 127.815 81.489) (end 128.48 80.824) (width 0.4) (layer "B.Cu") (net 114))
  (segment (start 127.815 82.04) (end 127.815 81.134) (width 0.4) (layer "B.Cu") (net 114))
  (segment (start 127.815 81.134) (end 127.505 80.824) (width 0.4) (layer "B.Cu") (net 114))
  (segment (start 127.815 82.04) (end 127.815 81.489) (width 0.4) (layer "B.Cu") (net 114))
  (segment (start 123.128 78.598) (end 123.325 78.795) (width 0.1) (layer "F.Cu") (net 115))
  (segment (start 123.325 78.795) (end 123.325 79.2) (width 0.1) (layer "F.Cu") (net 115))
  (segment (start 124.099 75.171) (end 123.997 75.171) (width 0.1) (layer "F.Cu") (net 115))
  (segment (start 123.128 76.04) (end 123.128 78.598) (width 0.1) (layer "F.Cu") (net 115))
  (segment (start 123.997 75.171) (end 123.128 76.04) (width 0.1) (layer "F.Cu") (net 115))
  (via (at 124.099 75.171) (size 0.45) (drill 0.1) (layers "F.Cu" "B.Cu") (net 115))
  (segment (start 124.098 75.17) (end 124.099 75.171) (width 0.25) (layer "B.Cu") (net 115))
  (segment (start 123.482 75.17) (end 124.098 75.17) (width 0.25) (layer "B.Cu") (net 115))
  (segment (start 122.675 78.795) (end 122.87 78.6) (width 0.1) (layer "F.Cu") (net 116))
  (segment (start 122.738 76.32) (end 122.548 76.32) (width 0.1) (layer "F.Cu") (net 116))
  (segment (start 122.868 78.598) (end 122.87 78.6) (width 0.1) (layer "F.Cu") (net 116))
  (segment (start 122.868 76.45) (end 122.868 78.598) (width 0.1) (layer "F.Cu") (net 116))
  (segment (start 122.868 76.45) (end 122.738 76.32) (width 0.1) (layer "F.Cu") (net 116))
  (segment (start 121.898 76.97) (end 121.799 76.97) (width 0.1) (layer "F.Cu") (net 116))
  (segment (start 122.548 76.32) (end 121.898 76.97) (width 0.1) (layer "F.Cu") (net 116))
  (segment (start 122.675 79.2) (end 122.675 78.795) (width 0.1) (layer "F.Cu") (net 116))
  (via (at 121.799 76.97) (size 0.45) (drill 0.1) (layers "F.Cu" "B.Cu") (net 116))
  (segment (start 122.514 76.97) (end 121.799 76.97) (width 0.25) (layer "B.Cu") (net 116))
  (segment (start 144.944277 90.248425) (end 144.885852 90.19) (width 0.1) (layer "F.Cu") (net 117))
  (segment (start 143.62 90.19) (end 141.76 88.33) (width 0.1) (layer "F.Cu") (net 117))
  (segment (start 141.76 88.33) (end 141.76 86.53) (width 0.1) (layer "F.Cu") (net 117))
  (segment (start 141.76 86.53) (end 140.71 85.48) (width 0.1) (layer "F.Cu") (net 117))
  (segment (start 138.96 85.48) (end 138.71 85.23) (width 0.1) (layer "F.Cu") (net 117))
  (segment (start 144.885852 90.19) (end 143.62 90.19) (width 0.1) (layer "F.Cu") (net 117))
  (segment (start 138.71 85.23) (end 138.71 84.68) (width 0.1) (layer "F.Cu") (net 117))
  (segment (start 140.71 85.48) (end 138.96 85.48) (width 0.1) (layer "F.Cu") (net 117))
  (segment (start 138.71 84.68) (end 138.48 84.45) (width 0.1) (layer "F.Cu") (net 117))
  (via (at 144.944277 90.248425) (size 0.45) (drill 0.1) (layers "F.Cu" "B.Cu") (net 117))
  (segment (start 144.65083 90.543291) (end 144.65083 90.541872) (width 0.1) (layer "B.Cu") (net 117))
  (segment (start 144.65083 90.541872) (end 144.944277 90.248425) (width 0.1) (layer "B.Cu") (net 117))
  (segment (start 141.27 89.118319) (end 141.27 86.63) (width 0.1) (layer "F.Cu") (net 118))
  (segment (start 141.27 86.63) (end 140.49 85.85) (width 0.1) (layer "F.Cu") (net 118))
  (segment (start 138.85 85.85) (end 138.25 85.25) (width 0.1) (layer "F.Cu") (net 118))
  (segment (start 140.49 85.85) (end 138.85 85.85) (width 0.1) (layer "F.Cu") (net 118))
  (segment (start 138.31 84.725) (end 138.42 84.725) (width 0.1) (layer "F.Cu") (net 118))
  (segment (start 138.25 85.25) (end 138.25 84.785) (width 0.1) (layer "F.Cu") (net 118))
  (segment (start 138.42 84.725) (end 138.48 84.785) (width 0.1) (layer "F.Cu") (net 118))
  (segment (start 142.045846 89.894165) (end 141.27 89.118319) (width 0.1) (layer "F.Cu") (net 118))
  (segment (start 138.25 84.785) (end 138.31 84.725) (width 0.1) (layer "F.Cu") (net 118))
  (segment (start 138.48 84.785) (end 138.48 84.91) (width 0.1) (layer "F.Cu") (net 118))
  (via (at 142.045846 89.894165) (size 0.45) (drill 0.1) (layers "F.Cu" "B.Cu") (net 118))
  (segment (start 142.338588 89.601423) (end 142.045846 89.894165) (width 0.1) (layer "B.Cu") (net 118))
  (segment (start 142.340002 89.601423) (end 142.338588 89.601423) (width 0.1) (layer "B.Cu") (net 118))
  (segment (start 115.661002 63.686) (end 115.661001 63.411) (width 0.25) (layer "F.Cu") (net 119))
  (segment (start 115.440001 63.19) (end 115.249 62.998999) (width 0.25) (layer "F.Cu") (net 119))
  (segment (start 115.249 62.998999) (end 115.249 62.2595) (width 0.25) (layer "F.Cu") (net 119))
  (segment (start 115.661001 63.411) (end 115.440001 63.19) (width 0.25) (layer "F.Cu") (net 119))
  (via (at 115.440001 63.19) (size 0.45) (drill 0.1) (layers "F.Cu" "B.Cu") (net 119))
  (segment (start 114.430001 63.19) (end 115.440001 63.19) (width 0.25) (layer "B.Cu") (net 119))
  (via (at 127 62.75) (size 0.45) (drill 0.1) (layers "F.Cu" "B.Cu") (net 120))
  (segment (start 126.735 62.75) (end 127 62.75) (width 0.1) (layer "B.Cu") (net 120))
  (segment (start 118.25 89.25) (end 118.25 89.222499) (width 0.1) (layer "F.Cu") (net 121))
  (segment (start 118.25 89.222499) (end 118.1975 89.169999) (width 0.1) (layer "F.Cu") (net 121))
  (via (at 118.25 89.25) (size 0.45) (drill 0.1) (layers "F.Cu" "B.Cu") (net 121))
  (segment (start 116.19 90.84) (end 116.55 90.48) (width 0.1) (layer "B.Cu") (net 121))
  (segment (start 118.35 90.33) (end 118.35 89.35) (width 0.1) (layer "B.Cu") (net 121))
  (segment (start 116.19 91.145) (end 116.19 90.84) (width 0.1) (layer "B.Cu") (net 121))
  (segment (start 118.35 89.35) (end 118.25 89.25) (width 0.1) (layer "B.Cu") (net 121))
  (segment (start 116.55 90.48) (end 118.2 90.48) (width 0.1) (layer "B.Cu") (net 121))
  (segment (start 118.2 90.48) (end 118.35 90.33) (width 0.1) (layer "B.Cu") (net 121))
  (via (at 148.25 68.74) (size 0.45) (drill 0.1) (layers "F.Cu" "B.Cu") (net 122))
  (segment (start 148.5 70.455) (end 148.5 68.99) (width 0.1) (layer "B.Cu") (net 122))
  (segment (start 148.5 68.99) (end 148.25 68.74) (width 0.1) (layer "B.Cu") (net 122))
  (via (at 106.2745 89.2) (size 0.45) (drill 0.1) (layers "F.Cu" "B.Cu") (net 123))
  (segment (start 106.4605 89.2) (end 106.2745 89.2) (width 0.1) (layer "B.Cu") (net 123))
  (segment (start 147.335 70.29) (end 147.5 70.455) (width 0.1) (layer "F.Cu") (net 138))
  (segment (start 146.575 70.29) (end 147.335 70.29) (width 0.1) (layer "F.Cu") (net 138))
  (via (at 147.5 70.455) (size 0.45) (drill 0.1) (layers "F.Cu" "B.Cu") (net 138))
  (segment (start 147.47 70.455) (end 146.5 71.425) (width 0.1) (layer "B.Cu") (net 138))
  (segment (start 147.5 70.455) (end 147.47 70.455) (width 0.1) (layer "B.Cu") (net 138))
  (segment (start 148.425 71.35) (end 148.5 71.425) (width 0.1) (layer "F.Cu") (net 139))
  (segment (start 148.425 70.94) (end 148.425 71.35) (width 0.1) (layer "F.Cu") (net 139))
  (via (at 148.5 71.425) (size 0.45) (drill 0.1) (layers "F.Cu" "B.Cu") (net 139))
  (segment (start 102.385 88.9) (end 102.385 88.904997) (width 0.1) (layer "F.Cu") (net 140))
  (segment (start 102.385 88.904997) (end 102.390003 88.91) (width 0.1) (layer "F.Cu") (net 140))
  (via (at 102.390003 88.91) (size 0.45) (drill 0.1) (layers "F.Cu" "B.Cu") (net 140))
  (segment (start 102.390003 88.91) (end 103.69 88.91) (width 0.1) (layer "B.Cu") (net 140))
  (via (at 106.9455 92.248) (size 0.45) (drill 0.1) (layers "F.Cu" "B.Cu") (net 141))
  (segment (start 106.9435 92.25) (end 106.9455 92.248) (width 0.1) (layer "B.Cu") (net 141))
  (segment (start 106.83 92.25) (end 106.9435 92.25) (width 0.1) (layer "B.Cu") (net 141))
  (segment (start 112.06 89.81) (end 111.32 89.81) (width 0.1) (layer "F.Cu") (net 142))
  (via (at 107.6925 92.248) (size 0.45) (drill 0.1) (layers "F.Cu" "B.Cu") (net 142))
  (via (at 111.32 89.81) (size 0.45) (drill 0.1) (layers "F.Cu" "B.Cu") (net 142))
  (segment (start 110.29 89.81) (end 107.85 92.25) (width 0.1) (layer "B.Cu") (net 142))
  (segment (start 111.32 89.81) (end 110.29 89.81) (width 0.1) (layer "B.Cu") (net 142))
  (segment (start 107.981 90.349) (end 107.99 90.34) (width 0.1) (layer "F.Cu") (net 143))
  (segment (start 107.6925 90.349) (end 107.981 90.349) (width 0.1) (layer "F.Cu") (net 143))
  (via (at 112.06 90.47) (size 0.45) (drill 0.1) (layers "F.Cu" "B.Cu") (net 143))
  (via (at 107.99 90.34) (size 0.45) (drill 0.1) (layers "F.Cu" "B.Cu") (net 143))
  (via (at 111.61 90.47) (size 0.45) (drill 0.1) (layers "F.Cu" "B.Cu") (net 143))
  (via (at 112.06 91.79) (size 0.45) (drill 0.1) (layers "F.Cu" "B.Cu") (net 143))
  (via (at 111.61 91.79) (size 0.45) (drill 0.1) (layers "F.Cu" "B.Cu") (net 143))
  (via (at 111.61 91.13) (size 0.45) (drill 0.1) (layers "F.Cu" "B.Cu") (net 143))
  (via (at 112.51 91.79) (size 0.45) (drill 0.1) (layers "F.Cu" "B.Cu") (net 143))
  (via (at 112.51 91.13) (size 0.45) (drill 0.1) (layers "F.Cu" "B.Cu") (net 143))
  (via (at 112.51 90.47) (size 0.45) (drill 0.1) (layers "F.Cu" "B.Cu") (net 143))
  (via (at 112.06 91.13) (size 0.45) (drill 0.1) (layers "F.Cu" "B.Cu") (net 143))
  (segment (start 107.99 90.34) (end 108.12 90.47) (width 0.1) (layer "In3.Cu") (net 143))
  (segment (start 108.12 90.47) (end 111.61 90.47) (width 0.1) (layer "In3.Cu") (net 143))
  (segment (start 118.931999 90.321999) (end 118.9495 90.321999) (width 0.1) (layer "F.Cu") (net 144))
  (segment (start 118.91 90.3) (end 118.931999 90.321999) (width 0.1) (layer "F.Cu") (net 144))
  (via (at 118.91 90.3) (size 0.45) (drill 0.1) (layers "F.Cu" "B.Cu") (net 144))
  (segment (start 117.515 90.78) (end 117.15 91.145) (width 0.1) (layer "B.Cu") (net 144))
  (segment (start 118.91 90.3) (end 118.43 90.78) (width 0.1) (layer "B.Cu") (net 144))
  (segment (start 118.43 90.78) (end 117.515 90.78) (width 0.1) (layer "B.Cu") (net 144))
  (segment (start 117.9 90.02) (end 118.201999 90.321999) (width 0.1) (layer "F.Cu") (net 145))
  (segment (start 113.8125 91.79) (end 114.585 91.79) (width 0.1) (layer "F.Cu") (net 145))
  (segment (start 118.201999 90.321999) (end 118.2025 90.321999) (width 0.1) (layer "F.Cu") (net 145))
  (via (at 117.9 90.02) (size 0.45) (drill 0.1) (layers "F.Cu" "B.Cu") (net 145))
  (via (at 114.585 91.79) (size 0.45) (drill 0.1) (layers "F.Cu" "B.Cu") (net 145))
  (segment (start 115.23 91.145) (end 115.23 90.88) (width 0.1) (layer "B.Cu") (net 145))
  (segment (start 116.09 90.02) (end 117.9 90.02) (width 0.1) (layer "B.Cu") (net 145))
  (segment (start 115.23 90.88) (end 116.09 90.02) (width 0.1) (layer "B.Cu") (net 145))
  (segment (start 114.585 91.79) (end 115.23 91.145) (width 0.1) (layer "B.Cu") (net 145))
  (segment (start 117.88 91.17) (end 118.2025 91.4925) (width 0.1) (layer "F.Cu") (net 146))
  (segment (start 118.2025 91.4925) (end 118.2025 92.220999) (width 0.1) (layer "F.Cu") (net 146))
  (via (at 114.2625 91.13) (size 0.45) (drill 0.1) (layers "F.Cu" "B.Cu") (net 146))
  (via (at 114.2625 90.47) (size 0.45) (drill 0.1) (layers "F.Cu" "B.Cu") (net 146))
  (via (at 113.3625 89.81) (size 0.45) (drill 0.1) (layers "F.Cu" "B.Cu") (net 146))
  (via (at 114.2625 89.81) (size 0.45) (drill 0.1) (layers "F.Cu" "B.Cu") (net 146))
  (via (at 113.8125 89.81) (size 0.45) (drill 0.1) (layers "F.Cu" "B.Cu") (net 146))
  (via (at 113.3625 90.47) (size 0.45) (drill 0.1) (layers "F.Cu" "B.Cu") (net 146))
  (via (at 113.8125 91.13) (size 0.45) (drill 0.1) (layers "F.Cu" "B.Cu") (net 146))
  (via (at 117.88 91.17) (size 0.45) (drill 0.1) (layers "F.Cu" "B.Cu") (net 146))
  (via (at 113.3625 91.13) (size 0.45) (drill 0.1) (layers "F.Cu" "B.Cu") (net 146))
  (via (at 113.8125 90.47) (size 0.45) (drill 0.1) (layers "F.Cu" "B.Cu") (net 146))
  (segment (start 114.3025 91.17) (end 114.2625 91.13) (width 0.1) (layer "In3.Cu") (net 146))
  (segment (start 117.88 91.17) (end 114.3025 91.17) (width 0.1) (layer "In3.Cu") (net 146))
  (segment (start 110.075 85.05) (end 110.075 86.645) (width 0.1) (layer "F.Cu") (net 147))
  (segment (start 110.075 86.645) (end 110.065 86.655) (width 0.1) (layer "F.Cu") (net 147))
  (via (at 110.065 86.655) (size 0.45) (drill 0.1) (layers "F.Cu" "B.Cu") (net 147))
  (segment (start 107.71 83.4) (end 107.425 83.685) (width 0.1) (layer "F.Cu") (net 148))
  (segment (start 108.425 83.4) (end 107.71 83.4) (width 0.1) (layer "F.Cu") (net 148))
  (via (at 107.425 83.685) (size 0.45) (drill 0.1) (layers "F.Cu" "B.Cu") (net 148))
  (segment (start 156.39 60.35) (end 156.39 58.375) (width 0.1) (layer "F.Cu") (net 149))
  (segment (start 156.39 58.375) (end 156.89 57.875) (width 0.1) (layer "F.Cu") (net 149))
  (via (at 156.89 57.875) (size 0.45) (drill 0.1) (layers "F.Cu" "B.Cu") (net 149))
  (segment (start 156.39 60.85) (end 156.155 60.615) (width 0.1) (layer "F.Cu") (net 150))
  (segment (start 156.155 60.615) (end 156.155 58.14) (width 0.1) (layer "F.Cu") (net 150))
  (segment (start 156.155 58.14) (end 155.89 57.875) (width 0.1) (layer "F.Cu") (net 150))
  (via (at 155.89 57.875) (size 0.45) (drill 0.1) (layers "F.Cu" "B.Cu") (net 150))
  (segment (start 156.64 59.125) (end 157.89 57.875) (width 0.1) (layer "F.Cu") (net 151))
  (segment (start 156.64 60.6) (end 156.64 59.125) (width 0.1) (layer "F.Cu") (net 151))
  (segment (start 156.89 60.85) (end 156.64 60.6) (width 0.1) (layer "F.Cu") (net 151))
  (via (at 157.89 57.875) (size 0.45) (drill 0.1) (layers "F.Cu" "B.Cu") (net 151))
  (via (at 154.84 60.9) (size 0.45) (drill 0.1) (layers "F.Cu" "B.Cu") (net 152))
  (segment (start 152.91 60.1) (end 153.3 60.49) (width 0.1) (layer "B.Cu") (net 152))
  (segment (start 154.43 60.49) (end 154.84 60.9) (width 0.1) (layer "B.Cu") (net 152))
  (segment (start 152.91 59.985) (end 152.91 60.1) (width 0.1) (layer "B.Cu") (net 152))
  (segment (start 153.3 60.49) (end 154.43 60.49) (width 0.1) (layer "B.Cu") (net 152))
  (via (at 158.67 61.27) (size 0.45) (drill 0.1) (layers "F.Cu" "B.Cu") (net 153))
  (segment (start 158.94 61) (end 158.94 60.97) (width 0.4) (layer "B.Cu") (net 153))
  (segment (start 158.67 61.27) (end 158.94 61) (width 0.4) (layer "B.Cu") (net 153))
  (segment (start 160.78 63.115) (end 160.925 62.97) (width 0.1) (layer "F.Cu") (net 154))
  (segment (start 158.89 63.35) (end 159.125 63.115) (width 0.1) (layer "F.Cu") (net 154))
  (segment (start 159.125 63.115) (end 160.78 63.115) (width 0.1) (layer "F.Cu") (net 154))
  (via (at 160.925 62.97) (size 0.45) (drill 0.1) (layers "F.Cu" "B.Cu") (net 154))
  (segment (start 157.39 61.85) (end 157.39 61.45) (width 0.1) (layer "F.Cu") (net 155))
  (segment (start 157.39 61.45) (end 157.49 61.35) (width 0.1) (layer "F.Cu") (net 155))
  (via (at 157.49 61.35) (size 0.45) (drill 0.1) (layers "F.Cu" "B.Cu") (net 155))
  (segment (start 157.49 61.275) (end 158.89 59.875) (width 0.1) (layer "B.Cu") (net 155))
  (segment (start 157.49 61.35) (end 157.49 61.275) (width 0.1) (layer "B.Cu") (net 155))
  (segment (start 154.89 62.31) (end 154.89 62.85) (width 0.1) (layer "F.Cu") (net 156))
  (segment (start 154.89 62.31) (end 154.89 62.35) (width 0.1) (layer "F.Cu") (net 156))
  (segment (start 154.89 62.85) (end 154.89 62.35) (width 0.1) (layer "F.Cu") (net 156))
  (via (at 154.89 62.31) (size 0.45) (drill 0.1) (layers "F.Cu" "B.Cu") (net 156))
  (segment (start 154.89 62.31) (end 154.89 62.005) (width 0.1) (layer "B.Cu") (net 156))
  (segment (start 154.89 62.005) (end 154.925 61.97) (width 0.1) (layer "B.Cu") (net 156))
  (segment (start 111.575 84.55) (end 111.525 84.5) (width 0.1) (layer "F.Cu") (net 157))
  (segment (start 111.575 85.05) (end 111.575 84.55) (width 0.1) (layer "F.Cu") (net 157))
  (via (at 111.7 88.3) (size 0.45) (drill 0.1) (layers "F.Cu" "B.Cu") (net 157))
  (via (at 111.525 84.5) (size 0.45) (drill 0.1) (layers "F.Cu" "B.Cu") (net 157))
  (segment (start 111.7 88.3) (end 111.7 84.675) (width 0.1) (layer "In3.Cu") (net 157))
  (segment (start 111.7 84.675) (end 111.525 84.5) (width 0.1) (layer "In3.Cu") (net 157))
  (segment (start 109.05 84.17) (end 108.91 84.03) (width 0.1) (layer "B.Cu") (net 157))
  (segment (start 108.91 82.15) (end 109.4 81.66) (width 0.1) (layer "B.Cu") (net 157))
  (segment (start 111.525 84.5) (end 111.195 84.17) (width 0.1) (layer "B.Cu") (net 157))
  (segment (start 111.195 84.17) (end 109.05 84.17) (width 0.1) (layer "B.Cu") (net 157))
  (segment (start 108.91 84.03) (end 108.91 82.15) (width 0.1) (layer "B.Cu") (net 157))
  (segment (start 117.159001 65.91) (end 117.159001 65.684) (width 0.25) (layer "F.Cu") (net 158))
  (segment (start 117.284001 66.035) (end 117.159001 65.91) (width 0.25) (layer "F.Cu") (net 158))
  (via (at 117.284001 66.035) (size 0.45) (drill 0.1) (layers "F.Cu" "B.Cu") (net 158))
  (segment (start 117.284001 65.993999) (end 116.450001 65.16) (width 0.25) (layer "B.Cu") (net 158))
  (segment (start 117.284001 66.035) (end 117.284001 65.993999) (width 0.25) (layer "B.Cu") (net 158))
  (via (at 112.225 83.4) (size 0.45) (drill 0.1) (layers "F.Cu" "B.Cu") (net 159))
  (segment (start 112.200001 83.68) (end 112.2 83.425) (width 0.1) (layer "B.Cu") (net 159))
  (segment (start 111.795 84.93) (end 112.2 84.525) (width 0.1) (layer "B.Cu") (net 159))
  (segment (start 109.4 84.68) (end 110.4 84.68) (width 0.1) (layer "B.Cu") (net 159))
  (segment (start 110.4 84.68) (end 110.650001 84.93) (width 0.1) (layer "B.Cu") (net 159))
  (segment (start 110.650001 84.93) (end 111.795 84.93) (width 0.1) (layer "B.Cu") (net 159))
  (segment (start 112.2 83.425) (end 112.225 83.4) (width 0.1) (layer "B.Cu") (net 159))
  (segment (start 112.2 84.525) (end 112.200001 83.68) (width 0.1) (layer "B.Cu") (net 159))
  (segment (start 111.074999 85.665) (end 111.095 85.685001) (width 0.1) (layer "F.Cu") (net 160))
  (segment (start 111.075 85.05) (end 111.074999 85.665) (width 0.1) (layer "F.Cu") (net 160))
  (via (at 111.095 85.685001) (size 0.45) (drill 0.1) (layers "F.Cu" "B.Cu") (net 160))
  (segment (start 112.225 83.9) (end 112.97 83.9) (width 0.1) (layer "F.Cu") (net 161))
  (segment (start 112.97 83.9) (end 113.19 83.68) (width 0.1) (layer "F.Cu") (net 161))
  (via (at 113.19 83.68) (size 0.45) (drill 0.1) (layers "F.Cu" "B.Cu") (net 161))
  (segment (start 156.39 61.85) (end 156.39 61.45) (width 0.1) (layer "F.Cu") (net 162))
  (segment (start 156.39 61.45) (end 156.29 61.35) (width 0.1) (layer "F.Cu") (net 162))
  (via (at 156.29 61.35) (size 0.45) (drill 0.1) (layers "F.Cu" "B.Cu") (net 162))
  (segment (start 155.89 60.95) (end 155.89 59.875) (width 0.1) (layer "B.Cu") (net 162))
  (segment (start 156.29 61.35) (end 155.89 60.95) (width 0.1) (layer "B.Cu") (net 162))
  (segment (start 155.89 61.85) (end 155.39 61.35) (width 0.1) (layer "F.Cu") (net 163))
  (segment (start 155.89 62.35) (end 155.89 61.85) (width 0.1) (layer "F.Cu") (net 163))
  (via (at 155.39 61.35) (size 0.45) (drill 0.1) (layers "F.Cu" "B.Cu") (net 163))
  (segment (start 155.39 61.35) (end 155.39 58.435) (width 0.1) (layer "B.Cu") (net 163))
  (segment (start 155.39 58.435) (end 154.89 57.935) (width 0.1) (layer "B.Cu") (net 163))
  (segment (start 154.39 62.85) (end 153.52 62.85) (width 0.1) (layer "F.Cu") (net 164))
  (segment (start 153.14 62.47) (end 151.485 62.47) (width 0.1) (layer "F.Cu") (net 164))
  (segment (start 153.52 62.85) (end 153.14 62.47) (width 0.1) (layer "F.Cu") (net 164))
  (segment (start 151.485 62.47) (end 150.985 62.97) (width 0.1) (layer "F.Cu") (net 164))
  (via (at 150.985 62.97) (size 0.45) (drill 0.1) (layers "F.Cu" "B.Cu") (net 164))
  (segment (start 159.39 62.35) (end 159.515 62.35) (width 0.1) (layer "F.Cu") (net 165))
  (segment (start 159.515 62.35) (end 159.895 61.97) (width 0.1) (layer "F.Cu") (net 165))
  (via (at 159.895 61.97) (size 0.45) (drill 0.1) (layers "F.Cu" "B.Cu") (net 165))
  (segment (start 156.89 61.85) (end 156.89 61.35) (width 0.1) (layer "F.Cu") (net 166))
  (via (at 156.89 61.35) (size 0.45) (drill 0.1) (layers "F.Cu" "B.Cu") (net 166))
  (segment (start 156.89 61.35) (end 156.89 59.875) (width 0.1) (layer "B.Cu") (net 166))
  (segment (start 159.155 62.585) (end 159.905 62.585) (width 0.1) (layer "F.Cu") (net 167))
  (segment (start 159.905 62.585) (end 160.4 62.09) (width 0.1) (layer "F.Cu") (net 167))
  (segment (start 160.4 61.495) (end 160.925 60.97) (width 0.1) (layer "F.Cu") (net 167))
  (segment (start 158.89 62.85) (end 159.155 62.585) (width 0.1) (layer "F.Cu") (net 167))
  (segment (start 160.4 62.09) (end 160.4 61.495) (width 0.1) (layer "F.Cu") (net 167))
  (via (at 160.925 60.97) (size 0.45) (drill 0.1) (layers "F.Cu" "B.Cu") (net 167))
  (segment (start 155.07 63.35) (end 155.18 63.24) (width 0.1) (layer "F.Cu") (net 168))
  (segment (start 154.89 63.35) (end 155.07 63.35) (width 0.1) (layer "F.Cu") (net 168))
  (via (at 155.18 63.24) (size 0.45) (drill 0.1) (layers "F.Cu" "B.Cu") (net 168))
  (segment (start 155.125 63.24) (end 154.855 62.97) (width 0.1) (layer "B.Cu") (net 168))
  (segment (start 155.18 63.24) (end 155.125 63.24) (width 0.1) (layer "B.Cu") (net 168))
  (segment (start 110.575 85.05) (end 110.575001 85.96) (width 0.1) (layer "F.Cu") (net 169))
  (segment (start 112.61 86.2) (end 113.125 85.685) (width 0.1) (layer "F.Cu") (net 169))
  (segment (start 110.575001 85.96) (end 110.815 86.2) (width 0.1) (layer "F.Cu") (net 169))
  (segment (start 110.815 86.2) (end 112.61 86.2) (width 0.1) (layer "F.Cu") (net 169))
  (via (at 113.125 85.685) (size 0.45) (drill 0.1) (layers "F.Cu" "B.Cu") (net 169))
  (segment (start 114.145 85.685) (end 113.125 85.685) (width 0.1) (layer "B.Cu") (net 169))
  (segment (start 129.74 76.63) (end 129.35 76.63) (width 0.1) (layer "F.Cu") (net 170))
  (segment (start 129.35 76.63) (end 129.17 76.81) (width 0.1) (layer "F.Cu") (net 170))
  (segment (start 129.17 76.81) (end 129.17 77.345) (width 0.1) (layer "F.Cu") (net 170))
  (segment (start 129.17 77.345) (end 128.675 77.84) (width 0.1) (layer "F.Cu") (net 170))
  (via (at 128.675 77.84) (size 0.45) (drill 0.1) (layers "F.Cu" "B.Cu") (net 170))
  (segment (start 130.43 71.585) (end 130.05 71.205) (width 0.1) (layer "F.Cu") (net 171))
  (segment (start 130.43 75.02) (end 130.43 71.585) (width 0.1) (layer "F.Cu") (net 171))
  (segment (start 130.66 75.25) (end 130.43 75.02) (width 0.1) (layer "F.Cu") (net 171))
  (via (at 130.05 71.205) (size 0.45) (drill 0.1) (layers "F.Cu" "B.Cu") (net 171))
  (via (at 130.675 76.6) (size 0.45) (drill 0.1) (layers "F.Cu" "B.Cu") (net 172))
  (via (at 131.075 67.305) (size 0.45) (drill 0.1) (layers "F.Cu" "B.Cu") (net 172))
  (segment (start 130.22 75.66) (end 130.78 75.1) (width 0.1) (layer "In3.Cu") (net 172))
  (segment (start 131.59 67.82) (end 131.075 67.305) (width 0.1) (layer "In3.Cu") (net 172))
  (segment (start 130.675 76.6) (end 130.22 76.145) (width 0.1) (layer "In3.Cu") (net 172))
  (segment (start 130.78 72.26) (end 131.59 71.45) (width 0.1) (layer "In3.Cu") (net 172))
  (segment (start 131.59 71.45) (end 131.59 67.82) (width 0.1) (layer "In3.Cu") (net 172))
  (segment (start 130.78 75.1) (end 130.78 72.26) (width 0.1) (layer "In3.Cu") (net 172))
  (segment (start 130.22 76.145) (end 130.22 75.66) (width 0.1) (layer "In3.Cu") (net 172))
  (via (at 137.225 67.305) (size 0.45) (drill 0.1) (layers "F.Cu" "B.Cu") (net 173))
  (via (at 133.402 75.725) (size 0.45) (drill 0.1) (layers "F.Cu" "B.Cu") (net 173))
  (segment (start 134.6 71.74) (end 134.6 69.09) (width 0.1) (layer "In3.Cu") (net 173))
  (segment (start 136.72 67.81) (end 137.225 67.305) (width 0.1) (layer "In3.Cu") (net 173))
  (segment (start 132.39 74.54) (end 132.39 73.95) (width 0.1) (layer "In3.Cu") (net 173))
  (segment (start 133.402 75.725) (end 133.402 75.552) (width 0.1) (layer "In3.Cu") (net 173))
  (segment (start 134.6 69.09) (end 134.93 68.76) (width 0.1) (layer "In3.Cu") (net 173))
  (segment (start 132.39 73.95) (end 134.6 71.74) (width 0.1) (layer "In3.Cu") (net 173))
  (segment (start 136.72 68.56) (end 136.72 67.81) (width 0.1) (layer "In3.Cu") (net 173))
  (segment (start 133.402 75.552) (end 132.39 74.54) (width 0.1) (layer "In3.Cu") (net 173))
  (segment (start 134.93 68.76) (end 136.52 68.76) (width 0.1) (layer "In3.Cu") (net 173))
  (segment (start 136.52 68.76) (end 136.72 68.56) (width 0.1) (layer "In3.Cu") (net 173))
  (via (at 130.675 77.25) (size 0.45) (drill 0.1) (layers "F.Cu" "B.Cu") (net 174))
  (via (at 130.05 67.305) (size 0.45) (drill 0.1) (layers "F.Cu" "B.Cu") (net 174))
  (segment (start 129.9 75.45) (end 130.54 74.81) (width 0.1) (layer "In3.Cu") (net 174))
  (segment (start 130.54 67.795) (end 130.05 67.305) (width 0.1) (layer "In3.Cu") (net 174))
  (segment (start 130.54 74.81) (end 130.54 67.795) (width 0.1) (layer "In3.Cu") (net 174))
  (segment (start 130.675 77.25) (end 129.9 76.475) (width 0.1) (layer "In3.Cu") (net 174))
  (segment (start 129.9 76.475) (end 129.9 75.45) (width 0.1) (layer "In3.Cu") (net 174))
  (segment (start 131.225 77.5) (end 131.225 76.275) (width 0.1) (layer "F.Cu") (net 175))
  (segment (start 130.9 77.9) (end 131.225 77.575) (width 0.1) (layer "F.Cu") (net 175))
  (segment (start 131.225 77.575) (end 131.225 77.5) (width 0.1) (layer "F.Cu") (net 175))
  (via (at 133.125 67.305) (size 0.45) (drill 0.1) (layers "F.Cu" "B.Cu") (net 175))
  (via (at 131.225 76.275) (size 0.45) (drill 0.1) (layers "F.Cu" "B.Cu") (net 175))
  (segment (start 131.225 76.275) (end 131.225 75.995) (width 0.1) (layer "In3.Cu") (net 175))
  (segment (start 133.64 67.82) (end 133.125 67.305) (width 0.1) (layer "In3.Cu") (net 175))
  (segment (start 131.1 75.577335) (end 131.24 75.437335) (width 0.1) (layer "In3.Cu") (net 175))
  (segment (start 131.24 75.437335) (end 131.24 73.75) (width 0.1) (layer "In3.Cu") (net 175))
  (segment (start 131.1 75.87) (end 131.1 75.577335) (width 0.1) (layer "In3.Cu") (net 175))
  (segment (start 131.24 73.75) (end 133.64 71.35) (width 0.1) (layer "In3.Cu") (net 175))
  (segment (start 133.64 71.35) (end 133.64 67.82) (width 0.1) (layer "In3.Cu") (net 175))
  (segment (start 131.225 75.995) (end 131.1 75.87) (width 0.1) (layer "In3.Cu") (net 175))
  (via (at 134.249 75.726) (size 0.45) (drill 0.1) (layers "F.Cu" "B.Cu") (net 176))
  (via (at 139.275 67.305) (size 0.45) (drill 0.1) (layers "F.Cu" "B.Cu") (net 176))
  (segment (start 134.325 75.65) (end 134.325 74.065) (width 0.1) (layer "In3.Cu") (net 176))
  (segment (start 138.68 67.9) (end 139.275 67.305) (width 0.1) (layer "In3.Cu") (net 176))
  (segment (start 137.96 72.14) (end 138.68 71.42) (width 0.1) (layer "In3.Cu") (net 176))
  (segment (start 136.25 72.14) (end 137.96 72.14) (width 0.1) (layer "In3.Cu") (net 176))
  (segment (start 138.68 71.42) (end 138.68 67.9) (width 0.1) (layer "In3.Cu") (net 176))
  (segment (start 134.249 75.726) (end 134.325 75.65) (width 0.1) (layer "In3.Cu") (net 176))
  (segment (start 134.325 74.065) (end 136.25 72.14) (width 0.1) (layer "In3.Cu") (net 176))
  (segment (start 130.9 82.45) (end 131.225 82.775) (width 0.1) (layer "F.Cu") (net 177))
  (via (at 131.225 82.775) (size 0.45) (drill 0.1) (layers "F.Cu" "B.Cu") (net 177))
  (segment (start 131.185 83.12) (end 131.185 82.815) (width 0.1) (layer "B.Cu") (net 177))
  (segment (start 131.185 82.815) (end 131.225 82.775) (width 0.1) (layer "B.Cu") (net 177))
  (via (at 132.1 67.305) (size 0.45) (drill 0.1) (layers "F.Cu" "B.Cu") (net 178))
  (via (at 130.675 75.95) (size 0.45) (drill 0.1) (layers "F.Cu" "B.Cu") (net 178))
  (segment (start 131.01 73.15) (end 132.6 71.56) (width 0.1) (layer "In3.Cu") (net 178))
  (segment (start 130.675 75.645) (end 131.01 75.31) (width 0.1) (layer "In3.Cu") (net 178))
  (segment (start 132.6 67.805) (end 132.1 67.305) (width 0.1) (layer "In3.Cu") (net 178))
  (segment (start 131.01 75.31) (end 131.01 73.15) (width 0.1) (layer "In3.Cu") (net 178))
  (segment (start 130.675 75.95) (end 130.675 75.645) (width 0.1) (layer "In3.Cu") (net 178))
  (segment (start 132.6 71.56) (end 132.6 67.805) (width 0.1) (layer "In3.Cu") (net 178))
  (via (at 135.175 67.305) (size 0.45) (drill 0.1) (layers "F.Cu" "B.Cu") (net 179))
  (via (at 132.2 75.725) (size 0.45) (drill 0.1) (layers "F.Cu" "B.Cu") (net 179))
  (segment (start 131.92 73.76) (end 134.11 71.57) (width 0.1) (layer "In3.Cu") (net 179))
  (segment (start 134.11 68.37) (end 135.175 67.305) (width 0.1) (layer "In3.Cu") (net 179))
  (segment (start 131.92 75.445) (end 131.92 73.76) (width 0.1) (layer "In3.Cu") (net 179))
  (segment (start 134.11 71.57) (end 134.11 68.37) (width 0.1) (layer "In3.Cu") (net 179))
  (segment (start 132.2 75.725) (end 131.92 75.445) (width 0.1) (layer "In3.Cu") (net 179))
  (via (at 132.85 75.725) (size 0.45) (drill 0.1) (layers "F.Cu" "B.Cu") (net 180))
  (via (at 136.2 67.305) (size 0.45) (drill 0.1) (layers "F.Cu" "B.Cu") (net 180))
  (segment (start 132.15 74.74) (end 132.15 73.85) (width 0.1) (layer "In3.Cu") (net 180))
  (segment (start 134.36 68.46) (end 135.05 67.77) (width 0.1) (layer "In3.Cu") (net 180))
  (segment (start 135.05 67.77) (end 135.735 67.77) (width 0.1) (layer "In3.Cu") (net 180))
  (segment (start 132.15 73.85) (end 134.36 71.64) (width 0.1) (layer "In3.Cu") (net 180))
  (segment (start 132.85 75.44) (end 132.15 74.74) (width 0.1) (layer "In3.Cu") (net 180))
  (segment (start 135.735 67.77) (end 136.2 67.305) (width 0.1) (layer "In3.Cu") (net 180))
  (segment (start 132.85 75.725) (end 132.85 75.44) (width 0.1) (layer "In3.Cu") (net 180))
  (segment (start 134.36 71.64) (end 134.36 68.46) (width 0.1) (layer "In3.Cu") (net 180))
  (via (at 134.15 67.305) (size 0.45) (drill 0.1) (layers "F.Cu" "B.Cu") (net 181))
  (via (at 131.55 75.725) (size 0.45) (drill 0.1) (layers "F.Cu" "B.Cu") (net 181))
  (segment (start 133.88 71.47) (end 133.88 67.575) (width 0.1) (layer "In3.Cu") (net 181))
  (segment (start 133.88 67.575) (end 134.15 67.305) (width 0.1) (layer "In3.Cu") (net 181))
  (segment (start 131.47 75.13) (end 131.47 73.88) (width 0.1) (layer "In3.Cu") (net 181))
  (segment (start 131.55 75.21) (end 131.47 75.13) (width 0.1) (layer "In3.Cu") (net 181))
  (segment (start 131.55 75.725) (end 131.55 75.21) (width 0.1) (layer "In3.Cu") (net 181))
  (segment (start 131.47 73.88) (end 133.88 71.47) (width 0.1) (layer "In3.Cu") (net 181))
  (segment (start 136.75 83.1) (end 137.075 83.425) (width 0.1) (layer "F.Cu") (net 182))
  (via (at 141.15 78.875) (size 0.45) (drill 0.1) (layers "F.Cu" "B.Cu") (net 182))
  (via (at 137.075 83.425) (size 0.45) (drill 0.1) (layers "F.Cu" "B.Cu") (net 182))
  (segment (start 140.62 79.86) (end 141.15 79.33) (width 0.1) (layer "In3.Cu") (net 182))
  (segment (start 141.15 79.33) (end 141.15 78.875) (width 0.1) (layer "In3.Cu") (net 182))
  (segment (start 137.475 82.4) (end 140.015 79.86) (width 0.1) (layer "In3.Cu") (net 182))
  (segment (start 137.075 83.425) (end 137.475 83.025) (width 0.1) (layer "In3.Cu") (net 182))
  (segment (start 140.015 79.86) (end 140.62 79.86) (width 0.1) (layer "In3.Cu") (net 182))
  (segment (start 137.475 83.025) (end 137.475 82.4) (width 0.1) (layer "In3.Cu") (net 182))
  (segment (start 136.1 77.25) (end 136.425 76.925) (width 0.1) (layer "F.Cu") (net 183))
  (via (at 136.425 76.925) (size 0.45) (drill 0.1) (layers "F.Cu" "B.Cu") (net 183))
  (segment (start 136.75 77.25) (end 137.075 76.925) (width 0.1) (layer "F.Cu") (net 184))
  (via (at 137.075 76.925) (size 0.45) (drill 0.1) (layers "F.Cu" "B.Cu") (net 184))
  (segment (start 139.4 76.17) (end 139.6311 75.9389) (width 0.1) (layer "F.Cu") (net 185))
  (segment (start 139.6311 75.9389) (end 144.4611 75.9389) (width 0.1) (layer "F.Cu") (net 185))
  (segment (start 144.4611 75.9389) (end 146.105 74.295) (width 0.1) (layer "F.Cu") (net 185))
  (segment (start 146.105 74.295) (end 146.105 73.96) (width 0.1) (layer "F.Cu") (net 185))
  (via (at 146.105 73.96) (size 0.45) (drill 0.1) (layers "F.Cu" "B.Cu") (net 185))
  (segment (start 139.6289 76.4011) (end 145.6639 76.4011) (width 0.1) (layer "F.Cu") (net 186))
  (segment (start 139.4 76.63) (end 139.6289 76.4011) (width 0.1) (layer "F.Cu") (net 186))
  (segment (start 145.6639 76.4011) (end 146.105 75.96) (width 0.1) (layer "F.Cu") (net 186))
  (via (at 146.105 75.96) (size 0.45) (drill 0.1) (layers "F.Cu" "B.Cu") (net 186))
  (segment (start 137.1 75.25) (end 136.8711 75.0211) (width 0.1) (layer "F.Cu") (net 187))
  (segment (start 136.8711 72.9111) (end 135.175 71.215) (width 0.1) (layer "F.Cu") (net 187))
  (segment (start 135.175 71.215) (end 135.175 71.205) (width 0.1) (layer "F.Cu") (net 187))
  (segment (start 136.8711 75.0211) (end 136.8711 72.9111) (width 0.1) (layer "F.Cu") (net 187))
  (via (at 135.175 71.205) (size 0.45) (drill 0.1) (layers "F.Cu" "B.Cu") (net 187))
  (segment (start 137.4 83.1) (end 137.725 83.425) (width 0.1) (layer "F.Cu") (net 188))
  (via (at 137.725 83.425) (size 0.45) (drill 0.1) (layers "F.Cu" "B.Cu") (net 188))
  (via (at 142.17 78.87) (size 0.45) (drill 0.1) (layers "F.Cu" "B.Cu") (net 188))
  (segment (start 137.725 82.618669) (end 139.063669 81.28) (width 0.1) (layer "In3.Cu") (net 188))
  (segment (start 139.063669 81.28) (end 140.62 81.28) (width 0.1) (layer "In3.Cu") (net 188))
  (segment (start 137.725 83.425) (end 137.725 82.618669) (width 0.1) (layer "In3.Cu") (net 188))
  (segment (start 141.7 80.2) (end 141.7 79.3) (width 0.1) (layer "In3.Cu") (net 188))
  (segment (start 140.62 81.28) (end 141.7 80.2) (width 0.1) (layer "In3.Cu") (net 188))
  (segment (start 141.7 79.3) (end 142.13 78.87) (width 0.1) (layer "In3.Cu") (net 188))
  (segment (start 142.13 78.87) (end 142.17 78.87) (width 0.1) (layer "In3.Cu") (net 188))
  (segment (start 134.15 81.8) (end 133.825 81.475) (width 0.1) (layer "F.Cu") (net 189))
  (via (at 131.225 82.125) (size 0.45) (drill 0.1) (layers "F.Cu" "B.Cu") (net 189))
  (via (at 133.825 81.475) (size 0.45) (drill 0.1) (layers "F.Cu" "B.Cu") (net 189))
  (segment (start 133.36 82.59) (end 133.01 82.59) (width 0.1) (layer "In3.Cu") (net 189))
  (segment (start 133.825 81.475) (end 133.825 82.125) (width 0.1) (layer "In3.Cu") (net 189))
  (segment (start 132.52 82.1) (end 131.25 82.1) (width 0.1) (layer "In3.Cu") (net 189))
  (segment (start 131.25 82.1) (end 131.225 82.125) (width 0.1) (layer "In3.Cu") (net 189))
  (segment (start 133.825 82.125) (end 133.36 82.59) (width 0.1) (layer "In3.Cu") (net 189))
  (segment (start 133.01 82.59) (end 132.52 82.1) (width 0.1) (layer "In3.Cu") (net 189))
  (segment (start 135.69 69.77) (end 135.175 69.255) (width 0.1) (layer "F.Cu") (net 190))
  (segment (start 137.1 72.76) (end 135.69 71.35) (width 0.1) (layer "F.Cu") (net 190))
  (segment (start 137.1 74.79) (end 137.1 72.76) (width 0.1) (layer "F.Cu") (net 190))
  (segment (start 135.69 71.35) (end 135.69 69.77) (width 0.1) (layer "F.Cu") (net 190))
  (via (at 135.175 69.255) (size 0.45) (drill 0.1) (layers "F.Cu" "B.Cu") (net 190))
  (segment (start 133.825 76.925) (end 133.825 76.275) (width 0.1) (layer "F.Cu") (net 191))
  (segment (start 134.15 77.25) (end 133.825 76.925) (width 0.1) (layer "F.Cu") (net 191))
  (via (at 133.825 76.275) (size 0.45) (drill 0.1) (layers "F.Cu" "B.Cu") (net 191))
  (via (at 138.25 67.305) (size 0.45) (drill 0.1) (layers "F.Cu" "B.Cu") (net 191))
  (segment (start 133.825 76.275) (end 133.825 75.5) (width 0.1) (layer "In3.Cu") (net 191))
  (segment (start 133.825 75.5) (end 133.425 75.1) (width 0.1) (layer "In3.Cu") (net 191))
  (segment (start 137.76 71.5) (end 137.76 67.795) (width 0.1) (layer "In3.Cu") (net 191))
  (segment (start 136.16 71.9) (end 137.36 71.9) (width 0.1) (layer "In3.Cu") (net 191))
  (segment (start 137.76 67.795) (end 138.25 67.305) (width 0.1) (layer "In3.Cu") (net 191))
  (segment (start 137.36 71.9) (end 137.76 71.5) (width 0.1) (layer "In3.Cu") (net 191))
  (segment (start 133.425 74.635) (end 136.16 71.9) (width 0.1) (layer "In3.Cu") (net 191))
  (segment (start 133.425 75.1) (end 133.425 74.635) (width 0.1) (layer "In3.Cu") (net 191))
  (segment (start 131.8111 75.0211) (end 131.8111 72.5189) (width 0.1) (layer "F.Cu") (net 192))
  (segment (start 132.04 75.25) (end 131.8111 75.0211) (width 0.1) (layer "F.Cu") (net 192))
  (segment (start 131.8111 72.5189) (end 133.125 71.205) (width 0.1) (layer "F.Cu") (net 192))
  (via (at 133.125 71.205) (size 0.45) (drill 0.1) (layers "F.Cu" "B.Cu") (net 192))
  (segment (start 132.6 71.39) (end 132.6 69.755) (width 0.1) (layer "F.Cu") (net 193))
  (segment (start 131.58 72.41) (end 132.6 71.39) (width 0.1) (layer "F.Cu") (net 193))
  (segment (start 132.6 69.755) (end 132.1 69.255) (width 0.1) (layer "F.Cu") (net 193))
  (segment (start 131.58 74.79) (end 131.58 72.41) (width 0.1) (layer "F.Cu") (net 193))
  (via (at 132.1 69.255) (size 0.45) (drill 0.1) (layers "F.Cu" "B.Cu") (net 193))
  (segment (start 131.3511 75.0211) (end 131.3511 71.9539) (width 0.1) (layer "F.Cu") (net 194))
  (segment (start 131.58 75.25) (end 131.3511 75.0211) (width 0.1) (layer "F.Cu") (net 194))
  (segment (start 131.3511 71.9539) (end 132.1 71.205) (width 0.1) (layer "F.Cu") (net 194))
  (via (at 132.1 71.205) (size 0.45) (drill 0.1) (layers "F.Cu" "B.Cu") (net 194))
  (segment (start 131.12 71.82) (end 131.59 71.35) (width 0.1) (layer "F.Cu") (net 195))
  (segment (start 131.12 74.79) (end 131.12 71.82) (width 0.1) (layer "F.Cu") (net 195))
  (segment (start 131.59 69.77) (end 131.075 69.255) (width 0.1) (layer "F.Cu") (net 195))
  (segment (start 131.59 71.35) (end 131.59 69.77) (width 0.1) (layer "F.Cu") (net 195))
  (via (at 131.075 69.255) (size 0.45) (drill 0.1) (layers "F.Cu" "B.Cu") (net 195))
  (segment (start 131.12 75.25) (end 130.8911 75.0211) (width 0.1) (layer "F.Cu") (net 196))
  (segment (start 130.8911 75.0211) (end 130.8911 71.3639) (width 0.1) (layer "F.Cu") (net 196))
  (segment (start 130.8911 71.3639) (end 131.05 71.205) (width 0.1) (layer "F.Cu") (net 196))
  (via (at 131.05 71.205) (size 0.45) (drill 0.1) (layers "F.Cu" "B.Cu") (net 196))
  (segment (start 130.66 74.79) (end 130.66 71.43) (width 0.1) (layer "F.Cu") (net 197))
  (segment (start 130.66 71.43) (end 130.54 71.31) (width 0.1) (layer "F.Cu") (net 197))
  (segment (start 130.54 69.745) (end 130.05 69.255) (width 0.1) (layer "F.Cu") (net 197))
  (segment (start 130.54 71.31) (end 130.54 69.745) (width 0.1) (layer "F.Cu") (net 197))
  (via (at 130.05 69.255) (size 0.45) (drill 0.1) (layers "F.Cu" "B.Cu") (net 197))
  (segment (start 137.7911 75.0211) (end 137.7911 71.7711) (width 0.1) (layer "F.Cu") (net 198))
  (segment (start 138.02 75.25) (end 137.7911 75.0211) (width 0.1) (layer "F.Cu") (net 198))
  (segment (start 137.7911 71.7711) (end 137.225 71.205) (width 0.1) (layer "F.Cu") (net 198))
  (via (at 137.225 71.205) (size 0.45) (drill 0.1) (layers "F.Cu" "B.Cu") (net 198))
  (via (at 138.7 75.725) (size 0.45) (drill 0.1) (layers "F.Cu" "B.Cu") (net 199))
  (via (at 142.35 67.305) (size 0.45) (drill 0.1) (layers "F.Cu" "B.Cu") (net 199))
  (segment (start 138.7 73.64) (end 140.27 72.07) (width 0.1) (layer "In3.Cu") (net 199))
  (segment (start 140.27 69.385) (end 142.35 67.305) (width 0.1) (layer "In3.Cu") (net 199))
  (segment (start 140.27 72.07) (end 140.27 69.385) (width 0.1) (layer "In3.Cu") (net 199))
  (segment (start 138.7 75.725) (end 138.7 73.64) (width 0.1) (layer "In3.Cu") (net 199))
  (via (at 141.325 67.305) (size 0.45) (drill 0.1) (layers "F.Cu" "B.Cu") (net 200))
  (via (at 136.75 75.725) (size 0.45) (drill 0.1) (layers "F.Cu" "B.Cu") (net 200))
  (segment (start 136.75 75.725) (end 136.75 74.84) (width 0.1) (layer "In3.Cu") (net 200))
  (segment (start 136.75 74.84) (end 139.71 71.88) (width 0.1) (layer "In3.Cu") (net 200))
  (segment (start 141.325 67.445) (end 141.325 67.305) (width 0.1) (layer "In3.Cu") (net 200))
  (segment (start 139.71 71.88) (end 139.71 69.06) (width 0.1) (layer "In3.Cu") (net 200))
  (segment (start 139.71 69.06) (end 141.325 67.445) (width 0.1) (layer "In3.Cu") (net 200))
  (segment (start 138.48 75.25) (end 138.2511 75.0211) (width 0.1) (layer "F.Cu") (net 201))
  (segment (start 138.2511 71.2061) (end 138.25 71.205) (width 0.1) (layer "F.Cu") (net 201))
  (segment (start 138.2511 75.0211) (end 138.2511 71.2061) (width 0.1) (layer "F.Cu") (net 201))
  (via (at 138.25 71.205) (size 0.45) (drill 0.1) (layers "F.Cu" "B.Cu") (net 201))
  (segment (start 136.72 71.39) (end 136.72 69.775) (width 0.1) (layer "F.Cu") (net 202))
  (segment (start 137.56 72.23) (end 136.72 71.39) (width 0.1) (layer "F.Cu") (net 202))
  (segment (start 137.56 74.79) (end 137.56 72.23) (width 0.1) (layer "F.Cu") (net 202))
  (segment (start 136.72 69.775) (end 136.2 69.255) (width 0.1) (layer "F.Cu") (net 202))
  (via (at 136.2 69.255) (size 0.45) (drill 0.1) (layers "F.Cu" "B.Cu") (net 202))
  (segment (start 138.02 74.79) (end 138.02 71.63) (width 0.1) (layer "F.Cu") (net 203))
  (segment (start 137.78 69.81) (end 137.225 69.255) (width 0.1) (layer "F.Cu") (net 203))
  (segment (start 138.02 71.63) (end 137.78 71.39) (width 0.1) (layer "F.Cu") (net 203))
  (segment (start 137.78 71.39) (end 137.78 69.81) (width 0.1) (layer "F.Cu") (net 203))
  (via (at 137.225 69.255) (size 0.45) (drill 0.1) (layers "F.Cu" "B.Cu") (net 203))
  (segment (start 129.1061 76.3989) (end 128.675 76.83) (width 0.1) (layer "F.Cu") (net 204))
  (segment (start 129.9689 76.3989) (end 129.1061 76.3989) (width 0.1) (layer "F.Cu") (net 204))
  (segment (start 130.2 76.63) (end 129.9689 76.3989) (width 0.1) (layer "F.Cu") (net 204))
  (via (at 128.675 76.83) (size 0.45) (drill 0.1) (layers "F.Cu" "B.Cu") (net 204))
  (segment (start 113.7 81.9) (end 112.225 81.9) (width 0.1) (layer "F.Cu") (net 205))
  (segment (start 108.425 86.4) (end 107.55 85.525) (width 0.1) (layer "F.Cu") (net 206))
  (segment (start 107.55 85.525) (end 107.55 84.725) (width 0.1) (layer "F.Cu") (net 206))
  (segment (start 107.875 84.4) (end 108.425 84.4) (width 0.1) (layer "F.Cu") (net 206))
  (segment (start 107.55 84.725) (end 107.875 84.4) (width 0.1) (layer "F.Cu") (net 206))
  (segment (start 113.7 82.9) (end 112.225 82.9) (width 0.1) (layer "F.Cu") (net 207))
  (segment (start 111.075 79.25) (end 111.075 78.5875) (width 0.25) (layer "F.Cu") (net 268))
  (segment (start 111.575 79.25) (end 111.575 78.5875) (width 0.25) (layer "F.Cu") (net 268))
  (segment (start 111.075 78.5875) (end 111.075 78.4) (width 0.25) (layer "F.Cu") (net 268))
  (via (at 111.6 78.2) (size 0.45) (drill 0.1) (layers "F.Cu" "B.Cu") (net 268))
  (segment (start 111.6 78.2) (end 112.209 78.809) (width 0.25) (layer "B.Cu") (net 268))
  (segment (start 112.209 78.809) (end 112.209 79.65) (width 0.25) (layer "B.Cu") (net 268))

  (zone (net 4) (net_name "Net-(C26-Pad2)") (layer "F.Cu") (hatch edge 0.508)
    (connect_pads yes (clearance 0.2))
    (min_thickness 0.1) (filled_areas_thickness no)
    (fill yes (thermal_gap 0.15) (thermal_bridge_width 0.5))
    (polygon
      (pts
        (xy 108.875 76.05)
        (xy 109.7 78.35)
        (xy 109.7 78.6)
        (xy 108.95 78.6)
        (xy 106.955 76.05)
        (xy 106.955 69.55)
        (xy 108.875 69.55)
      )
    )
  )
  (zone (net 1) (net_name "GND") (layer "F.Cu") (name "GND_LOGO") (hatch edge 0.508)
    (priority 100)
    (connect_pads yes (clearance 0.1))
    (min_thickness 0.1) (filled_areas_thickness no)
    (fill yes (thermal_gap 0.1) (thermal_bridge_width 0.1))
    (polygon
      (pts
        (xy 148.589 57.5)
        (xy 128.6 57.5)
        (xy 128.6 50.7)
        (xy 148.589 50.7)
      )
    )
  )
  (zone (net 268) (net_name "Net-(C28-Pad2)") (layer "F.Cu") (hatch edge 0.508)
    (connect_pads yes (clearance 0.2))
    (min_thickness 0.1) (filled_areas_thickness no)
    (fill yes (thermal_gap 0.15) (thermal_bridge_width 0.5))
    (polygon
      (pts
        (xy 113.695 76.05)
        (xy 111.7 78.6)
        (xy 110.95 78.6)
        (xy 110.95 78.35)
        (xy 111.775 76.05)
        (xy 111.775 69.55)
        (xy 113.695 69.55)
      )
    )
  )
  (zone (net 55) (net_name "Net-(L3-Pad1)") (layer "F.Cu") (name "GND_BGA") (hatch edge 0.508)
    (connect_pads yes (clearance 0.1))
    (min_thickness 0.1) (filled_areas_thickness no)
    (fill yes (thermal_gap 0.1) (thermal_bridge_width 0.1))
    (polygon
      (pts
        (xy 140.943 71.765)
        (xy 140.943 73.6195)
        (xy 138.99 74.52)
        (xy 138.84625 74.52)
        (xy 138.7025 74.52)
        (xy 138.415 74.52)
        (xy 138.657 73.6195)
        (xy 138.657 71.765)
      )
    )
  )
  (zone (net 3) (net_name "5V0_USB") (layer "F.Cu") (hatch edge 0.508)
    (priority 10)
    (connect_pads (clearance 0.2))
    (min_thickness 0.1) (filled_areas_thickness no)
    (fill yes (thermal_gap 0.15) (thermal_bridge_width 0.25))
    (polygon
      (pts
        (xy 106.68 63.0595)
        (xy 105.29 63.0595)
        (xy 105.29 61.5595)
        (xy 106.68 61.5595)
      )
    )
  )
  (zone (net 90) (net_name "Net-(U2-VIN)") (layer "F.Cu") (hatch edge 0.508)
    (priority 10)
    (connect_pads (clearance 0.2))
    (min_thickness 0.1) (filled_areas_thickness no)
    (fill yes (thermal_gap 0.15) (thermal_bridge_width 0.25))
    (polygon
      (pts
        (xy 110.9 61.2295)
        (xy 109.51 61.2295)
        (xy 109.51 59.7295)
        (xy 110.9 59.7295)
      )
    )
  )
  (zone (net 74) (net_name "Net-(C10-Pad2)") (layer "F.Cu") (hatch edge 0.508)
    (connect_pads (clearance 0.2))
    (min_thickness 0.1) (filled_areas_thickness no)
    (fill yes (thermal_gap 0.15) (thermal_bridge_width 0.5))
    (polygon
      (pts
        (xy 101.4 74.45)
        (xy 104.15 74.45)
        (xy 104.15 78.1)
        (xy 105.75 78.1)
        (xy 106.75 79.1)
        (xy 107.55 79.9)
        (xy 107.75 79.9)
        (xy 108.55 79.9)
        (xy 108.55 81.399999)
        (xy 107.75 81.4)
        (xy 106.75 82.199999)
        (xy 101.4 82.2)
      )
    )
  )
  (zone (net 112) (net_name "Net-(U4A-VCC0P9_SVR_SENSE)") (layer "F.Cu") (name "GND") (hatch edge 0.508)
    (connect_pads yes (clearance 0.2))
    (min_thickness 0.1) (filled_areas_thickness no)
    (fill yes (thermal_gap 0.15) (thermal_bridge_width 0.25))
    (polygon
      (pts
        (xy 145.5 72.3)
        (xy 142.1 72.3)
        (xy 139.8 69.835)
        (xy 138.657 69.835)
        (xy 138.657 67.9805)
        (xy 140.943 67.9805)
        (xy 142.6 69.7)
        (xy 145.5 69.7)
      )
    )
  )
  (zone (net 1) (net_name "GND") (layer "F.Cu") (hatch edge 0.508)
    (connect_pads (clearance 0.2))
    (min_thickness 0.1) (filled_areas_thickness no)
    (fill yes (thermal_gap 0.15) (thermal_bridge_width 0.5))
    (polygon
      (pts
        (xy 104.084001 65.31)
        (xy 116.784001 65.31)
        (xy 116.784001 68.26)
        (xy 104.084001 68.26)
      )
    )
  )
  (zone (net 100) (net_name "Net-(D2-A)") (layer "F.Cu") (hatch edge 0.508)
    (priority 10)
    (connect_pads (clearance 0.2))
    (min_thickness 0.1) (filled_areas_thickness no)
    (fill yes (thermal_gap 0.15) (thermal_bridge_width 0.25))
    (polygon
      (pts
        (xy 121.03 58.2495)
        (xy 119.41 58.2495)
        (xy 119.41 61.7395)
        (xy 118.3 61.7395)
        (xy 118.3 56.7495)
        (xy 121.04 56.7495)
      )
    )
  )
  (zone (net 95) (net_name "Net-(U2-SW)") (layer "F.Cu") (hatch edge 0.508)
    (priority 1)
    (connect_pads yes (clearance 0.2))
    (min_thickness 0.1) (filled_areas_thickness no)
    (fill yes (thermal_gap 0.15) (thermal_bridge_width 0.5))
    (polygon
      (pts
        (xy 119.25 66.7)
        (xy 117.33 65.11)
        (xy 116.211001 65.11)
        (xy 116.209001 64.76)
        (xy 118.46 64.76)
        (xy 121.1 65.52)
        (xy 123.95 65.52)
        (xy 123.95 66.7)
      )
    )
  )
  (zone (net 1) (net_name "GND") (layer "F.Cu") (hatch edge 0.508)
    (priority 20)
    (connect_pads yes (clearance 0.2))
    (min_thickness 0.1) (filled_areas_thickness no)
    (fill yes (thermal_gap 0.15) (thermal_bridge_width 0.5))
    (polygon
      (pts
        (xy 164.45 81.623922)
        (xy 161.37 81.623922)
        (xy 161.37 78.793922)
        (xy 164.45 78.793922)
      )
    )
  )
  (zone (net 1) (net_name "GND") (layer "F.Cu") (hatch edge 0.508)
    (connect_pads (clearance 0.2))
    (min_thickness 0.1) (filled_areas_thickness no)
    (fill yes (thermal_gap 0.15) (thermal_bridge_width 0.5))
    (polygon
      (pts
        (xy 114.740001 56.72)
        (xy 118.080001 56.72)
        (xy 118.080001 62.48)
        (xy 116.420001 62.48)
        (xy 116.420001 61.2)
        (xy 114.740001 61.2)
      )
    )
  )
  (zone (net 75) (net_name "Net-(C32-Pad2)") (layer "F.Cu") (hatch edge 0.508)
    (priority 1)
    (connect_pads (clearance 0.2))
    (min_thickness 0.1) (filled_areas_thickness no)
    (fill yes (thermal_gap 0.15) (thermal_bridge_width 0.25))
    (polygon
      (pts
        (xy 112.894999 81.26)
        (xy 112.894999 80.02)
        (xy 119.304999 80.02)
        (xy 119.304999 81.26)
      )
    )
  )
  (zone (net 1) (net_name "GND") (layer "F.Cu") (hatch edge 0.508)
    (priority 20)
    (connect_pads yes (clearance 0.2))
    (min_thickness 0.1) (filled_areas_thickness no)
    (fill yes (thermal_gap 0.15) (thermal_bridge_width 0.5))
    (polygon
      (pts
        (xy 164.44 73.313922)
        (xy 161.37 73.313922)
        (xy 161.37 70.383922)
        (xy 164.44 70.383922)
      )
    )
  )
  (zone (net 32) (net_name "VBUS") (layer "F.Cu") (hatch edge 0.508)
    (priority 1)
    (connect_pads (clearance 0.1))
    (min_thickness 0.1) (filled_areas_thickness no)
    (fill yes (thermal_gap 0.1) (thermal_bridge_width 0.25))
    (polygon
      (pts
        (xy 164.3 65.2)
        (xy 159.7 65.2)
        (xy 159.7 63.45)
        (xy 162.36 63.45)
        (xy 162.36 62)
        (xy 164.3 62)
      )
    )
  )
  (zone (net 60) (net_name "12V0_DCDC") (layer "F.Cu") (hatch edge 0.508)
    (priority 21)
    (connect_pads (clearance 0.2))
    (min_thickness 0.1) (filled_areas_thickness no)
    (fill yes (thermal_gap 0.15) (thermal_bridge_width 0.5))
    (polygon
      (pts
        (xy 117.45 87.15)
        (xy 117.45 89.4)
        (xy 117.45 92.2)
        (xy 114.94 92.2)
        (xy 114.94 88.8)
        (xy 113.7 88.8)
        (xy 113.7 87.15)
      )
    )
  )
  (zone (net 90) (net_name "Net-(U2-VIN)") (layer "F.Cu") (hatch edge 0.508)
    (priority 1)
    (connect_pads (clearance 0.2))
    (min_thickness 0.1) (filled_areas_thickness no)
    (fill yes (thermal_gap 0.15) (thermal_bridge_width 0.5))
    (polygon
      (pts
        (xy 107.084001 59.41)
        (xy 111.134001 59.410001)
        (xy 111.134001 61.41)
        (xy 114.649001 61.409999)
        (xy 114.649001 64.31)
        (xy 115.984002 64.31)
        (xy 115.984001 65.06)
        (xy 107.084001 65.06)
      )
    )
  )
  (zone (net 1) (net_name "GND") (layer "F.Cu") (hatch edge 0.508)
    (priority 10)
    (connect_pads (clearance 0.2))
    (min_thickness 0.1) (filled_areas_thickness no)
    (fill yes (thermal_gap 0.15) (thermal_bridge_width 0.25))
    (polygon
      (pts
        (xy 118 62.4795)
        (xy 116.72 62.4795)
        (xy 116.72 56.8095)
        (xy 118 56.8095)
      )
    )
  )
  (zone (net 2) (net_name "3V3_SYS") (layer "F.Cu") (name "GND_BGA") (hatch edge 0.508)
    (connect_pads (clearance 0.1))
    (min_thickness 0.1) (filled_areas_thickness no)
    (fill yes (thermal_gap 0.1) (thermal_bridge_width 0.1))
    (polygon
      (pts
        (xy 144.42 75.76)
        (xy 140.12 75.76)
        (xy 140.12 75.2)
        (xy 144.42 75.2)
      )
    )
  )
  (zone (net 2) (net_name "3V3_SYS") (layer "F.Cu") (hatch edge 0.508)
    (priority 1)
    (connect_pads (clearance 0.25))
    (min_thickness 0.1) (filled_areas_thickness no)
    (fill yes (thermal_gap 0.1) (thermal_bridge_width 0.6))
    (polygon
      (pts
        (xy 120.85 95.2)
        (xy 119.15 95.2)
        (xy 119.15 93.93)
        (xy 120.85 93.93)
      )
    )
  )
  (zone (net 3) (net_name "5V0_USB") (layer "F.Cu") (hatch edge 0.508)
    (priority 1)
    (connect_pads (clearance 0.2))
    (min_thickness 0.1) (filled_areas_thickness no)
    (fill yes (thermal_gap 0.15) (thermal_bridge_width 0.5))
    (polygon
      (pts
        (xy 101.83 71)
        (xy 105.92 71)
        (xy 105.92 74.25)
        (xy 101.83 74.25)
      )
    )
  )
  (zone (net 100) (net_name "Net-(D2-A)") (layer "F.Cu") (hatch edge 0.508)
    (priority 1)
    (connect_pads (clearance 0.2))
    (min_thickness 0.1) (filled_areas_thickness no)
    (fill yes (thermal_gap 0.15) (thermal_bridge_width 0.5))
    (polygon
      (pts
        (xy 118.279001 61.56)
        (xy 117.979001 61.56)
        (xy 118.279001 61.56)
        (xy 118.279001 56.7175)
        (xy 121.094001 56.7175)
        (xy 121.094001 61.46)
        (xy 124.209 61.46)
        (xy 124.209 63.87)
        (xy 118.279001 63.87)
      )
    )
  )
  (zone (net 8) (net_name "12V0_PCIE") (layer "F.Cu") (hatch edge 0.508)
    (priority 20)
    (connect_pads yes (clearance 0.1))
    (min_thickness 0.1) (filled_areas_thickness no)
    (fill yes (thermal_gap 0.15) (thermal_bridge_width 0.5))
    (polygon
      (pts
        (xy 114.35 92.95)
        (xy 114.35 94.15)
        (xy 113.8 94.7)
        (xy 111.14 94.7)
        (xy 111.14 92.555)
        (xy 114.12 92.555)
      )
    )
  )
  (zone (net 112) (net_name "Net-(U4A-VCC0P9_SVR_SENSE)") (layer "F.Cu") (hatch edge 0.508)
    (priority 1)
    (connect_pads (clearance 0.2))
    (min_thickness 0.1) (filled_areas_thickness no)
    (fill yes (thermal_gap 0.15) (thermal_bridge_width 0.25))
    (polygon
      (pts
        (xy 145.5 72.3)
        (xy 142.22 72.3)
        (xy 142.22 69.7)
        (xy 145.5 69.7)
      )
    )
  )
  (zone (net 75) (net_name "Net-(C32-Pad2)") (layer "F.Cu") (hatch edge 0.508)
    (connect_pads (clearance 0.2))
    (min_thickness 0.1) (filled_areas_thickness no)
    (fill yes (thermal_gap 0.15) (thermal_bridge_width 0.5))
    (polygon
      (pts
        (xy 119.3 81.3)
        (xy 117.125 86.65)
        (xy 114.6 86.65)
        (xy 114.6 81.475)
        (xy 114.4 81.275)
        (xy 113.775 81.275)
        (xy 112.1 81.275)
        (xy 112.1 80)
        (xy 119.3 80)
      )
    )
  )
  (zone (net 3) (net_name "5V0_USB") (layer "F.Cu") (hatch edge 0.508)
    (priority 1)
    (connect_pads (clearance 0.2))
    (min_thickness 0.1) (filled_areas_thickness no)
    (fill yes (thermal_gap 0.15) (thermal_bridge_width 0.5))
    (polygon
      (pts
        (xy 106.880001 65.11)
        (xy 104.090001 65.11)
        (xy 104.090001 59.41)
        (xy 106.880001 59.41)
      )
    )
  )
  (zone (net 61) (net_name "12V0_MOLEX") (layer "F.Cu") (hatch edge 0.508)
    (priority 20)
    (connect_pads yes (clearance 0.2))
    (min_thickness 0.1) (filled_areas_thickness no)
    (fill yes (thermal_gap 0.15) (thermal_bridge_width 0.5))
    (polygon
      (pts
        (xy 110.93 94.15)
        (xy 108.51 94.15)
        (xy 108.51 89.42)
        (xy 110.93 89.42)
      )
    )
  )
  (zone (net 2) (net_name "3V3_SYS") (layers "F.Cu" "In2.Cu") (hatch edge 0.508)
    (priority 20)
    (connect_pads (clearance 0.2))
    (min_thickness 0.1) (filled_areas_thickness no)
    (fill yes (thermal_gap 0.15) (thermal_bridge_width 0.5))
    (polygon
      (pts
        (xy 124.210001 61.26)
        (xy 121.300001 61.26)
        (xy 121.300001 56.72)
        (xy 124.210001 56.72)
      )
    )
  )
  (zone (net 146) (net_name "Net-(Q4-S)") (layers "F&B.Cu") (hatch edge 0.508)
    (priority 30)
    (connect_pads yes (clearance 0.1))
    (min_thickness 0.1) (filled_areas_thickness no)
    (fill yes (thermal_gap 0.15) (thermal_bridge_width 0.5))
    (polygon
      (pts
        (xy 114.49 91.36)
        (xy 113.13 91.36)
        (xy 113.13 89.58)
        (xy 114.49 89.58)
      )
    )
  )
  (zone (net 1) (net_name "GND") (layers "F&B.Cu") (hatch edge 0.508)
    (connect_pads yes (clearance 0.2))
    (min_thickness 0.1) (filled_areas_thickness no)
    (fill yes (thermal_gap 0.15) (thermal_bridge_width 0.5))
    (polygon
      (pts
        (xy 117.8 94.705)
        (xy 114.2625 94.705)
        (xy 114.2625 94.5625)
        (xy 114.5575 94.2675)
        (xy 114.554982 92.549993)
        (xy 117.8 92.55)
      )
    )
  )
  (zone (net 1) (net_name "GND") (layers "F&B.Cu") (hatch edge 0.508)
    (priority 20)
    (connect_pads yes (clearance 0.2))
    (min_thickness 0.1) (filled_areas_thickness no)
    (fill yes (thermal_gap 0.15) (thermal_bridge_width 0.5))
    (polygon
      (pts
        (xy 164.1 92.5)
        (xy 158.8 92.5)
        (xy 158.8 90)
        (xy 164.1 90)
      )
    )
  )
  (zone (net 143) (net_name "Net-(Q3-S)") (layers "F&B.Cu") (hatch edge 0.508)
    (priority 30)
    (connect_pads yes (clearance 0.1))
    (min_thickness 0.1) (filled_areas_thickness no)
    (fill yes (thermal_gap 0.15) (thermal_bridge_width 0.5))
    (polygon
      (pts
        (xy 112.74 92.02)
        (xy 111.38 92.02)
        (xy 111.38 90.24)
        (xy 112.74 90.24)
      )
    )
  )
  (zone (net 61) (net_name "12V0_MOLEX") (layers "F&B.Cu") (hatch edge 0.508)
    (priority 20)
    (connect_pads yes (clearance 0.2))
    (min_thickness 0.1) (filled_areas_thickness no)
    (fill yes (thermal_gap 0.15) (thermal_bridge_width 0.5))
    (polygon
      (pts
        (xy 164.1 89.6)
        (xy 158.8 89.6)
        (xy 158.8 87.1)
        (xy 164.1 87.1)
      )
    )
  )
  (zone (net 1) (net_name "GND") (layers "In1.Cu" "In4.Cu") (name "GND") (hatch edge 0.508)
    (connect_pads (clearance 0.2))
    (min_thickness 0.2) (filled_areas_thickness no)
    (fill yes (thermal_gap 0.508) (thermal_bridge_width 0.508))
    (polygon
      (pts
        (xy 170 100)
        (xy 100 100)
        (xy 100 50)
        (xy 170 50)
      )
    )
  )
  (zone (net 106) (net_name "Net-(C53-Pad2)") (layer "In2.Cu") (name "GND_BGA") (hatch edge 0.508)
    (priority 10)
    (connect_pads (clearance 0.1))
    (min_thickness 0.1) (filled_areas_thickness no)
    (fill yes (thermal_gap 0.15) (thermal_bridge_width 0.25))
    (polygon
      (pts
        (xy 135.355 80.395)
        (xy 131.645 80.395)
        (xy 131.645 79.295)
        (xy 133.63 79.295)
        (xy 133.63 78.02)
        (xy 134.82 76.64)
        (xy 135.355 76.64)
      )
    )
  )
  (zone (net 2) (net_name "3V3_SYS") (layer "In2.Cu") (hatch edge 0.508)
    (connect_pads yes (clearance 0.2))
    (min_thickness 0.2) (filled_areas_thickness no)
    (fill yes (thermal_gap 0.2) (thermal_bridge_width 0.2))
    (polygon
      (pts
        (xy 170.2 100.2)
        (xy 99.8 100.2)
        (xy 99.8 49.8)
        (xy 170.2 49.8)
      )
    )
  )
  (zone (net 0) (net_name "") (layer "In2.Cu") (name "GND") (hatch edge 0.508)
    (connect_pads (clearance 0))
    (min_thickness 0.2) (filled_areas_thickness no)
    (keepout (tracks allowed) (vias allowed) (pads allowed) (copperpour not_allowed) (footprints allowed))
    (fill (thermal_gap 0.508) (thermal_bridge_width 0.508))
    (polygon
      (pts
        (xy 138.15 78.65)
        (xy 136.65 78.65)
        (xy 136.65 77.8)
        (xy 138.15 77.8)
      )
    )
  )
  (zone (net 113) (net_name "Net-(U4A-VCC0P9_LVR_SENSE)") (layer "In2.Cu") (name "GND_BGA") (hatch edge 0.508)
    (priority 10)
    (connect_pads (clearance 0.1))
    (min_thickness 0.1) (filled_areas_thickness no)
    (fill yes (thermal_gap 0.15) (thermal_bridge_width 0.25))
    (polygon
      (pts
        (xy 140.64 83.02)
        (xy 136.83 83.02)
        (xy 136.83 79.11)
        (xy 140.64 79.11)
      )
    )
  )
  (zone (net 3) (net_name "5V0_USB") (layer "In2.Cu") (hatch edge 0.508)
    (priority 10)
    (connect_pads yes (clearance 0.2))
    (min_thickness 0.2) (filled_areas_thickness no)
    (fill yes (thermal_gap 0.2) (thermal_bridge_width 0.2))
    (polygon
      (pts
        (xy 170 86)
        (xy 160 86)
        (xy 160 59)
        (xy 110 59)
        (xy 110 76.8)
        (xy 100 76.8)
        (xy 100 50)
        (xy 170 50)
      )
    )
  )
  (zone (net 107) (net_name "Net-(C54-Pad2)") (layer "In2.Cu") (name "GND_BGA") (hatch edge 0.508)
    (priority 10)
    (connect_pads (clearance 0.1))
    (min_thickness 0.1) (filled_areas_thickness no)
    (fill yes (thermal_gap 0.15) (thermal_bridge_width 0.25))
    (polygon
      (pts
        (xy 133.395 79.095)
        (xy 131.005 79.095)
        (xy 131.005 78.005)
        (xy 133.395 78.005)
      )
    )
  )
  (zone (net 61) (net_name "12V0_MOLEX") (layers "In2.Cu" "In3.Cu") (hatch edge 0.508)
    (priority 10)
    (connect_pads yes (clearance 0.2))
    (min_thickness 0.2) (filled_areas_thickness no)
    (fill yes (thermal_gap 0.15) (thermal_bridge_width 0.2))
    (polygon
      (pts
        (xy 170.01 100)
        (xy 100.01 100)
        (xy 100.01 88.75)
        (xy 107.2 88.75)
        (xy 155.4 88.75)
        (xy 155.53 88.75)
        (xy 157.97 86.31)
        (xy 170.01 86.31)
      )
    )
  )
  (zone (net 112) (net_name "Net-(U4A-VCC0P9_SVR_SENSE)") (layer "In3.Cu") (name "GND") (hatch edge 0.508)
    (connect_pads yes (clearance 0.2))
    (min_thickness 0.2) (filled_areas_thickness no)
    (fill yes (thermal_gap 0.508) (thermal_bridge_width 0.508))
    (polygon
      (pts
        (xy 145.91 77.36)
        (xy 142.86 77.36)
        (xy 142.1 77.36)
        (xy 139.295 80.145)
        (xy 138.27 81.15)
        (xy 134.83 81.15)
        (xy 134.83 67.78)
        (xy 145.91 67.78)
      )
    )
  )
  (zone (net 0) (net_name "") (layer "In4.Cu") (name "HIGH_SPEED_VOID") (hatch edge 0.508)
    (connect_pads (clearance 0))
    (min_thickness 0.254) (filled_areas_thickness no)
    (keepout (tracks allowed) (vias allowed) (pads allowed) (copperpour not_allowed) (footprints allowed))
    (fill (thermal_gap 0.508) (thermal_bridge_width 0.508))
    (polygon
      (pts
        (xy 155.86 77.1)
        (xy 155.86 78.74)
        (xy 154.3 78.74)
        (xy 154.3 77.1)
      )
    )
  )
  (zone (net 0) (net_name "") (layer "In4.Cu") (name "HIGH_SPEED_VOID") (hatch edge 0.508)
    (connect_pads (clearance 0))
    (min_thickness 0.254) (filled_areas_thickness no)
    (keepout (tracks allowed) (vias allowed) (pads allowed) (copperpour not_allowed) (footprints allowed))
    (fill (thermal_gap 0.508) (thermal_bridge_width 0.508))
    (polygon
      (pts
        (xy 127.82 93.43)
        (xy 126.18 93.43)
        (xy 126.18 91.87)
        (xy 127.82 91.87)
      )
    )
  )
  (zone (net 0) (net_name "") (layer "In4.Cu") (name "HIGH_SPEED_VOID") (hatch edge 0.508)
    (connect_pads (clearance 0))
    (min_thickness 0.254) (filled_areas_thickness no)
    (keepout (tracks allowed) (vias allowed) (pads allowed) (copperpour not_allowed) (footprints allowed))
    (fill (thermal_gap 0.508) (thermal_bridge_width 0.508))
    (polygon
      (pts
        (xy 155.855 80.42)
        (xy 155.855 82.06)
        (xy 154.295 82.06)
        (xy 154.295 80.42)
      )
    )
  )
  (zone (net 0) (net_name "") (layer "In4.Cu") (name "HIGH_SPEED_VOID") (hatch edge 0.508)
    (connect_pads (clearance 0))
    (min_thickness 0.254) (filled_areas_thickness no)
    (keepout (tracks allowed) (vias allowed) (pads allowed) (copperpour not_allowed) (footprints allowed))
    (fill (thermal_gap 0.508) (thermal_bridge_width 0.508))
    (polygon
      (pts
        (xy 135.895 57.78)
        (xy 135.895 59.42)
        (xy 134.335 59.42)
        (xy 134.335 57.78)
      )
    )
  )
  (zone (net 0) (net_name "") (layer "In4.Cu") (name "HIGH_SPEED_VOID") (hatch edge 0.508)
    (connect_pads (clearance 0))
    (min_thickness 0.254) (filled_areas_thickness no)
    (keepout (tracks allowed) (vias allowed) (pads allowed) (copperpour not_allowed) (footprints allowed))
    (fill (thermal_gap 0.508) (thermal_bridge_width 0.508))
    (polygon
      (pts
        (xy 132.82 93.43)
        (xy 131.18 93.43)
        (xy 131.18 91.87)
        (xy 132.82 91.87)
      )
    )
  )
  (zone (net 0) (net_name "") (layer "In4.Cu") (name "HIGH_SPEED_VOID") (hatch edge 0.508)
    (connect_pads (clearance 0))
    (min_thickness 0.254) (filled_areas_thickness no)
    (keepout (tracks allowed) (vias allowed) (pads allowed) (copperpour not_allowed) (footprints allowed))
    (fill (thermal_gap 0.508) (thermal_bridge_width 0.508))
    (polygon
      (pts
        (xy 136.82 93.43)
        (xy 135.18 93.43)
        (xy 135.18 91.87)
        (xy 136.82 91.87)
      )
    )
  )
  (zone (net 0) (net_name "") (layer "In4.Cu") (name "HIGH_SPEED_VOID") (hatch edge 0.508)
    (connect_pads (clearance 0))
    (min_thickness 0.254) (filled_areas_thickness no)
    (keepout (tracks allowed) (vias allowed) (pads allowed) (copperpour not_allowed) (footprints allowed))
    (fill (thermal_gap 0.508) (thermal_bridge_width 0.508))
    (polygon
      (pts
        (xy 140.82 93.43)
        (xy 139.18 93.43)
        (xy 139.18 91.87)
        (xy 140.82 91.87)
      )
    )
  )
  (zone (net 8) (net_name "12V0_PCIE") (layer "B.Cu") (hatch edge 0.508)
    (priority 20)
    (connect_pads yes (clearance 0.1))
    (min_thickness 0.1) (filled_areas_thickness no)
    (fill yes (thermal_gap 0.15) (thermal_bridge_width 0.5))
    (polygon
      (pts
        (xy 114.12 92.255)
        (xy 114.35 92.485)
        (xy 114.35 94.15)
        (xy 113.8 94.7)
        (xy 111.14 94.7)
        (xy 111.14 92.225)
        (xy 113.31 92.225)
        (xy 113.31 91.56)
        (xy 114.12 91.56)
      )
    )
  )
  (zone (net 2) (net_name "3V3_SYS") (layer "B.Cu") (hatch edge 0.508)
    (priority 1)
    (connect_pads (clearance 0.25))
    (min_thickness 0.1) (filled_areas_thickness no)
    (fill yes (thermal_gap 0.1) (thermal_bridge_width 0.6))
    (polygon
      (pts
        (xy 121.57 87.05)
        (xy 121.57 92.53)
        (xy 120.85 93.25)
        (xy 120.85 95.2)
        (xy 118.15 95.2)
        (xy 118.15 93.25)
        (xy 118.76 92.64)
        (xy 118.76 87.05)
      )
    )
  )
)
